G04 ================== begin FILE IDENTIFICATION RECORD ==================*
G04 Layout Name:  E:/<user>/9332_F0TG_MB_C/brd/0417/9332_F0TG_MB_C_V02_0417_0820.brd*
G04 Film Name:    smt*
G04 File Format:  Gerber RS274X*
G04 File Origin:  Cadence Allegro 17.2-S081*
G04 Origin Date:  Wed Apr 19 14:49:57 2023*
G04 *
G04 Layer:  DRAWING FORMAT/TITLE_BLOCK_A*
G04 Layer:  DRAWING FORMAT/TITLE_BLOCK*
G04 Layer:  VIA CLASS/SOLDERMASK_TOP*
G04 Layer:  PIN/SOLDERMASK_TOP*
G04 Layer:  PACKAGE GEOMETRY/SOLDERMASK_TOP*
G04 Layer:  MANUFACTURING/PHOTOPLOT_OUTLINE*
G04 Layer:  DRAWING FORMAT/TITLE_DATA_SMT*
G04 Layer:  BOARD GEOMETRY/SOLDERMASK_TOP*
G04 *
G04 Offset:    (0.00 0.00)*
G04 Mirror:    No*
G04 Mode:      Positive*
G04 Rotation:  0*
G04 FullContactRelief:  No*
G04 UndefLineWidth:     6.00*
G04 ================== end FILE IDENTIFICATION RECORD ====================*
%FSLAX25Y25*MOIN*%
%IR0*IPPOS*OFA0.00000B0.00000*MIA0B0*SFA1.00000B1.00000*%
%AMMACRO251*
4,1,5,.01972,-.00791,
-.01264,-.00791,
-.01972,-.00083,
-.01972,.00791,
.01972,.00791,
.01972,-.00791,
0.0*
%
%ADD251MACRO251*%
%AMMACRO168*
4,1,40,.01381,-.00276,
.013749,-.003449,
.013568,-.004116,
.013275,-.004742,
.012878,-.005308,
.012388,-.005796,
.011821,-.006192,
.011194,-.006483,
.010526,-.006661,
.00984,-.00672,
-.00984,-.00672,
-.010529,-.00666,
-.011197,-.006482,
-.011824,-.00619,
-.012391,-.005794,
-.01288,-.005306,
-.013277,-.00474,
-.01357,-.004113,
-.013749,-.003445,
-.01381,-.00276,
-.01381,.00276,
-.013749,.003449,
-.013568,.004116,
-.013275,.004742,
-.012878,.005308,
-.012388,.005796,
-.011821,.006192,
-.011194,.006483,
-.010526,.006661,
-.00984,.00672,
.00984,.00672,
.010529,.00666,
.011197,.006482,
.011824,.00619,
.012391,.005794,
.01288,.005306,
.013277,.00474,
.01357,.004113,
.013749,.003445,
.01381,.00276,
.01381,-.00276,
0.0*
%
%ADD168MACRO168*%
%AMMACRO166*
4,1,40,-.00276,-.01381,
-.003449,-.013749,
-.004116,-.013568,
-.004742,-.013275,
-.005308,-.012878,
-.005796,-.012388,
-.006192,-.011821,
-.006483,-.011194,
-.006661,-.010526,
-.00672,-.00984,
-.00672,.00984,
-.00666,.010529,
-.006482,.011197,
-.00619,.011824,
-.005794,.012391,
-.005306,.01288,
-.00474,.013277,
-.004113,.01357,
-.003445,.013749,
-.00276,.01381,
.00276,.01381,
.003449,.013749,
.004116,.013568,
.004742,.013275,
.005308,.012878,
.005796,.012388,
.006192,.011821,
.006483,.011194,
.006661,.010526,
.00672,.00984,
.00672,-.00984,
.00666,-.010529,
.006482,-.011197,
.00619,-.011824,
.005794,-.012391,
.005306,-.01288,
.00474,-.013277,
.004113,-.01357,
.003445,-.013749,
.00276,-.01381,
-.00276,-.01381,
0.0*
%
%ADD166MACRO166*%
%AMMACRO248*
4,1,32,-.01575,.06201,
-.01575,.0502,
.00197,.0502,
.00197,.04035,
-.01575,.04035,
-.01575,.03248,
.00197,.03248,
.00197,.02461,
-.01575,.02461,
-.01575,.01673,
.00197,.01673,
.00197,.00886,
-.01575,.00886,
-.01575,.00098,
.00197,.00098,
.00197,-.00689,
-.01575,-.00689,
-.01575,-.01476,
.00197,-.01476,
.00197,-.02264,
-.01575,-.02264,
-.01575,-.03051,
.00197,-.03051,
.00197,-.03839,
-.01575,-.03839,
-.01575,-.04626,
.00197,-.04626,
.00197,-.05413,
-.01575,-.05413,
-.01575,-.06201,
.01575,-.06201,
.01575,.06201,
-.01575,.06201,
0.0*
%
%ADD248MACRO248*%
%AMMACRO59*
4,1,44,-.01381,.00295,
-.01375,.003639,
-.013571,.004307,
-.01328,.004934,
-.012883,.005501,
-.012394,.00599,
-.011828,.006387,
-.011201,.00668,
-.010533,.006859,
-.009845,.00692,
-.00984,.00692,
.00984,.00692,
.010529,.00686,
.011197,.006681,
.011824,.00639,
.012391,.005993,
.01288,.005504,
.013277,.004938,
.01357,.004311,
.013749,.003643,
.01381,.002955,
.01381,.00295,
.01381,-.00295,
.01375,-.003639,
.013571,-.004307,
.01328,-.004934,
.012883,-.005501,
.012394,-.00599,
.011828,-.006387,
.011201,-.00668,
.010533,-.006859,
.009845,-.00692,
.00984,-.00692,
-.00984,-.00692,
-.010529,-.00686,
-.011197,-.006681,
-.011824,-.00639,
-.012391,-.005993,
-.01288,-.005504,
-.013277,-.004938,
-.01357,-.004311,
-.013749,-.003643,
-.01381,-.002955,
-.01381,-.00295,
-.01381,.00295,
0.0*
%
%ADD59MACRO59*%
%AMMACRO57*
4,1,44,.00295,.01381,
.003639,.01375,
.004307,.013571,
.004934,.01328,
.005501,.012883,
.00599,.012394,
.006387,.011828,
.00668,.011201,
.006859,.010533,
.00692,.009845,
.00692,.00984,
.00692,-.00984,
.00686,-.010529,
.006681,-.011197,
.00639,-.011824,
.005993,-.012391,
.005504,-.01288,
.004938,-.013277,
.004311,-.01357,
.003643,-.013749,
.002955,-.01381,
.00295,-.01381,
-.00295,-.01381,
-.003639,-.01375,
-.004307,-.013571,
-.004934,-.01328,
-.005501,-.012883,
-.00599,-.012394,
-.006387,-.011828,
-.00668,-.011201,
-.006859,-.010533,
-.00692,-.009845,
-.00692,-.00984,
-.00692,.00984,
-.00686,.010529,
-.006681,.011197,
-.00639,.011824,
-.005993,.012391,
-.005504,.01288,
-.004938,.013277,
-.004311,.01357,
-.003643,.013749,
-.002955,.01381,
-.00295,.01381,
.00295,.01381,
0.0*
%
%ADD57MACRO57*%
%AMMACRO322*
4,1,8,.03153,-.06499,
-.03153,-.06499,
-.03153,-.01768,
.01571,-.01768,
.01571,.01769,
-.03153,.01769,
-.03153,.06499,
.03153,.06499,
.03153,-.06499,
0.0*
%
%ADD322MACRO322*%
%ADD302R,.1X.038*%
%AMMACRO253*
4,1,28,.0059,.01191,
.006923,.011835,
.007917,.01158,
.008851,.011155,
.009697,.010575,
.01043,.009857,
.011027,.009023,
.01147,.008097,
.011746,.007109,
.011845,.006087,
.01185,.00602,
.01184,-.00149,
.00948,-.00149,
.00947,-.01192,
-.00949,-.0119,
-.00948,-.00147,
-.01184,-.00147,
-.01183,.00604,
-.011745,.007062,
-.011479,.008053,
-.011045,.008983,
-.010457,.009824,
-.009731,.010549,
-.008891,.011138,
-.007961,.011571,
-.006969,.011837,
-.005947,.011926,
-.00588,.01193,
.0059,.01191,
0.0*
%
%ADD253MACRO253*%
%AMMACRO180*
4,1,28,-.01191,.0059,
-.011835,.006923,
-.01158,.007917,
-.011155,.008851,
-.010575,.009697,
-.009857,.01043,
-.009023,.011027,
-.008097,.01147,
-.007109,.011746,
-.006087,.011845,
-.00602,.01185,
.00149,.01184,
.00149,.00948,
.01192,.00947,
.0119,-.00949,
.00147,-.00948,
.00147,-.01184,
-.00604,-.01183,
-.007062,-.011745,
-.008053,-.011479,
-.008983,-.011045,
-.009824,-.010457,
-.010549,-.009731,
-.011138,-.008891,
-.011571,-.007961,
-.011837,-.006969,
-.011926,-.005947,
-.01193,-.00588,
-.01191,.0059,
0.0*
%
%ADD180MACRO180*%
%ADD143R,.103X.071*%
%AMMACRO139*
4,1,28,.01191,-.0059,
.011835,-.006923,
.01158,-.007917,
.011155,-.008851,
.010575,-.009697,
.009857,-.01043,
.009023,-.011027,
.008097,-.01147,
.007109,-.011746,
.006087,-.011845,
.00602,-.01185,
-.00149,-.01184,
-.00149,-.00948,
-.01192,-.00947,
-.0119,.00949,
-.00147,.00948,
-.00147,.01184,
.00604,.01183,
.007062,.011745,
.008053,.011479,
.008983,.011045,
.009824,.010457,
.010549,.009731,
.011138,.008891,
.011571,.007961,
.011837,.006969,
.011926,.005947,
.01193,.00588,
.01191,-.0059,
0.0*
%
%ADD139MACRO139*%
%ADD87R,.052X.13*%
%ADD61O,.141X.072*%
%AMMACRO38*
4,1,8,-.06499,-.03153,
-.06499,.03153,
-.01768,.03153,
-.01768,-.01571,
.01769,-.01571,
.01769,.03153,
.06499,.03153,
.06499,-.03153,
-.06499,-.03153,
0.0*
%
%ADD38MACRO38*%
%ADD158R,.071X.103*%
%AMMACRO310*
4,1,8,.08468,.09255,
.08468,-.0295,
.09452,-.0295,
.09452,-.09255,
-.09452,-.09255,
-.09452,-.0295,
-.08468,-.0295,
-.08468,.09255,
.08468,.09255,
0.0*
%
%ADD310MACRO310*%
%AMMACRO303*
4,1,8,-.09255,.08468,
.0295,.08468,
.0295,.09452,
.09255,.09452,
.09255,-.09452,
.0295,-.09452,
.0295,-.08468,
-.09255,-.08468,
-.09255,.08468,
0.0*
%
%ADD303MACRO303*%
%ADD220R,.114X.053*%
%ADD68R,.103X.046*%
%AMMACRO306*
4,1,8,.01971,.00292,
-.00194,.00292,
-.00194,-.00292,
.01971,-.00292,
.01971,-.01676,
-.01972,-.01676,
-.01972,.01676,
.01971,.01676,
.01971,.00292,
0.0*
%
%ADD306MACRO306*%
%AMMACRO154*
4,1,8,.00292,-.01971,
.00292,.00194,
-.00292,.00194,
-.00292,-.01971,
-.01676,-.01971,
-.01676,.01972,
.01676,.01972,
.01676,-.01971,
.00292,-.01971,
0.0*
%
%ADD154MACRO154*%
%ADD140R,.046X.103*%
%ADD221C,.02*%
%ADD269O,.141X.068*%
%ADD288R,.162X.081*%
%ADD256C,.04*%
%AMMACRO252*
4,1,28,-.00591,-.0119,
-.006933,-.011824,
-.007926,-.011566,
-.00886,-.011141,
-.009705,-.010559,
-.010437,-.00984,
-.011032,-.009004,
-.011474,-.008078,
-.011747,-.007089,
-.011845,-.006068,
-.01185,-.00601,
-.01184,.0015,
-.00948,.0015,
-.00947,.01193,
.00949,.01191,
.00948,.00148,
.01184,.00148,
.01183,-.00603,
.011745,-.007052,
.011479,-.008043,
.011045,-.008973,
.010457,-.009814,
.009731,-.010539,
.008891,-.011127,
.007961,-.011561,
.00697,-.011827,
.005948,-.011916,
.00589,-.01192,
-.00591,-.0119,
0.0*
%
%ADD252MACRO252*%
%AMMACRO179*
4,1,28,.0119,-.00591,
.011824,-.006933,
.011566,-.007926,
.011141,-.00886,
.010559,-.009705,
.00984,-.010437,
.009004,-.011032,
.008078,-.011474,
.007089,-.011747,
.006068,-.011845,
.00601,-.01185,
-.0015,-.01184,
-.0015,-.00948,
-.01193,-.00947,
-.01191,.00949,
-.00148,.00948,
-.00148,.01184,
.00603,.01183,
.007052,.011745,
.008043,.011479,
.008973,.011045,
.009814,.010457,
.010539,.009731,
.011127,.008891,
.011561,.007961,
.011827,.00697,
.011916,.005948,
.01192,.00589,
.0119,-.00591,
0.0*
%
%ADD179MACRO179*%
%AMMACRO138*
4,1,28,-.0119,.00591,
-.011824,.006933,
-.011566,.007926,
-.011141,.00886,
-.010559,.009705,
-.00984,.010437,
-.009004,.011032,
-.008078,.011474,
-.007089,.011747,
-.006068,.011845,
-.00601,.01185,
.0015,.01184,
.0015,.00948,
.01193,.00947,
.01191,-.00949,
.00148,-.00948,
.00148,-.01184,
-.00603,-.01183,
-.007052,-.011745,
-.008043,-.011479,
-.008973,-.011045,
-.009814,-.010457,
-.010539,-.009731,
-.011127,-.008891,
-.011561,-.007961,
-.011827,-.00697,
-.011916,-.005948,
-.01192,-.00589,
-.0119,.00591,
0.0*
%
%ADD138MACRO138*%
%AMMACRO129*
21,1,.016,.0081,0.0,0.0,60.*%
%ADD129MACRO129*%
%ADD239C,.05*%
%ADD54R,.123X.067*%
%ADD46R,.17X.083*%
%ADD262R,.142X.067*%
%ADD111C,.015*%
%ADD28R,.067X.123*%
%ADD295C,.052*%
%AMMACRO213*
21,1,.016,.0081,0.0,0.0,45.*%
%ADD213MACRO213*%
%ADD202C,.07*%
%ADD153C,.061*%
%ADD104C,.016*%
%ADD102R,.067X.142*%
%AMMACRO84*
4,1,21,.014,.0055,
.014,-.0055,
-.0085,-.0055,
-.009455,-.005416,
-.010381,-.005168,
-.01125,-.004763,
-.012035,-.004213,
-.012713,-.003535,
-.013263,-.00275,
-.013668,-.001881,
-.013916,-.000955,
-.014,0.0,
-.013916,.000955,
-.013668,.001881,
-.013263,.00275,
-.012713,.003535,
-.012035,.004213,
-.01125,.004763,
-.010381,.005168,
-.009455,.005416,
-.0085,.0055,
.014,.0055,
0.0*
%
%ADD84MACRO84*%
%ADD72R,.0081X.016*%
%ADD10C,.034*%
%AMMACRO85*
4,1,21,.0055,-.014,
-.0055,-.014,
-.0055,.0085,
-.005416,.009455,
-.005168,.010381,
-.004763,.01125,
-.004213,.012035,
-.003535,.012713,
-.00275,.013263,
-.001881,.013668,
-.000955,.013916,
0.0,.014,
.000955,.013916,
.001881,.013668,
.00275,.013263,
.003535,.012713,
.004213,.012035,
.004763,.01125,
.005168,.010381,
.005416,.009455,
.0055,.0085,
.0055,-.014,
0.0*
%
%ADD85MACRO85*%
%ADD67R,.016X.0081*%
%ADD47R,.174X.028*%
%ADD110R,.107X.069*%
%ADD301R,.069X.107*%
%ADD107C,.019*%
%ADD71R,.182X.058*%
%ADD43C,.064*%
%AMMACRO156*
4,1,8,-.0445,-.0784,
-.0445,.0784,
.0445,.0784,
.0445,.0216,
.0165,.0216,
.0165,-.0216,
.0445,-.0216,
.0445,-.0784,
-.0445,-.0784,
0.0*
%
%ADD156MACRO156*%
%ADD60C,.065*%
%ADD279R,.134X.099*%
%ADD219C,.066*%
%ADD115R,.099X.115*%
%AMMACRO314*
4,1,30,-.08089,.09065,
-.08227,.09203,
-.10433,.09203,
-.10433,.08022,
-.08309,.08022,
-.08171,.07884,
-.02464,.07884,
-.02464,-.02608,
-.06988,-.02609,
-.06988,-.09203,
.06988,-.09203,
.06988,-.01427,
.04035,-.01427,
.04035,.02116,
.10433,.02117,
.10433,.03298,
.09055,.03298,
.09055,.04085,
.10433,.04084,
.10433,.05261,
.09055,.05266,
.09055,.06053,
.10433,.06054,
.10433,.07237,
.09055,.07237,
.09055,.08022,
.10433,.08022,
.10433,.09203,
.08227,.09203,
.08089,.09065,
-.08089,.09065,
0.0*
%
%ADD314MACRO314*%
%ADD217C,.085*%
%ADD296R,.052X.052*%
%ADD211R,.07X.07*%
%ADD142C,.02165*%
%ADD96R,.119X.089*%
%ADD41C,.068*%
%ADD117C,.03417*%
%ADD70R,.182X.099*%
%ADD65R,.071X.071*%
%ADD236R,.036X.036*%
%ADD324C,.0395*%
%ADD150R,.064X.064*%
%ADD247R,.134X.0888*%
%ADD66R,.065X.065*%
%ADD192R,.0888X.134*%
%ADD323C,.0785*%
%ADD291R,.068X.068*%
%AMMACRO267*
21,1,.016,.0081,0.0,0.0,33.917*%
%ADD267MACRO267*%
%AMMACRO282*
4,1,5,-.01362,-.00692,
-.01873,-.00181,
-.01873,.00692,
.01873,.00692,
.01873,-.00692,
-.01362,-.00692,
0.0*
%
%ADD282MACRO282*%
%AMMACRO182*
4,1,5,.01578,-.00692,
-.01067,-.00692,
-.01578,-.00181,
-.01578,.00692,
.01578,.00692,
.01578,-.00692,
0.0*
%
%ADD182MACRO182*%
%ADD118R,.03417X.03417*%
%AMMACRO184*
4,1,5,-.00692,-.01578,
-.00692,.01067,
-.00181,.01578,
.00692,.01578,
.00692,-.01578,
-.00692,-.01578,
0.0*
%
%ADD184MACRO184*%
%AMMACRO94*
4,1,17,-.0055,.014,
.0055,.014,
.0055,-.0085,
.005491,-.00882,
.005463,-.009139,
.00543,-.00938,
.00088,-.01393,
-.000076,-.014,
-.00103,-.013903,
-.001953,-.013642,
-.002816,-.013225,
-.003593,-.012664,
-.004262,-.011977,
-.004801,-.011184,
-.005194,-.01031,
-.005429,-.00938,
-.0055,-.0085,
-.0055,.014,
0.0*
%
%ADD94MACRO94*%
%AMMACRO90*
4,1,17,-.014,-.0055,
-.014,.0055,
.0085,.0055,
.00882,.005491,
.009139,.005463,
.00938,.00543,
.01393,.00088,
.014,-.000076,
.013903,-.00103,
.013642,-.001953,
.013225,-.002816,
.012664,-.003593,
.011977,-.004262,
.011184,-.004801,
.01031,-.005194,
.00938,-.005429,
.0085,-.0055,
-.014,-.0055,
0.0*
%
%ADD90MACRO90*%
%AMMACRO14*
4,1,28,-.00589,-.01192,
-.006913,-.011842,
-.007907,-.011587,
-.008842,-.011163,
-.009688,-.010584,
-.010422,-.009866,
-.011019,-.009032,
-.011463,-.008107,
-.011739,-.007119,
-.01184,-.006097,
-.01184,-.00603,
-.01184,.00148,
-.00948,.00148,
-.00948,.01191,
.00948,.01191,
.00948,.00148,
.01184,.00148,
.01184,-.00603,
.011751,-.007052,
.011486,-.008044,
.011053,-.008974,
.010465,-.009815,
.00974,-.010541,
.0089,-.01113,
.00797,-.011564,
.006979,-.01183,
.005957,-.01192,
.00589,-.01192,
-.00589,-.01192,
0.0*
%
%ADD14MACRO14*%
%AMMACRO25*
4,1,28,-.01192,.00589,
-.011842,.006913,
-.011587,.007907,
-.011163,.008842,
-.010584,.009688,
-.009866,.010422,
-.009032,.011019,
-.008107,.011463,
-.007119,.011739,
-.006097,.01184,
-.00603,.01184,
.00148,.01184,
.00148,.00948,
.01191,.00948,
.01191,-.00948,
.00148,-.00948,
.00148,-.01184,
-.00603,-.01184,
-.007052,-.011751,
-.008044,-.011486,
-.008974,-.011053,
-.009815,-.010465,
-.010541,-.00974,
-.01113,-.0089,
-.011564,-.00797,
-.01183,-.006979,
-.01192,-.005957,
-.01192,-.00589,
-.01192,.00589,
0.0*
%
%ADD25MACRO25*%
%ADD257C,.06974*%
%AMMACRO124*
4,1,6,-.1083,.04334,
.1083,.04334,
.1083,-.01578,
.03743,-.01578,
.03743,-.04334,
-.1083,-.04334,
-.1083,.04334,
0.0*
%
%ADD124MACRO124*%
%ADD116C,.03968*%
%AMMACRO189*
4,1,5,.01578,-.00692,
-.01578,-.00692,
-.01578,.00181,
-.01067,.00692,
.01578,.00692,
.01578,-.00692,
0.0*
%
%ADD189MACRO189*%
%AMMACRO307*
4,1,9,.01972,.00969,
.01972,-.01676,
-.01971,-.01676,
-.01971,-.00292,
.00194,-.00292,
.00194,.00292,
-.01971,.00292,
-.01971,.01676,
.01264,.01676,
.01972,.00969,
0.0*
%
%ADD307MACRO307*%
%AMMACRO281*
4,1,8,-.02661,.02021,
.0266,.02021,
.0266,-.02021,
.01276,-.02021,
.01276,.00637,
-.01277,.00637,
-.01277,-.02021,
-.02661,-.02021,
-.02661,.02021,
0.0*
%
%ADD281MACRO281*%
%AMMACRO183*
4,1,5,-.00692,-.01578,
-.00692,.01578,
.00181,.01578,
.00692,.01067,
.00692,-.01578,
-.00692,-.01578,
0.0*
%
%ADD183MACRO183*%
%AMMACRO155*
4,1,9,.00969,-.01972,
-.01676,-.01972,
-.01676,.01971,
-.00292,.01971,
-.00292,-.00194,
.00292,-.00194,
.00292,.01971,
.01676,.01971,
.01676,-.01264,
.00969,-.01972,
0.0*
%
%ADD155MACRO155*%
%AMMACRO93*
4,1,17,-.0055,.014,
.0055,.014,
.0055,-.0085,
.005416,-.009455,
.005168,-.010382,
.004763,-.011251,
.004213,-.012037,
.003535,-.012715,
.002749,-.013265,
.00188,-.01367,
.000953,-.013919,
-.000002,-.014002,
-.00089,-.01393,
-.00543,-.00939,
-.005472,-.009073,
-.005495,-.008754,
-.0055,-.0085,
-.0055,.014,
0.0*
%
%ADD93MACRO93*%
%AMMACRO82*
4,1,17,-.014,-.0055,
-.014,.0055,
.0085,.0055,
.009455,.005416,
.010382,.005168,
.011251,.004763,
.012037,.004213,
.012715,.003535,
.013265,.002749,
.01367,.00188,
.013919,.000953,
.014002,-.000002,
.01393,-.00089,
.00939,-.00543,
.009073,-.005472,
.008754,-.005495,
.0085,-.0055,
-.014,-.0055,
0.0*
%
%ADD82MACRO82*%
%AMMACRO13*
4,1,28,.0059,.01191,
.006923,.01183,
.007916,.011573,
.00885,.011148,
.009696,.010567,
.010428,.009849,
.011024,.009013,
.011466,.008088,
.011741,.007099,
.01184,.006078,
.01184,.00602,
.01184,-.00149,
.00948,-.00149,
.00948,-.01192,
-.00948,-.01192,
-.00948,-.00149,
-.01184,-.00149,
-.01184,.00602,
-.011751,.007042,
-.011486,.008033,
-.011053,.008964,
-.010465,.009805,
-.00974,.010531,
-.0089,.01112,
-.007971,.011554,
-.00698,.01182,
-.005958,.01191,
-.0059,.01191,
.0059,.01191,
0.0*
%
%ADD13MACRO13*%
%AMMACRO206*
4,1,5,.00594,.01972,
.00594,-.01461,
.00083,-.01972,
-.00594,-.01972,
-.00594,.01972,
.00594,.01972,
0.0*
%
%ADD206MACRO206*%
%AMMACRO27*
4,1,28,.01191,-.0059,
.01183,-.006923,
.011573,-.007916,
.011148,-.00885,
.010567,-.009696,
.009849,-.010428,
.009013,-.011024,
.008088,-.011466,
.007099,-.011741,
.006078,-.01184,
.00602,-.01184,
-.00149,-.01184,
-.00149,-.00948,
-.01192,-.00948,
-.01192,.00948,
-.00149,.00948,
-.00149,.01184,
.00602,.01184,
.007042,.011751,
.008033,.011486,
.008964,.011053,
.009805,.010465,
.010531,.00974,
.01112,.0089,
.011554,.007971,
.01182,.00698,
.01191,.005958,
.01191,.0059,
.01191,-.0059,
0.0*
%
%ADD27MACRO27*%
%ADD276R,.06974X.06974*%
%ADD321R,.201X.132*%
%AMMACRO131*
4,1,5,-.00791,-.01972,
-.00791,.01264,
-.00083,.01972,
.00791,.01972,
.00791,-.01972,
-.00791,-.01972,
0.0*
%
%ADD131MACRO131*%
%AMMACRO274*
4,1,5,-.01972,.00791,
.01264,.00791,
.01972,.00083,
.01972,-.00791,
-.01972,-.00791,
-.01972,.00791,
0.0*
%
%ADD274MACRO274*%
%ADD74R,.03X.011*%
%AMMACRO312*
4,1,8,-.03153,.06499,
.03153,.06499,
.03153,.01768,
-.01571,.01768,
-.01571,-.01769,
.03153,-.01769,
.03153,-.06499,
-.03153,-.06499,
-.03153,.06499,
0.0*
%
%ADD312MACRO312*%
%ADD293R,.04X.02*%
%ADD73R,.011X.03*%
%AMMACRO39*
4,1,8,.06499,.03153,
.06499,-.03153,
.01768,-.03153,
.01768,.01571,
-.01769,.01571,
-.01769,-.03153,
-.06499,-.03153,
-.06499,.03153,
.06499,.03153,
0.0*
%
%ADD39MACRO39*%
%ADD287R,.032X.011*%
%ADD264R,.17X.201*%
%ADD159R,.02X.04*%
%ADD286R,.011X.032*%
%ADD204R,.05X.021*%
%ADD100R,.024X.02*%
%ADD223R,.021X.05*%
%ADD181R,.04X.014*%
%ADD175R,.02X.024*%
%ADD173R,.042X.03*%
%AMMACRO133*
4,1,32,.06201,.01575,
.0502,.01575,
.0502,-.00197,
.04035,-.00197,
.04035,.01575,
.03248,.01575,
.03248,-.00197,
.02461,-.00197,
.02461,.01575,
.01673,.01575,
.01673,-.00197,
.00886,-.00197,
.00886,.01575,
.00098,.01575,
.00098,-.00197,
-.00689,-.00197,
-.00689,.01575,
-.01476,.01575,
-.01476,-.00197,
-.02264,-.00197,
-.02264,.01575,
-.03051,.01575,
-.03051,-.00197,
-.03839,-.00197,
-.03839,.01575,
-.04626,.01575,
-.04626,-.00197,
-.05413,-.00197,
-.05413,.01575,
-.06201,.01575,
-.06201,-.01575,
.06201,-.01575,
.06201,.01575,
0.0*
%
%ADD133MACRO133*%
%AMMACRO130*
21,1,.016,.0081,0.0,0.0,110.*%
%ADD130MACRO130*%
%ADD119R,.024X.021*%
%ADD304R,.05X.032*%
%ADD292R,.032X.04*%
%AMMACRO273*
4,1,32,.01575,-.06201,
.01575,-.0502,
-.00197,-.0502,
-.00197,-.04035,
.01575,-.04035,
.01575,-.03248,
-.00197,-.03248,
-.00197,-.02461,
.01575,-.02461,
.01575,-.01673,
-.00197,-.01673,
-.00197,-.00886,
.01575,-.00886,
.01575,-.00098,
-.00197,-.00098,
-.00197,.00689,
.01575,.00689,
.01575,.01476,
-.00197,.01476,
-.00197,.02264,
.01575,.02264,
.01575,.03051,
-.00197,.03051,
-.00197,.03839,
.01575,.03839,
.01575,.04626,
-.00197,.04626,
-.00197,.05413,
.01575,.05413,
.01575,.06201,
-.01575,.06201,
-.01575,-.06201,
.01575,-.06201,
0.0*
%
%ADD273MACRO273*%
%ADD271O,.275X.22*%
%ADD198R,.044X.011*%
%ADD191R,.021X.024*%
%ADD177R,.035X.011*%
%ADD152R,.032X.014*%
%ADD145R,.03X.042*%
%ADD106O,.017X.014*%
%ADD33R,.024X.022*%
%ADD308R,.014X.032*%
%ADD305R,.134X.134*%
%ADD278R,.024X.014*%
%ADD227R,.17X.134*%
%AMMACRO210*
21,1,.016,.0081,0.0,0.0,112.*%
%ADD210MACRO210*%
%ADD199R,.011X.035*%
%ADD197R,.011X.044*%
%ADD178R,.036X.011*%
%ADD105O,.014X.017*%
%ADD80R,.032X.05*%
%ADD76R,.022X.024*%
%ADD48R,.022X.016*%
%ADD32R,.033X.014*%
%ADD277R,.274X.13*%
%AMMACRO266*
4,1,28,-.0059,-.01191,
-.006923,-.011835,
-.007917,-.01158,
-.008851,-.011155,
-.009697,-.010575,
-.01043,-.009857,
-.011027,-.009023,
-.01147,-.008097,
-.011746,-.007109,
-.011845,-.006087,
-.01185,-.00602,
-.01184,.00149,
-.00948,.00149,
-.00947,.01192,
.00949,.0119,
.00948,.00147,
.01184,.00147,
.01183,-.00604,
.011745,-.007062,
.011479,-.008053,
.011045,-.008983,
.010457,-.009824,
.009731,-.010549,
.008891,-.011138,
.007961,-.011571,
.006969,-.011837,
.005947,-.011926,
.00588,-.01193,
-.0059,-.01191,
0.0*
%
%ADD266MACRO266*%
%ADD132R,.011X.036*%
%ADD99R,.025X.014*%
%ADD40R,.028X.011*%
%ADD31R,.014X.033*%
%ADD290R,.021X.063*%
%ADD255R,.04X.036*%
%ADD226R,.014X.025*%
%ADD194R,.056X.011*%
%ADD157R,.024X.016*%
%ADD147R,.142X.119*%
%ADD55R,.011X.028*%
%ADD36R,.026X.014*%
%ADD29R,.028X.021*%
%ADD26R,.04X.044*%
%ADD19R,.038X.02*%
%ADD311R,.048X.02*%
%ADD283R,.054X.014*%
%ADD244R,.018X.014*%
%ADD230R,.019X.013*%
%ADD195R,.011X.056*%
%ADD125R,.119X.142*%
%ADD123R,.036X.014*%
%ADD109R,.021X.028*%
%ADD108R,.036X.032*%
%ADD103R,.06X.044*%
%ADD98R,.025X.016*%
%ADD63R,.036X.04*%
%ADD51R,.028X.013*%
%ADD35R,.014X.026*%
%ADD22R,.052X.06*%
%AMMACRO320*
4,1,32,.05512,.01181,
.04331,.01181,
.04331,-.00098,
.03543,-.00098,
.03543,.01181,
.02362,.01181,
.02362,-.00098,
.01575,-.00098,
.01575,.01181,
.00394,.01181,
.00394,-.00098,
-.00394,-.00098,
-.00394,.01181,
-.01575,.01181,
-.01575,-.00098,
-.02362,-.00098,
-.02362,.01181,
-.03543,.01181,
-.03543,-.00098,
-.04331,-.00098,
-.04331,.01181,
-.05512,.01181,
-.05512,-.00098,
-.06299,-.00098,
-.06299,.01181,
-.0748,.01181,
-.0748,-.01181,
.0748,-.01181,
.0748,.01181,
.06299,.01181,
.06299,-.00098,
.05512,-.00098,
.05512,.01181,
0.0*
%
%ADD320MACRO320*%
%ADD315R,.027X.015*%
%ADD299R,.052X.044*%
%ADD275R,.132X.139*%
%ADD261R,.06X.054*%
%ADD243R,.019X.014*%
%ADD242R,.014X.018*%
%ADD228R,.013X.019*%
%ADD225R,.016X.025*%
%ADD203R,.05X.028*%
%ADD174R,.032X.036*%
%ADD169R,.058X.02*%
%ADD151R,.056X.022*%
%ADD122R,.014X.054*%
%ADD121R,.014X.036*%
%ADD95R,.032X.028*%
%AMMACRO81*
4,1,8,-.08468,-.09255,
-.08468,.0295,
-.09452,.0295,
-.09452,.09255,
.09452,.09255,
.09452,.0295,
.08468,.0295,
.08468,-.09255,
-.08468,-.09255,
0.0*
%
%ADD81MACRO81*%
%ADD78R,.06X.018*%
%ADD62R,.044X.06*%
%ADD52R,.013X.028*%
%ADD37R,.02X.048*%
%ADD318R,.015X.027*%
%ADD316R,.028X.015*%
%ADD313C,.142*%
%ADD309R,.054X.034*%
%ADD300R,.028X.032*%
%ADD298R,.044X.052*%
%ADD268R,.1732X.134*%
%ADD259R,.063X.052*%
%ADD249R,.036X.016*%
%ADD241R,.014X.019*%
%ADD231R,.02X.058*%
%ADD222R,.028X.05*%
%ADD214R,.018X.06*%
%AMMACRO209*
21,1,.016,.0081,0.0,0.0,135.*%
%ADD209MACRO209*%
%ADD207R,.058X.03*%
%ADD186R,.056X.014*%
%ADD162R,.016X.053*%
%AMMACRO92*
4,1,21,-.0055,.014,
.0055,.014,
.0055,-.0085,
.005416,-.009455,
.005168,-.010381,
.004763,-.01125,
.004213,-.012035,
.003535,-.012713,
.00275,-.013263,
.001881,-.013668,
.000955,-.013916,
0.0,-.014,
-.000955,-.013916,
-.001881,-.013668,
-.00275,-.013263,
-.003535,-.012713,
-.004213,-.012035,
-.004763,-.01125,
-.005168,-.010381,
-.005416,-.009455,
-.0055,-.0085,
-.0055,.014,
0.0*
%
%ADD92MACRO92*%
%AMMACRO88*
4,1,21,-.014,-.0055,
-.014,.0055,
.0085,.0055,
.009455,.005416,
.010381,.005168,
.01125,.004763,
.012035,.004213,
.012713,.003535,
.013263,.00275,
.013668,.001881,
.013916,.000955,
.014,0.0,
.013916,-.000955,
.013668,-.001881,
.013263,-.00275,
.012713,-.003535,
.012035,-.004213,
.01125,-.004763,
.010381,-.005168,
.009455,-.005416,
.0085,-.0055,
-.014,-.0055,
0.0*
%
%ADD88MACRO88*%
%ADD317R,.015X.028*%
%ADD254R,.053X.018*%
%ADD216R,.044X.036*%
%ADD172C,.26*%
%ADD141R,.06X.056*%
%ADD134R,.016X.036*%
%ADD113R,.036X.026*%
%ADD112R,.054X.044*%
%ADD44R,.019X.016*%
%ADD18R,.038X.024*%
%AMMACRO265*
4,1,28,.00591,.0119,
.006933,.011824,
.007926,.011566,
.00886,.011141,
.009705,.010559,
.010437,.00984,
.011032,.009004,
.011474,.008078,
.011747,.007089,
.011845,.006068,
.01185,.00601,
.01184,-.0015,
.00948,-.0015,
.00947,-.01193,
-.00949,-.01191,
-.00948,-.00148,
-.01184,-.00148,
-.01183,.00603,
-.011745,.007052,
-.011479,.008043,
-.011045,.008973,
-.010457,.009814,
-.009731,.010539,
-.008891,.011127,
-.007961,.011561,
-.00697,.011827,
-.005948,.011916,
-.00589,.01192,
.00591,.0119,
0.0*
%
%ADD265MACRO265*%
%ADD260R,.193X.19*%
%ADD235R,.056X.06*%
%ADD229R,.067X.05*%
%ADD212R,.052X.029*%
%ADD208R,.063X.018*%
%ADD146R,.018X.053*%
%ADD137R,.026X.036*%
%ADD135R,.083X.016*%
%ADD120O,.319X.256*%
%ADD77R,.016X.019*%
%ADD69C,.414*%
%ADD53R,.044X.054*%
%ADD42R,.019X.061*%
%ADD294R,.036X.028*%
%ADD270R,.054X.019*%
%ADD258R,.018X.063*%
%ADD250R,.016X.083*%
%AMMACRO233*
4,1,8,.0445,.0784,
.0445,-.0784,
-.0445,-.0784,
-.0445,-.0216,
-.0165,-.0216,
-.0165,.0216,
-.0445,.0216,
-.0445,.0784,
.0445,.0784,
0.0*
%
%ADD233MACRO233*%
%ADD224R,.029X.017*%
%ADD218R,.067X.015*%
%ADD79R,.044X.019*%
%ADD24C,.145*%
%ADD12C,.118*%
%ADD285R,.067X.016*%
%ADD272R,.056X.018*%
%ADD201R,.046X.028*%
%ADD148R,.057X.026*%
%ADD128C,.182*%
%ADD101R,.028X.036*%
%ADD97R,.017X.029*%
%ADD49R,.073X.081*%
%ADD246C,.237*%
%ADD215R,.026X.057*%
%ADD205R,.048X.018*%
%ADD193R,.028X.046*%
%ADD171R,.054X.039*%
%ADD165R,.056X.028*%
%ADD284R,.067X.018*%
%ADD263C,.319*%
%AMMACRO167*
4,1,44,-.12011,.11614,
-.12005,.116829,
-.119871,.117497,
-.119579,.118124,
-.119183,.118691,
-.118694,.11918,
-.118127,.119577,
-.117501,.11987,
-.116833,.120049,
-.116143,.12011,
-.11614,.12011,
.11614,.12011,
.116829,.12005,
.117497,.119871,
.118124,.119579,
.118691,.119183,
.11918,.118694,
.119577,.118127,
.11987,.117501,
.120049,.116833,
.12011,.116143,
.12011,.11614,
.12011,-.11614,
.12005,-.116829,
.119871,-.117497,
.119579,-.118124,
.119183,-.118691,
.118694,-.11918,
.118127,-.119577,
.117501,-.11987,
.116833,-.120049,
.116143,-.12011,
.11614,-.12011,
-.11614,-.12011,
-.116829,-.12005,
-.117497,-.119871,
-.118124,-.119579,
-.118691,-.119183,
-.11918,-.118694,
-.119577,-.118127,
-.11987,-.117501,
-.120049,-.116833,
-.12011,-.116143,
-.12011,-.11614,
-.12011,.11614,
0.0*
%
%ADD167MACRO167*%
%ADD163R,.039X.054*%
%ADD161R,.028X.056*%
%ADD149R,.018X.048*%
%ADD297R,.067X.019*%
%ADD280R,.018X.067*%
%ADD170R,.058X.028*%
%ADD144C,.009*%
%ADD114R,.142X.142*%
%ADD23C,.248*%
%ADD232R,.028X.058*%
%ADD289R,.058X.048*%
%ADD245C,.295*%
%ADD238R,.069X.028*%
%ADD136C,.178*%
%ADD30R,.144X.144*%
%ADD15R,.099X.034*%
%ADD160R,.048X.058*%
%AMMACRO58*
4,1,44,-.04921,.05318,
.04921,.05318,
.049899,.05312,
.050567,.052941,
.051194,.05265,
.051761,.052253,
.05225,.051764,
.052647,.051198,
.05294,.050571,
.053119,.049903,
.05318,.049214,
.05318,.04921,
.05318,-.04921,
.05312,-.049899,
.052941,-.050567,
.05265,-.051194,
.052253,-.051761,
.051764,-.05225,
.051198,-.052647,
.050571,-.05294,
.049903,-.053119,
.049214,-.05318,
.04921,-.05318,
-.04921,-.05318,
-.049899,-.05312,
-.050567,-.052941,
-.051194,-.05265,
-.051761,-.052253,
-.05225,-.051764,
-.052647,-.051198,
-.05294,-.050571,
-.053119,-.049903,
-.05318,-.049214,
-.05318,-.04921,
-.05318,.04921,
-.05312,.049899,
-.052941,.050567,
-.05265,.051194,
-.052253,.051761,
-.051764,.05225,
-.051198,.052647,
-.050571,.05294,
-.049903,.053119,
-.049214,.05318,
-.04921,.05318,
0.0*
%
%ADD58MACRO58*%
%ADD45R,.063X.02447*%
%AMMACRO319*
4,1,24,-.01051,.04391,
-.01188,.04527,
-.03394,.04527,
-.03394,.03346,
-.02016,.03348,
-.02016,.02559,
-.03394,.02559,
-.03394,.01379,
-.02016,.0138,
-.02016,.0059,
-.03394,.00592,
-.03394,-.00591,
-.02016,-.00589,
-.02016,-.01378,
-.03394,-.01378,
-.03394,-.0256,
-.02016,-.02557,
-.02016,-.03347,
-.03394,-.03347,
-.03394,-.04527,
-.01188,-.04527,
-.00913,-.04255,
.03394,-.04255,
.03394,.04391,
-.01051,.04391,
0.0*
%
%ADD319MACRO319*%
%ADD196R,.209X.209*%
%ADD164R,.128X.128*%
%ADD64R,.095X.085*%
%ADD234R,.138X.138*%
%ADD56R,.148X.148*%
%ADD11C,.398*%
%AMMACRO190*
4,1,5,-.01578,.00692,
.01067,.00692,
.01578,.00181,
.01578,-.00692,
-.01578,-.00692,
-.01578,.00692,
0.0*
%
%ADD190MACRO190*%
%AMMACRO188*
4,1,5,.00692,.01578,
.00692,-.01067,
.00181,-.01578,
-.00692,-.01578,
-.00692,.01578,
.00692,.01578,
0.0*
%
%ADD188MACRO188*%
%AMMACRO127*
4,1,5,.00692,-.01362,
.00181,-.01873,
-.00692,-.01873,
-.00692,.01873,
.00692,.01873,
.00692,-.01362,
0.0*
%
%ADD127MACRO127*%
%ADD75R,.178X.178*%
%AMMACRO21*
4,1,28,.01192,-.00589,
.011842,-.006913,
.011587,-.007907,
.011163,-.008842,
.010584,-.009688,
.009866,-.010422,
.009032,-.011019,
.008107,-.011463,
.007119,-.011739,
.006097,-.01184,
.00603,-.01184,
-.00148,-.01184,
-.00148,-.00948,
-.01191,-.00948,
-.01191,.00948,
-.00148,.00948,
-.00148,.01184,
.00603,.01184,
.007052,.011751,
.008044,.011486,
.008974,.011053,
.009815,.010465,
.010541,.00974,
.01113,.0089,
.011564,.00797,
.01183,.006979,
.01192,.005957,
.01192,.00589,
.01192,-.00589,
0.0*
%
%ADD21MACRO21*%
%AMMACRO17*
4,1,28,.00589,.01192,
.006913,.011842,
.007907,.011587,
.008842,.011163,
.009688,.010584,
.010422,.009866,
.011019,.009032,
.011463,.008107,
.011739,.007119,
.01184,.006097,
.01184,.00603,
.01184,-.00148,
.00948,-.00148,
.00948,-.01191,
-.00948,-.01191,
-.00948,-.00148,
-.01184,-.00148,
-.01184,.00603,
-.011751,.007052,
-.011486,.008044,
-.011053,.008974,
-.010465,.009815,
-.00974,.010541,
-.0089,.01113,
-.00797,.011564,
-.006979,.01183,
-.005957,.01192,
-.00589,.01192,
.00589,.01192,
0.0*
%
%ADD17MACRO17*%
%AMMACRO34*
4,1,5,-.05023,-.05023,
-.05023,.03528,
-.03528,.05023,
.05023,.05023,
.05023,-.05023,
-.05023,-.05023,
0.0*
%
%ADD34MACRO34*%
%AMMACRO240*
4,1,14,-.11716,-.02956,
-.11716,.02956,
.11716,.02956,
.11716,-.02956,
-.02817,-.02956,
-.03143,-.027197,
-.035051,-.025436,
-.038922,-.02433,
-.042927,-.023914,
-.046943,-.024199,
-.050849,-.025177,
-.054525,-.026819,
-.057861,-.029074,
-.05844,-.02956,
-.11716,-.02956,
0.0*
%
%ADD240MACRO240*%
%AMMACRO187*
4,1,5,.00692,.01578,
.00692,-.01578,
-.00181,-.01578,
-.00692,-.01067,
-.00692,.01578,
.00692,.01578,
0.0*
%
%ADD187MACRO187*%
%AMMACRO185*
4,1,5,-.01578,.00692,
.01578,.00692,
.01578,-.00181,
.01067,-.00692,
-.01578,-.00692,
-.01578,.00692,
0.0*
%
%ADD185MACRO185*%
%AMMACRO126*
4,1,8,-.02021,-.02661,
-.02021,.0266,
.02021,.0266,
.02021,.01276,
-.00637,.01276,
-.00637,-.01277,
.02021,-.01277,
.02021,-.02661,
-.02021,-.02661,
0.0*
%
%ADD126MACRO126*%
%AMMACRO83*
4,1,17,.014,.0055,
.014,-.0055,
-.0085,-.0055,
-.00882,-.005491,
-.009139,-.005463,
-.00938,-.00543,
-.01393,-.00088,
-.014,.000076,
-.013903,.00103,
-.013642,.001953,
-.013225,.002816,
-.012664,.003593,
-.011977,.004262,
-.011184,.004801,
-.01031,.005194,
-.00938,.005429,
-.0085,.0055,
.014,.0055,
0.0*
%
%ADD83MACRO83*%
%AMMACRO89*
4,1,17,.0055,-.014,
-.0055,-.014,
-.0055,.0085,
-.005491,.00882,
-.005463,.009139,
-.00543,.00938,
-.00088,.01393,
.000076,.014,
.00103,.013903,
.001953,.013642,
.002816,.013225,
.003593,.012664,
.004262,.011977,
.004801,.011184,
.005194,.01031,
.005429,.00938,
.0055,.0085,
.0055,-.014,
0.0*
%
%ADD89MACRO89*%
%AMMACRO20*
4,1,28,-.01191,.0059,
-.01183,.006923,
-.011573,.007916,
-.011148,.00885,
-.010567,.009696,
-.009849,.010428,
-.009013,.011024,
-.008088,.011466,
-.007099,.011741,
-.006078,.01184,
-.00602,.01184,
.00149,.01184,
.00149,.00948,
.01192,.00948,
.01192,-.00948,
.00149,-.00948,
.00149,-.01184,
-.00602,-.01184,
-.007042,-.011751,
-.008033,-.011486,
-.008964,-.011053,
-.009805,-.010465,
-.010531,-.00974,
-.01112,-.0089,
-.011554,-.007971,
-.01182,-.00698,
-.01191,-.005958,
-.01191,-.0059,
-.01191,.0059,
0.0*
%
%ADD20MACRO20*%
%AMMACRO16*
4,1,28,-.0059,-.01191,
-.006923,-.01183,
-.007916,-.011573,
-.00885,-.011148,
-.009696,-.010567,
-.010428,-.009849,
-.011024,-.009013,
-.011466,-.008088,
-.011741,-.007099,
-.01184,-.006078,
-.01184,-.00602,
-.01184,.00149,
-.00948,.00149,
-.00948,.01192,
.00948,.01192,
.00948,.00149,
.01184,.00149,
.01184,-.00602,
.011751,-.007042,
.011486,-.008033,
.011053,-.008964,
.010465,-.009805,
.00974,-.010531,
.0089,-.01112,
.007971,-.011554,
.00698,-.01182,
.005958,-.01191,
.0059,-.01191,
-.0059,-.01191,
0.0*
%
%ADD16MACRO16*%
%AMMACRO50*
4,1,6,.1083,-.04334,
-.1083,-.04334,
-.1083,.01578,
-.03743,.01578,
-.03743,.04334,
.1083,.04334,
.1083,-.04334,
0.0*
%
%ADD50MACRO50*%
%AMMACRO237*
4,1,14,.11716,.02956,
.11716,-.02956,
-.11716,-.02956,
-.11716,.02956,
-.05844,.02956,
-.05518,.027197,
-.051559,.025436,
-.047688,.02433,
-.043683,.023914,
-.039667,.024199,
-.035761,.025177,
-.032085,.026819,
-.028749,.029074,
-.02817,.02956,
.11716,.02956,
0.0*
%
%ADD237MACRO237*%
%AMMACRO91*
4,1,17,.014,.0055,
.014,-.0055,
-.0085,-.0055,
-.009455,-.005416,
-.010382,-.005168,
-.011251,-.004763,
-.012037,-.004213,
-.012715,-.003535,
-.013265,-.002749,
-.01367,-.00188,
-.013919,-.000953,
-.014002,.000002,
-.01393,.00089,
-.00939,.00543,
-.009073,.005472,
-.008754,.005495,
-.0085,.0055,
.014,.0055,
0.0*
%
%ADD91MACRO91*%
%AMMACRO200*
4,1,5,.01972,-.00594,
-.01461,-.00594,
-.01972,-.00083,
-.01972,.00594,
.01972,.00594,
.01972,-.00594,
0.0*
%
%ADD200MACRO200*%
%AMMACRO86*
4,1,17,.0055,-.014,
-.0055,-.014,
-.0055,.0085,
-.005416,.009455,
-.005168,.010382,
-.004763,.011251,
-.004213,.012037,
-.003535,.012715,
-.002749,.013265,
-.00188,.01367,
-.000953,.013919,
.000002,.014002,
.00089,.01393,
.00543,.00939,
.005472,.009073,
.005495,.008754,
.0055,.0085,
.0055,-.014,
0.0*
%
%ADD86MACRO86*%
%AMMACRO176*
4,1,5,-.00594,-.01972,
-.00594,.01461,
-.00083,.01972,
.00594,.01972,
.00594,-.01972,
-.00594,-.01972,
0.0*
%
%ADD176MACRO176*%
%ADD325C,.006*%
%ADD326C,.2542*%
%ADD327C,.1582*%
G75*
%LPD*%
G75*
G36*
G01X26609Y139746D02*
G03I-5900J0D01*
G37*
G36*
G01X29463Y1590338D02*
G03I-5900J0D01*
G37*
G36*
G01X56058Y124181D02*
G02X65762Y113808I4852J-5187D01*
G01X61162Y109505D01*
G02X51458Y119878I-4852J5186D01*
G01X56058Y124181D01*
G37*
G36*
G01X138618Y605378D02*
G02I-20685J0D01*
G37*
G36*
G01X147929Y1482244D02*
G02I-9858J0D01*
G37*
G36*
G01X173520Y1593661D02*
G02I-9858J0D01*
G37*
G36*
G01X198098Y260083D02*
G02X156728I-20685J0D01*
G01Y294335D01*
G02X198098I20685J0D01*
G01Y260083D01*
G37*
G36*
G01X288893Y1019214D02*
G02I-13980J0D01*
G37*
G36*
G01X334168Y838505D02*
G02I-13979J0D01*
G37*
G36*
G01Y1199923D02*
G02I-13979J0D01*
G37*
G36*
G01X415159Y412106D02*
G03I-5900J0D01*
G37*
G36*
G01X575113Y838505D02*
G02I-13980J0D01*
G37*
G36*
G01Y1199923D02*
G02I-13980J0D01*
G37*
G36*
G01X620389Y1019214D02*
G02I-13980J0D01*
G37*
G36*
G01X683087Y1593661D02*
G02I-9858J0D01*
G37*
G36*
G01X724870Y260110D02*
G02X683500I-20685J0D01*
G01Y294362D01*
G02X724870I20685J0D01*
G01Y260110D01*
G37*
G36*
G01X708677Y1482244D02*
G02I-9858J0D01*
G37*
G36*
G01X784287Y605413D02*
G02I-20685J0D01*
G37*
G36*
G01X825575Y204724D02*
G02I-19885J0D01*
G37*
G36*
G01X857240Y1420331D02*
G02I-16000J0D01*
G37*
G36*
G01X870525Y1368522D02*
G03I-5900J0D01*
G37*
G36*
G01X948625Y321654D02*
G02I-19885J0D01*
G37*
G36*
G01X930909Y1014595D02*
G03I-5900J0D01*
G37*
G36*
G01X1032240Y1420331D02*
G02I-16000J0D01*
G37*
G36*
G01X1077544Y204724D02*
G02I-19885J0D01*
G37*
G36*
G01X1114760Y605378D02*
G02I-20685J0D01*
G37*
G36*
G01X1094563Y299646D02*
G03I-5900J0D01*
G37*
G36*
G01X1174240Y260083D02*
G02X1132870I-20685J0D01*
G01Y294335D01*
G02X1174240I20685J0D01*
G01Y260083D01*
G37*
G36*
G01X1155803Y1515236D02*
G02I-9858J0D01*
G37*
G36*
G01X1154139Y554216D02*
G03I-5900J0D01*
G37*
G36*
G01X1181394Y1626654D02*
G02I-9858J0D01*
G37*
G36*
G01X1265035Y1019213D02*
G02I-13980J0D01*
G37*
G36*
G01X1310310Y838504D02*
G02I-13979J0D01*
G37*
G36*
G01Y1199922D02*
G02I-13979J0D01*
G37*
G36*
G01X1495857Y1403002D02*
G03I-5900J0D01*
G37*
G36*
G01X1551255Y838504D02*
G02I-13980J0D01*
G37*
G36*
G01Y1199922D02*
G02I-13980J0D01*
G37*
G36*
G01X1574692Y178239D02*
G03I-5900J0D01*
G37*
G36*
G01X1596531Y1019213D02*
G02I-13980J0D01*
G37*
G36*
G01X1701012Y260110D02*
G02X1659642I-20685J0D01*
G01Y294362D01*
G02X1701012I20685J0D01*
G01Y260110D01*
G37*
G36*
G01X1690961Y1626654D02*
G02I-9858J0D01*
G37*
G36*
G01X1716551Y1515236D02*
G02I-9858J0D01*
G37*
G36*
G01X1710830Y1649379D02*
G03I-5900J0D01*
G37*
G36*
G01X1760429Y605413D02*
G02I-20685J0D01*
G37*
G36*
G01X1776979Y1714960D02*
G02I-10050J0D01*
G37*
G36*
G01X1837024Y127165D02*
G02X1822819I-7103J0D01*
G01Y133465D01*
G02X1837024I7103J0D01*
G01Y127165D01*
G37*
%LPC*%
G75*
G54D326*
X805690Y204724D03*
X1057659D03*
G54D327*
X1766929Y1714960D03*
%LPD*%
G75*
G54D100*
X155260Y1715941D03*
Y1718500D03*
Y1721059D03*
X162740Y1715941D03*
Y1718500D03*
Y1721059D03*
X181760Y1715441D03*
Y1718000D03*
Y1720559D03*
X189240Y1715441D03*
X198760Y1715000D03*
Y1712441D03*
X189240Y1718000D03*
Y1720559D03*
X198760Y1717559D03*
X206240Y1715000D03*
Y1712441D03*
Y1717559D03*
G54D200*
X514635Y212498D03*
G54D101*
X162609Y400600D03*
X157491D03*
X160050Y406900D03*
X184271Y400060D03*
X186830Y406360D03*
X189389Y400060D03*
G54D110*
X195345Y1407483D03*
Y1427365D03*
X347380Y616161D03*
Y636043D03*
X356251Y1369970D03*
Y1389852D03*
X466581Y573882D03*
Y593764D03*
X1133565Y1409036D03*
Y1428918D03*
X1345073Y1391844D03*
Y1411726D03*
X1454057Y619617D03*
Y639499D03*
G54D201*
X529815Y445740D03*
Y438260D03*
X519185D03*
Y442000D03*
Y445740D03*
X555185Y458760D03*
Y466240D03*
X565815Y462500D03*
Y458760D03*
Y466240D03*
G54D120*
X250326Y185236D03*
X368437D03*
G54D300*
X1418249Y244450D03*
X1421989D03*
G54D210*
X607057Y771392D03*
X613470Y759230D03*
G54D102*
X168071Y1411468D03*
Y1432728D03*
X300044Y1387041D03*
Y1408301D03*
X328994Y1376650D03*
Y1397910D03*
G54D111*
X189254Y1522200D03*
X193979D03*
X198703D03*
X189254Y1524169D03*
Y1526137D03*
X193979Y1524169D03*
Y1526137D03*
X198703Y1524169D03*
Y1526137D03*
X189254Y1528106D03*
X193979D03*
X198703D03*
X203428Y1522200D03*
X208152D03*
X212876D03*
Y1524169D03*
Y1526137D03*
X203428Y1524169D03*
Y1526137D03*
X208152Y1524169D03*
Y1526137D03*
X203428Y1528106D03*
X208152D03*
X212876D03*
X217601Y1522200D03*
X222325D03*
X227050D03*
Y1526137D03*
X217601Y1524169D03*
Y1526137D03*
X222325Y1524169D03*
Y1526137D03*
X227050Y1524169D03*
X217601Y1528106D03*
X222325D03*
X227050D03*
X231774Y1522200D03*
X236498D03*
X241223D03*
X245947D03*
X231774Y1524169D03*
Y1526137D03*
X236498Y1524169D03*
Y1526137D03*
X241223Y1524169D03*
Y1526137D03*
X245947Y1524169D03*
Y1526137D03*
X231774Y1528106D03*
X236498D03*
X241223D03*
X245947D03*
X255396Y1522200D03*
X250672D03*
X255396Y1524169D03*
Y1526137D03*
X250672Y1524169D03*
Y1526137D03*
X255396Y1528106D03*
X250672D03*
X317316Y1522200D03*
Y1524169D03*
Y1526137D03*
Y1528106D03*
X322041Y1522200D03*
X326765D03*
X331490D03*
X322041Y1524169D03*
Y1526137D03*
X326765Y1524169D03*
Y1526137D03*
X331490Y1524169D03*
Y1526137D03*
X322041Y1528106D03*
X326765D03*
X331490D03*
X336214Y1522200D03*
X340938D03*
X345663D03*
X350387D03*
X340938Y1524169D03*
Y1526137D03*
X336214Y1524169D03*
Y1526137D03*
X345663Y1524169D03*
Y1526137D03*
X350387Y1524169D03*
Y1526137D03*
X336214Y1528106D03*
X340938D03*
X345663D03*
X350387D03*
X355112Y1522200D03*
X359836D03*
X364560D03*
X359836Y1524169D03*
Y1526137D03*
X364560Y1524169D03*
Y1526137D03*
X355112D03*
Y1524169D03*
Y1528106D03*
X359836D03*
X364560D03*
X369285Y1522200D03*
X374009D03*
X378734D03*
X369285Y1524169D03*
Y1526137D03*
X374009Y1524169D03*
Y1526137D03*
X378734Y1524169D03*
Y1526137D03*
X369285Y1528106D03*
X374009D03*
X378734D03*
X383458Y1522200D03*
Y1524169D03*
Y1526137D03*
Y1528106D03*
X453427Y1522200D03*
Y1524169D03*
Y1526137D03*
Y1528106D03*
X458152Y1522200D03*
X462876D03*
X467601D03*
X458152Y1524169D03*
Y1526137D03*
X462876Y1524169D03*
Y1526137D03*
X467601Y1524169D03*
Y1526137D03*
X458152Y1528106D03*
X462876D03*
X467601D03*
X472325Y1522200D03*
X477049D03*
X481774D03*
X477049Y1524169D03*
Y1526137D03*
X472325Y1524169D03*
Y1526137D03*
X481774Y1524169D03*
Y1526137D03*
X472325Y1528106D03*
X477049D03*
X481774D03*
X486498Y1522200D03*
X491223D03*
X495947D03*
Y1524169D03*
Y1526137D03*
X491223D03*
X486498Y1524169D03*
Y1526137D03*
X491223Y1524169D03*
X486498Y1528106D03*
X491223D03*
X495947D03*
X500671Y1522200D03*
X505396D03*
X510120D03*
X500671Y1524169D03*
Y1526137D03*
X505396Y1524169D03*
Y1526137D03*
X510120Y1524169D03*
Y1526137D03*
X500671Y1528106D03*
X505396D03*
X510120D03*
X519569Y1522200D03*
X514845D03*
X519569Y1524169D03*
Y1526137D03*
X514845Y1524169D03*
Y1526137D03*
X519569Y1528106D03*
X514845D03*
X581489Y1522200D03*
X586214D03*
X581489Y1524169D03*
Y1526137D03*
X586214Y1524169D03*
Y1526137D03*
X581489Y1528106D03*
X586214D03*
X590938Y1522200D03*
X595663D03*
X600387D03*
X590938Y1524169D03*
Y1526137D03*
X595663Y1524169D03*
Y1526137D03*
X600387Y1524169D03*
Y1526137D03*
X590938Y1528106D03*
X595663D03*
X600387D03*
X605111Y1522200D03*
X609836D03*
X614560D03*
X605111Y1524169D03*
Y1526137D03*
X609836Y1524169D03*
Y1526137D03*
X614560Y1524169D03*
Y1526137D03*
X605111Y1528106D03*
X609836D03*
X614560D03*
X619285Y1522200D03*
X624009D03*
X628733D03*
X633458D03*
X624009Y1524169D03*
Y1526137D03*
X628733Y1524169D03*
Y1526137D03*
X633458Y1524169D03*
Y1526137D03*
X619285D03*
Y1524169D03*
Y1528106D03*
X624009D03*
X628733D03*
X633458D03*
X647631Y1522200D03*
X638182D03*
X642907D03*
X647631Y1524169D03*
Y1526137D03*
X638182Y1524169D03*
Y1526137D03*
X642907Y1524169D03*
Y1526137D03*
X647631Y1528106D03*
X638182D03*
X642907D03*
X1197127Y1557169D03*
Y1559137D03*
Y1555200D03*
Y1561106D03*
X1201852Y1557169D03*
Y1559137D03*
X1206576Y1557169D03*
Y1559137D03*
X1211301Y1557169D03*
Y1559137D03*
X1201852Y1555200D03*
Y1561106D03*
X1206576Y1555200D03*
Y1561106D03*
X1211301Y1555200D03*
Y1561106D03*
X1220749Y1557169D03*
Y1559137D03*
X1216025Y1557169D03*
Y1559137D03*
X1225474Y1557169D03*
Y1559137D03*
X1216025Y1555200D03*
Y1561106D03*
X1220749Y1555200D03*
Y1561106D03*
X1225474Y1555200D03*
Y1561106D03*
X1239647Y1557169D03*
Y1559137D03*
X1244371Y1557169D03*
Y1559137D03*
X1234923D03*
X1230198Y1557169D03*
Y1559137D03*
X1234923Y1557169D03*
X1230198Y1555200D03*
Y1561106D03*
X1234923Y1555200D03*
Y1561106D03*
X1239647Y1555200D03*
Y1561106D03*
X1244371Y1555200D03*
Y1561106D03*
X1249096Y1557169D03*
Y1559137D03*
X1253820Y1557169D03*
Y1559137D03*
X1258545Y1557169D03*
Y1559137D03*
X1249096Y1555200D03*
Y1561106D03*
X1253820Y1555200D03*
Y1561106D03*
X1258545Y1555200D03*
Y1561106D03*
X1263269Y1557169D03*
Y1559137D03*
Y1555200D03*
Y1561106D03*
X1325189Y1557169D03*
Y1559137D03*
X1329914Y1557169D03*
Y1559137D03*
X1325189Y1555200D03*
Y1561106D03*
X1329914Y1555200D03*
Y1561106D03*
X1348811Y1557169D03*
Y1559137D03*
X1334638Y1557169D03*
Y1559137D03*
X1339363Y1557169D03*
Y1559137D03*
X1344087Y1557169D03*
Y1559137D03*
X1334638Y1555200D03*
Y1561106D03*
X1339363Y1555200D03*
Y1561106D03*
X1344087Y1555200D03*
Y1561106D03*
X1348811Y1555200D03*
Y1561106D03*
X1362985Y1559137D03*
X1353536Y1557169D03*
Y1559137D03*
X1358260Y1557169D03*
Y1559137D03*
X1362985Y1557169D03*
X1353536Y1555200D03*
Y1561106D03*
X1358260Y1555200D03*
Y1561106D03*
X1362985Y1555200D03*
Y1561106D03*
X1367709Y1557169D03*
Y1559137D03*
X1372433Y1557169D03*
Y1559137D03*
X1377158Y1557169D03*
Y1559137D03*
X1367709Y1555200D03*
Y1561106D03*
X1372433Y1555200D03*
Y1561106D03*
X1377158Y1555200D03*
Y1561106D03*
X1391331Y1557169D03*
Y1559137D03*
X1381882Y1557169D03*
Y1559137D03*
X1386607Y1557169D03*
Y1559137D03*
X1391331Y1555200D03*
Y1561106D03*
X1381882Y1555200D03*
Y1561106D03*
X1386607Y1555200D03*
Y1561106D03*
X1461301Y1557169D03*
Y1559137D03*
X1466026Y1557169D03*
Y1559137D03*
X1461301Y1555200D03*
Y1561106D03*
X1466026Y1555200D03*
Y1561106D03*
X1470750Y1557169D03*
Y1559137D03*
X1475475Y1557169D03*
Y1559137D03*
X1480199Y1557169D03*
Y1559137D03*
X1470750Y1555200D03*
Y1561106D03*
X1475475Y1555200D03*
Y1561106D03*
X1480199Y1555200D03*
Y1561106D03*
X1484923Y1557169D03*
Y1559137D03*
X1489648Y1557169D03*
Y1559137D03*
X1494372Y1557169D03*
Y1559137D03*
X1484923Y1555200D03*
Y1561106D03*
X1489648Y1555200D03*
Y1561106D03*
X1494372Y1555200D03*
Y1561106D03*
X1503821Y1557169D03*
Y1559137D03*
X1508545Y1557169D03*
Y1559137D03*
X1513270Y1557169D03*
Y1559137D03*
X1499097D03*
Y1557169D03*
Y1555200D03*
Y1561106D03*
X1503821Y1555200D03*
Y1561106D03*
X1508545Y1555200D03*
Y1561106D03*
X1513270Y1555200D03*
Y1561106D03*
X1527443Y1557169D03*
Y1559137D03*
X1517994Y1557169D03*
Y1559137D03*
X1522719Y1557169D03*
Y1559137D03*
X1527443Y1555200D03*
Y1561106D03*
X1517994Y1555200D03*
Y1561106D03*
X1522719Y1555200D03*
Y1561106D03*
X1589363Y1557169D03*
Y1559137D03*
X1594088Y1557169D03*
Y1559137D03*
X1598812Y1557169D03*
Y1559137D03*
X1589363Y1555200D03*
Y1561106D03*
X1594088Y1555200D03*
Y1561106D03*
X1598812Y1555200D03*
Y1561106D03*
X1612985Y1557169D03*
Y1559137D03*
X1603537Y1557169D03*
Y1559137D03*
X1608261Y1557169D03*
Y1559137D03*
X1603537Y1555200D03*
Y1561106D03*
X1608261Y1555200D03*
Y1561106D03*
X1612985Y1555200D03*
Y1561106D03*
X1631883Y1557169D03*
Y1559137D03*
X1627159D03*
X1617710Y1557169D03*
Y1559137D03*
X1622434Y1557169D03*
Y1559137D03*
X1627159Y1557169D03*
X1617710Y1555200D03*
Y1561106D03*
X1622434Y1555200D03*
Y1561106D03*
X1627159Y1555200D03*
Y1561106D03*
X1631883Y1555200D03*
Y1561106D03*
X1636607Y1557169D03*
Y1559137D03*
X1641332Y1557169D03*
Y1559137D03*
X1646056Y1557169D03*
Y1559137D03*
X1636607Y1555200D03*
Y1561106D03*
X1641332Y1555200D03*
Y1561106D03*
X1646056Y1555200D03*
Y1561106D03*
X1655505Y1557169D03*
Y1559137D03*
X1650781Y1557169D03*
Y1559137D03*
X1655505Y1555200D03*
Y1561106D03*
X1650781Y1555200D03*
Y1561106D03*
G54D112*
X191038Y1572954D03*
Y1579954D03*
X197853Y1579110D03*
Y1586110D03*
X204768Y1579134D03*
Y1586134D03*
X289239Y598826D03*
Y605826D03*
X292747Y1578722D03*
Y1585722D03*
X296139Y598826D03*
X303039D03*
X296139Y605826D03*
X303039D03*
X299938Y1578884D03*
Y1585884D03*
X309939Y598826D03*
X317961Y598861D03*
X309939Y605826D03*
X317961Y605861D03*
X352618Y271310D03*
Y264310D03*
X392153Y209695D03*
Y216695D03*
X463751Y299601D03*
X456871Y299661D03*
X463751Y306601D03*
X456871Y306661D03*
X543871Y315661D03*
Y308661D03*
X550751Y315601D03*
Y308601D03*
X552400Y1578652D03*
X559348Y1578724D03*
X552400Y1585652D03*
X559348Y1585724D03*
X682200Y1521300D03*
Y1514300D03*
X773456Y253292D03*
Y260292D03*
X958452Y162103D03*
Y169103D03*
X969390Y209089D03*
Y216089D03*
X1198911Y1605954D03*
Y1612954D03*
X1205758Y1612274D03*
X1212608D03*
X1205758Y1619274D03*
X1212608D03*
X1295960Y1611652D03*
X1302908Y1611664D03*
X1295960Y1618652D03*
X1302908Y1618664D03*
X1312506Y94027D03*
Y101027D03*
X1567175Y571888D03*
Y578888D03*
X1560074Y1611242D03*
X1566978Y1611364D03*
X1560074Y1618242D03*
X1566978Y1618364D03*
X1597499Y558988D03*
Y565988D03*
X1590399Y558988D03*
Y565988D03*
X1667570Y414332D03*
Y421332D03*
X1679850Y435172D03*
Y428172D03*
X1690074Y1547300D03*
Y1554300D03*
X1750788Y183596D03*
Y190596D03*
X1749833Y205902D03*
Y212902D03*
X1764848Y183533D03*
Y190533D03*
X1757848Y183533D03*
Y190533D03*
X1763983Y205965D03*
X1756923Y205902D03*
X1763983Y212965D03*
X1756923Y212902D03*
X1765070Y255527D03*
X1757970Y255427D03*
X1765070Y262527D03*
X1757970Y262427D03*
X1771848Y183533D03*
Y190533D03*
X1770848Y211565D03*
Y204565D03*
X1777848Y211565D03*
Y204565D03*
G54D121*
X260521Y104291D03*
X258553D03*
Y115315D03*
X260521D03*
X274301Y104291D03*
X272333D03*
X270364D03*
X268395D03*
X266427D03*
X264459D03*
X262490D03*
Y115315D03*
X264459D03*
X266427D03*
X268395D03*
X270364D03*
X272333D03*
X691709Y108416D03*
Y119440D03*
X707457Y108416D03*
X705489D03*
X703520D03*
X701551D03*
X699583D03*
X697615D03*
X695646D03*
X693677D03*
Y119440D03*
X695646D03*
X697615D03*
X699583D03*
X701551D03*
X703520D03*
X705489D03*
X997487Y211742D03*
X1001423D03*
X1735642Y105415D03*
X1733674D03*
Y116439D03*
X1735642D03*
X1749422Y105415D03*
X1747454D03*
X1745485D03*
X1743516D03*
X1741548D03*
X1739580D03*
X1737611D03*
Y116439D03*
X1739580D03*
X1741548D03*
X1743516D03*
X1745485D03*
X1747454D03*
G54D103*
X186831Y151000D03*
X178169Y147260D03*
Y154740D03*
X396102Y536138D03*
X387440Y532398D03*
Y539878D03*
X588099Y253691D03*
Y261171D03*
X596761Y257431D03*
X608169Y447260D03*
X616831Y451000D03*
X608169Y454740D03*
X607557Y479606D03*
X616219Y475866D03*
Y483346D03*
X855184Y530845D03*
Y538325D03*
X863846Y534585D03*
X919968Y554548D03*
X928630Y558288D03*
X919968Y562028D03*
X1144118Y1445987D03*
Y1453467D03*
X1152780Y1449727D03*
G54D130*
X275558Y589395D03*
G54D211*
X609016Y274272D03*
G54D301*
X1500126Y609338D03*
X1520008D03*
G54D10*
X8879Y180928D03*
X8013Y219222D03*
X6109Y1673058D03*
X18691Y180321D03*
X14517Y223688D03*
X34180Y293407D03*
X38944Y303000D03*
X39600Y378562D03*
X38800Y406562D03*
X39163Y519914D03*
X40373Y762118D03*
Y768332D03*
X55301Y53544D03*
X44700Y375262D03*
X50200D03*
X53500Y371362D03*
X40800Y400962D03*
X43814Y408139D03*
X47902Y512585D03*
X53658Y512639D03*
X41010Y534105D03*
X49039Y542027D03*
X54399D03*
X42150Y1546791D03*
X45120Y1603396D03*
X45833Y1626496D03*
X50927Y1663587D03*
Y1668587D03*
X49069Y1678149D03*
X59406Y57055D03*
X64000Y306000D03*
X65710Y376042D03*
X63350Y371362D03*
X57342Y375262D03*
X58254Y514975D03*
X59849Y541987D03*
X66250Y1412899D03*
X68392Y1432013D03*
X59039Y1549644D03*
X66854Y1597165D03*
X61133Y1631796D03*
X56133Y1631696D03*
X62152Y1653448D03*
X68399Y1653382D03*
X56821Y1653527D03*
X64462Y1678404D03*
X56694Y1677916D03*
X70237Y1678363D03*
X80991Y151189D03*
X84009Y146557D03*
X80979Y156192D03*
X80965Y161194D03*
X84377Y166361D03*
X71136Y390398D03*
X76600Y386364D03*
X70500Y381562D03*
X71480Y399442D03*
X76200Y395865D03*
X78760Y1312186D03*
Y1307106D03*
X70460Y1600665D03*
X74233Y1614396D03*
Y1607847D03*
X73399Y1653408D03*
X79117Y1666864D03*
X82630Y1678315D03*
X76468Y1678409D03*
X89539Y-76554D03*
X89009Y146231D03*
X94010Y146250D03*
X98892Y147345D03*
X94291Y167275D03*
X89290Y167307D03*
X93193Y1377757D03*
X92988Y1560481D03*
X100939Y-76554D03*
X112339D03*
X100818Y165506D03*
X113500Y1398600D03*
X102376Y1409377D03*
X102548Y1415954D03*
X107202Y1558112D03*
X123739Y-76554D03*
X120016Y289822D03*
X115016D03*
X120016Y310256D03*
X115016D03*
X124700Y1401000D03*
X120700Y1408100D03*
X118658Y1455464D03*
X121500Y1467400D03*
X120353Y1655843D03*
X119927Y1669843D03*
Y1674843D03*
X123353Y1686843D03*
X135139Y-76554D03*
X136617Y521997D03*
Y526997D03*
X143649Y672383D03*
X143949Y677610D03*
X141514Y1436500D03*
X132353Y1655769D03*
X144253Y1655843D03*
X132427Y1686343D03*
X137427D03*
X157939Y-76554D03*
X146539D03*
X157923Y1520968D03*
X152339Y1655756D03*
X144985Y1671863D03*
X151353Y1686843D03*
X169339Y-76554D03*
X162112Y1450019D03*
X166180Y1514420D03*
X161162Y1514314D03*
X167900Y1540000D03*
Y1535000D03*
Y1530000D03*
X180739Y-76554D03*
X186421Y671555D03*
X184700Y677660D03*
X185124Y1701851D03*
X185084Y1691988D03*
X192139Y-76554D03*
X203539D03*
X195979Y106017D03*
X192845Y136262D03*
X195979Y125562D03*
X204088Y138912D03*
X197375Y152500D03*
X197575Y160432D03*
X198698Y1662215D03*
X214939Y-76554D03*
X208179Y106017D03*
X214900Y120502D03*
X218402Y148760D03*
X211862Y1701100D03*
X233335Y57341D03*
X233785Y208935D03*
X227157Y715915D03*
X245330Y56939D03*
X239734Y57435D03*
X237929Y107838D03*
X242196Y119305D03*
X243813Y132383D03*
X236916Y146832D03*
X237396Y163965D03*
X248625Y762182D03*
X243625D03*
X249909Y58971D03*
X253086Y87365D03*
X254936Y146882D03*
X254821Y151940D03*
X259496Y162665D03*
X256090Y206540D03*
X263271Y771988D03*
X259490Y1565110D03*
X258560Y1558660D03*
X274996Y153865D03*
X275049Y148706D03*
X276996Y143965D03*
X274996Y159206D03*
X278697Y165096D03*
X265075Y213077D03*
X264818Y227950D03*
X276704Y1526953D03*
X264617Y1561520D03*
X287196Y143965D03*
X292496Y144016D03*
X281996Y143965D03*
X284990Y168020D03*
X290840Y170080D03*
X283811Y215870D03*
X286546Y222118D03*
X287000Y243069D03*
X292740Y242691D03*
X286872Y1508981D03*
X289460Y1520200D03*
X289224Y1514314D03*
X281704Y1526953D03*
X297696Y144165D03*
X294224Y1514314D03*
X308222Y1561079D03*
X319641Y274000D03*
X314271Y593038D03*
X314771Y1555834D03*
X312715Y1575985D03*
X329221Y164920D03*
X333031Y255324D03*
X337750Y584750D03*
X339811Y131052D03*
X341895Y233980D03*
X342192Y270260D03*
X351157Y550415D03*
Y590415D03*
X365400Y146910D03*
X365836Y163265D03*
X365162Y243366D03*
X357391Y286874D03*
X357341Y281424D03*
X366000Y307500D03*
X365071Y551038D03*
X362200Y566750D03*
X364047Y556773D03*
X360261Y561044D03*
X379090Y157936D03*
X376091Y287874D03*
Y280274D03*
Y295474D03*
X382184Y476726D03*
Y496726D03*
X371962Y524954D03*
X380771Y542138D03*
X379689Y586040D03*
X368798Y587938D03*
X376197Y1576200D03*
X375513Y1587172D03*
X387894Y135157D03*
X397090Y151741D03*
X389000Y303760D03*
X394184Y476726D03*
X397184Y496726D03*
X392184D03*
X388985Y554870D03*
X395171Y559463D03*
X397101Y566188D03*
X395157Y573815D03*
X393604Y579473D03*
X387103Y584506D03*
X391175Y1565695D03*
X393261Y1560775D03*
X386822Y1556550D03*
X389128Y1576969D03*
X391604Y1587172D03*
X387324Y1670120D03*
X392324D03*
X397324D03*
X403881Y133980D03*
X406000Y139483D03*
X398599Y209695D03*
X407299Y201500D03*
X402184Y476844D03*
Y496726D03*
X406512Y534213D03*
X399657Y546915D03*
X409766Y1526953D03*
X404766D03*
X404775Y1535976D03*
Y1540976D03*
X407611Y1599022D03*
X401547Y1603022D03*
X407676Y1626475D03*
X412342Y1628467D03*
X406441Y1657000D03*
X427549Y60016D03*
X414400Y110770D03*
X413416Y153150D03*
X420527Y144234D03*
X427299Y199500D03*
X419299Y201000D03*
X422302Y214926D03*
X420000Y219940D03*
X423583Y245868D03*
X424220Y253768D03*
Y263768D03*
Y258768D03*
X415984Y476767D03*
Y496649D03*
X414934Y1508981D03*
X419934D03*
X425571Y1520200D03*
X424775Y1513907D03*
X422437Y1526983D03*
X425000Y1626900D03*
X413299Y1633417D03*
X417000Y1661000D03*
X440186Y93386D03*
X432200Y101800D03*
X428085Y98885D03*
X442221Y100933D03*
X436482Y98172D03*
X435383Y149854D03*
X441240Y149323D03*
X429200Y155890D03*
X435299Y201745D03*
X429784Y476690D03*
Y496572D03*
X435580Y1279986D03*
X430335Y1514314D03*
X431682Y1601671D03*
X433795Y1606554D03*
X436500Y1618700D03*
X428500Y1630500D03*
X434280Y1644807D03*
X446797Y148500D03*
X454997Y155750D03*
X443299Y201745D03*
X451224Y201820D03*
X447691Y489766D03*
X453470Y1555409D03*
X446959Y1576531D03*
X446807Y1585178D03*
X443594Y1640854D03*
X464249Y60016D03*
X466449Y55016D03*
X465849Y65016D03*
X465687Y105944D03*
X469874Y100869D03*
X466396Y95901D03*
X466600Y118000D03*
X468348Y112011D03*
X466600Y133000D03*
Y138000D03*
X466680Y124253D03*
X462637Y146170D03*
X468997Y155750D03*
X461997D03*
X459174Y209620D03*
Y204620D03*
X468540Y293270D03*
X461535Y293862D03*
X459673Y1572604D03*
X463581Y1584220D03*
X465000Y1644000D03*
X464500Y1679774D03*
X465000Y1705500D03*
X464500Y1711500D03*
X485260Y168390D03*
X478997Y155750D03*
X473997D03*
X485997D03*
X475578Y214985D03*
X477856Y1682741D03*
X479000Y1706500D03*
X502204Y179084D03*
X488800Y307380D03*
X515539Y77767D03*
X510477D03*
X507204Y179084D03*
X512204D03*
X510786Y194424D03*
X506462Y190316D03*
X510692Y248651D03*
X513193Y436878D03*
X511601Y445740D03*
X523150Y77767D03*
X528212D03*
X523504Y214072D03*
X528450Y1564400D03*
X523250Y1564540D03*
X522933Y1556550D03*
X544600Y131060D03*
X546461Y156667D03*
X533850Y169018D03*
X545396Y184681D03*
X536821Y190256D03*
Y195256D03*
X537402Y430775D03*
X540751Y603398D03*
X545877Y1526953D03*
X540877D03*
X554196Y179881D03*
X555755Y302485D03*
X548945Y302782D03*
X556248Y389786D03*
Y394786D03*
X561048Y412774D03*
X553715Y408628D03*
X556981Y451000D03*
X553058Y472332D03*
X555897Y657605D03*
Y662605D03*
X555091Y1265586D03*
X547645Y1509085D03*
X553633Y1520200D03*
X558397Y1514314D03*
X553397D03*
X572232Y77862D03*
X562784Y78299D03*
X572221Y83562D03*
X567521Y87362D03*
X567508Y81049D03*
X562821Y84262D03*
X575800Y316330D03*
X571925Y458443D03*
X570216Y759762D03*
X575216D03*
X570216Y772262D03*
X575216D03*
X572395Y1561079D03*
X572243Y1569327D03*
X586394Y78494D03*
X579060Y77970D03*
X579885Y371627D03*
X585585Y382427D03*
Y395177D03*
X578248Y415846D03*
X590998Y411846D03*
X578248Y423949D03*
X578267Y431976D03*
X584165Y479658D03*
X578944Y1555834D03*
X602287Y85071D03*
X595394Y144640D03*
X599030Y225861D03*
Y219777D03*
X605650Y214136D03*
X599974Y214461D03*
X594105Y234277D03*
X604974Y235511D03*
X600494Y232821D03*
X592248Y389786D03*
X598185Y404287D03*
X594251Y425240D03*
X600000Y446000D03*
X599623Y458376D03*
X599452Y470130D03*
X595253Y1266668D03*
X618039Y84584D03*
X616274Y187961D03*
X621274D03*
X616274Y197961D03*
X621274D03*
X616274Y192961D03*
X621274D03*
Y207961D03*
X616274Y202961D03*
X621274D03*
X616274Y212961D03*
X611074Y214061D03*
X620735Y215169D03*
X610304Y235381D03*
X615885Y371627D03*
X621585Y382427D03*
Y395177D03*
X617000Y435632D03*
X615425Y422465D03*
X634914Y121280D03*
X626705Y285305D03*
X631505Y299730D03*
Y294730D03*
X624609Y468828D03*
X622434Y1362366D03*
X628194Y1395604D03*
X634516Y1686547D03*
X633333Y1692156D03*
X642541Y78436D03*
X646388Y89882D03*
X651391Y138972D03*
Y133972D03*
X642394Y144262D03*
X651391Y143972D03*
Y148972D03*
X648585Y302289D03*
X649888Y395717D03*
X651132Y436517D03*
X650875Y449862D03*
X650800Y456240D03*
X651016Y469863D03*
X637522Y501978D03*
X643313Y518746D03*
X638967Y671774D03*
X638847Y1389887D03*
X650995Y1556550D03*
X657166Y79131D03*
X654391Y152972D03*
X654471Y163972D03*
X654371Y158572D03*
X654157Y169197D03*
X654326Y174437D03*
X654311Y186192D03*
X656318Y254591D03*
X656128Y263486D03*
X659326Y363566D03*
X659575Y478662D03*
X651908Y507929D03*
Y514092D03*
X666100Y1308048D03*
Y1312502D03*
X663224Y1387870D03*
X663431Y1645780D03*
X659837Y1698400D03*
X660654Y1704783D03*
X675242Y111960D03*
X673861Y121202D03*
X678072Y128093D03*
X680200Y417110D03*
Y425280D03*
X680266Y434313D03*
X680250Y452074D03*
Y459812D03*
Y467712D03*
X668660Y486095D03*
X681227Y488419D03*
X668946Y1508979D03*
X679792Y1536622D03*
X667971Y1685417D03*
X669513Y1732836D03*
X669555Y1723539D03*
X686211Y91492D03*
X695040Y401079D03*
X694600Y406060D03*
X683500Y421080D03*
X683400Y430360D03*
Y445830D03*
X683300Y438320D03*
X683450Y455932D03*
Y463812D03*
X694549Y499912D03*
X688500Y535514D03*
X691682Y586081D03*
X686211Y1534158D03*
X696554Y125044D03*
X710451Y152512D03*
X710799Y163012D03*
X700000Y386790D03*
X704000Y406000D03*
X699945Y402495D03*
X708218Y401233D03*
X709570Y504315D03*
X697359Y504128D03*
X700278Y499958D03*
X706041Y500099D03*
X700461Y517157D03*
X704710Y668000D03*
X698391Y1385228D03*
X708994Y1568507D03*
X710420Y1585173D03*
X710550Y1576523D03*
X709836Y1594721D03*
X709382Y1601210D03*
X697950Y1634097D03*
X707997Y1630768D03*
X702160Y1647367D03*
X709523Y1674429D03*
X704019Y1671507D03*
X704659Y1678474D03*
X719640Y386862D03*
X711500Y405673D03*
X723500Y401062D03*
X715500Y401378D03*
X719500Y406062D03*
X724500Y503014D03*
X712500Y500014D03*
X720500D03*
X716500Y503014D03*
X720400Y517440D03*
X718129Y656130D03*
X723166Y656225D03*
X715803Y670949D03*
X715152Y1634265D03*
X721898Y1636624D03*
X725371Y1673230D03*
X718891Y1672937D03*
X721408Y1677865D03*
X739500Y383500D03*
X733900Y405940D03*
X737425Y402000D03*
X736500Y500014D03*
X732500Y503014D03*
X728500Y500014D03*
X728938Y517520D03*
X741000Y518862D03*
X736339Y514603D03*
X731694Y662061D03*
X730782Y1555496D03*
X727755Y1636539D03*
X732260Y1633591D03*
X736485Y1636763D03*
X740723Y1633619D03*
X738526Y1674392D03*
X730592Y1672921D03*
X734017Y1676824D03*
X741850Y87100D03*
X753601Y143438D03*
X753501Y151312D03*
X755901Y170562D03*
X753500Y208000D03*
X746500Y207500D03*
X751000Y225000D03*
X754800Y379919D03*
X743500Y386962D03*
X745000Y400000D03*
X744000Y405970D03*
X750800Y405992D03*
X753700Y401179D03*
X752500Y500014D03*
X742144Y504935D03*
X744500Y500014D03*
X748500Y503014D03*
X747110Y1579863D03*
X747160Y1587773D03*
X744315Y1673134D03*
X745382Y1683663D03*
X764343Y162084D03*
X761000Y199000D03*
X763958Y272775D03*
X764767Y267322D03*
X763500Y386862D03*
X756300Y405840D03*
X762500Y401100D03*
X761600Y406060D03*
X766300Y404280D03*
X757500Y499980D03*
X765690D03*
X761500Y503014D03*
X764600Y517022D03*
X766566Y532172D03*
X770800Y535640D03*
X757770Y1636083D03*
X761510Y1656483D03*
X773901Y170064D03*
X783267Y267722D03*
Y282922D03*
Y275322D03*
X772513Y374490D03*
X783736Y441100D03*
X783241Y461515D03*
X777385Y466879D03*
X783796Y456205D03*
X783895Y470961D03*
X783759Y479344D03*
X777465Y483344D03*
X776400Y533300D03*
X778850Y1556133D03*
X771592Y1572717D03*
X771650Y1591733D03*
X793879Y194881D03*
X789942Y204724D03*
X793879Y214567D03*
X794058Y301569D03*
X793221Y296062D03*
X793897Y309026D03*
X786624Y465585D03*
X800185Y453381D03*
X799150Y1575233D03*
X799775Y1591498D03*
Y1598719D03*
X799888Y1603833D03*
X814115Y120773D03*
X810811Y135132D03*
X810641Y128262D03*
X810481Y141762D03*
X805690Y188976D03*
Y220472D03*
X803302Y265848D03*
X810139Y274098D03*
X805491Y373158D03*
X802175Y418362D03*
X813114Y443344D03*
X801552Y463318D03*
X811189Y524000D03*
X809216Y551473D03*
X814954Y565087D03*
X813400Y1575483D03*
X813571Y1597534D03*
X822531Y125698D03*
X828615D03*
X817501Y194881D03*
X821438Y204724D03*
X817501Y214567D03*
X816232Y341584D03*
X818157Y381020D03*
X816747Y412367D03*
X816236Y439279D03*
X816109Y449802D03*
X816000Y463578D03*
X816170Y458524D03*
X816109Y471344D03*
X820500Y515323D03*
X817441Y533000D03*
X820850Y1556133D03*
X831540Y70643D03*
X834115Y135698D03*
X833615Y129198D03*
X839461Y146042D03*
X833321Y145912D03*
X831296Y171632D03*
X845221Y192862D03*
X839221D03*
X834921Y220303D03*
X838681Y224752D03*
X843511Y228962D03*
X839081Y233252D03*
X836181Y275686D03*
X843417Y384888D03*
X838500Y471000D03*
X835236Y483635D03*
X841854Y504972D03*
X836893Y537215D03*
X834750Y561347D03*
X841150Y1575233D03*
X841775Y1591574D03*
X841851Y1598753D03*
X841924Y1603879D03*
X852258Y54892D03*
X856630Y70793D03*
X846191Y145262D03*
X849321Y196532D03*
X853341Y199932D03*
X855401Y204772D03*
X859075Y387739D03*
X852000Y408000D03*
X848500Y461500D03*
X852240Y482500D03*
X849351Y499070D03*
X855400Y1575483D03*
X856015Y1596916D03*
X855745Y1615986D03*
X866452Y168862D03*
Y173862D03*
X869901Y209562D03*
X868520Y263654D03*
X871190Y391760D03*
X865366Y393710D03*
X864386Y417186D03*
X862987Y507305D03*
X868496Y776516D03*
X862850Y1556133D03*
X870453Y1616463D03*
X883150Y1575233D03*
X883869Y1591629D03*
X883831Y1598716D03*
X883905Y1603864D03*
X882535Y1616701D03*
X900456Y155618D03*
X895456D03*
X893701Y201799D03*
X899501Y201899D03*
X904850Y1556133D03*
X897381Y1574788D03*
X898065Y1596318D03*
X910258Y600751D03*
X910377Y606694D03*
X925068Y272340D03*
X925650Y1576233D03*
Y1586733D03*
X925726Y1592261D03*
X945263Y269781D03*
X938956Y585132D03*
X940856Y614150D03*
X939681Y628662D03*
X944265Y1285729D03*
X937755Y1594881D03*
X963500Y1275000D03*
X977071Y215709D03*
X981897Y198629D03*
X992830Y260781D03*
Y271443D03*
X992508Y295634D03*
X988646Y371434D03*
X986696Y428366D03*
X988242Y1273193D03*
X1008707Y230423D03*
X997461Y230019D03*
X1008108Y420886D03*
X999304Y1282574D03*
Y1289215D03*
X1014435Y160518D03*
X1021440Y226423D03*
X1010028Y263340D03*
Y274002D03*
X1010550Y298312D03*
X1010157Y288489D03*
X1019264Y493655D03*
X1022764Y489655D03*
X1019410Y485582D03*
X1018872Y549855D03*
X1029269Y378764D03*
X1033069Y382764D03*
X1029269Y386244D03*
X1033449Y424500D03*
X1039015Y444404D03*
X1034246Y553980D03*
X1038333Y551098D03*
X1038054Y544261D03*
X1045848Y194881D03*
X1041911Y204724D03*
X1045848Y214567D03*
X1050639Y1311149D03*
Y1307149D03*
X1057659Y188976D03*
Y220472D03*
X1058223Y464938D03*
X1060316Y460251D03*
X1058205Y471500D03*
X1062258Y467919D03*
X1060719Y516059D03*
X1066019Y1378597D03*
X1069470Y194881D03*
X1073407Y204724D03*
X1069470Y214567D03*
X1075600Y1533700D03*
X1088558Y377306D03*
X1088588Y382506D03*
X1090035Y388477D03*
X1088221Y394170D03*
X1107043Y447355D03*
X1109043Y452855D03*
X1107005Y481355D03*
X1107043Y468039D03*
X1111043Y471855D03*
X1107005Y475355D03*
X1111005Y478355D03*
X1107043Y489391D03*
X1111043Y485771D03*
X1103110Y1533520D03*
X1113167Y1554508D03*
X1105500Y1643500D03*
X1107766Y1635951D03*
X1111167Y1643333D03*
X1110936Y1654416D03*
X1109519Y1660925D03*
X1103489Y1711244D03*
X1128100Y376862D03*
X1127408Y386271D03*
X1126387Y615658D03*
X1123816Y1456373D03*
X1119131Y1534854D03*
X1117665Y1539877D03*
X1125156Y1573436D03*
X1120656D03*
X1115005Y1573346D03*
X1120152Y1597498D03*
X1125756D03*
X1115005Y1587936D03*
X1116481Y1661631D03*
X1120303Y1670114D03*
X1115450Y1685011D03*
X1119361Y1724109D03*
X1141901Y56691D03*
X1138710Y370496D03*
X1131400Y391562D03*
X1141267Y500296D03*
X1143095Y1459523D03*
X1137604Y1561627D03*
X1141916Y1573597D03*
X1132168Y1630557D03*
X1138456Y1632280D03*
X1142350Y1659564D03*
X1135398Y1663760D03*
X1148043Y456855D03*
X1152043Y453121D03*
X1148043Y462921D03*
X1152543Y459855D03*
Y465480D03*
X1148043Y468039D03*
X1152839Y482374D03*
X1151036Y501627D03*
X1155109Y1456295D03*
X1152549Y1562311D03*
X1148089Y1573555D03*
X1163431Y82818D03*
X1166691Y1555367D03*
X1169035Y1547314D03*
X1187374Y59122D03*
X1187214Y52572D03*
X1186734Y65122D03*
X1180777Y90385D03*
X1180280Y100793D03*
X1177336Y577407D03*
X1178536Y584307D03*
X1174053Y1547420D03*
X1175773Y1568000D03*
Y1563000D03*
Y1573000D03*
X1181660Y1690829D03*
X1195488Y83175D03*
X1197381Y133866D03*
X1196227Y432202D03*
Y448202D03*
Y440202D03*
X1195645Y601873D03*
Y605973D03*
X1196988Y1673050D03*
X1189407Y1707143D03*
X1189454Y1723702D03*
X1213107Y161551D03*
X1210607Y157051D03*
Y166051D03*
X1210707Y171051D03*
X1212888Y176470D03*
X1209059Y181187D03*
X1212182Y185187D03*
X1214094Y282948D03*
Y287948D03*
X1209937Y465376D03*
Y460376D03*
Y470376D03*
X1203272Y1399140D03*
X1204492Y1442500D03*
X1204664Y1447500D03*
X1213072Y1673059D03*
X1230693Y150239D03*
X1230094Y287948D03*
Y282948D03*
X1222094D03*
Y292066D03*
Y305216D03*
X1226094Y314216D03*
X1232154Y436875D03*
Y431875D03*
Y441875D03*
X1224200Y1393500D03*
X1221837Y1438800D03*
X1246715Y463158D03*
X1245187Y458182D03*
Y453182D03*
X1239800Y1389500D03*
X1233700Y1395600D03*
X1241613Y1414500D03*
X1239965Y1427544D03*
X1252693Y133549D03*
X1249693Y129239D03*
Y145053D03*
X1253107Y167276D03*
X1249107Y163551D03*
X1253107Y180551D03*
X1249107Y177051D03*
Y170551D03*
X1253107Y174051D03*
X1249107Y184051D03*
X1262094Y282948D03*
X1254094D03*
X1262094Y287948D03*
X1258500Y392500D03*
X1259075Y769000D03*
X1275964Y95379D03*
X1267611Y150030D03*
X1270094Y282948D03*
Y292066D03*
X1274000Y385000D03*
X1277457Y396165D03*
X1269258Y399125D03*
X1272457Y394559D03*
X1269229Y407865D03*
X1277738Y417241D03*
X1272825Y416295D03*
X1277677Y770388D03*
X1264895Y769106D03*
X1267530Y1598620D03*
X1272490Y1594520D03*
X1265783Y1590340D03*
X1283465Y86960D03*
X1284593Y122259D03*
X1287693Y128239D03*
X1290193Y132739D03*
X1287693Y137239D03*
Y146239D03*
X1290193Y141739D03*
X1280901Y168401D03*
X1281128Y161816D03*
X1280791Y173783D03*
X1281570Y184513D03*
X1278094Y282948D03*
X1286094D03*
Y292066D03*
X1282458Y396184D03*
X1287340Y397279D03*
X1280886Y421145D03*
X1281677Y756588D03*
X1290677Y771388D03*
X1289577Y1559953D03*
X1284577D03*
X1296200Y56536D03*
X1301705Y72342D03*
X1294094Y287948D03*
Y282948D03*
X1302094D03*
Y292066D03*
X1296677Y770888D03*
X1297333Y1553200D03*
X1302097Y1547314D03*
X1294745Y1541981D03*
X1297097Y1547314D03*
X1308110Y56536D03*
X1320020Y56604D03*
X1313615Y72342D03*
X1310094Y287948D03*
Y282948D03*
X1318094D03*
X1316095Y1594079D03*
X1315943Y1600322D03*
X1331930Y56570D03*
X1329435Y70452D03*
X1333399Y87709D03*
X1334094Y287948D03*
X1326094Y282948D03*
X1334094D03*
X1326094Y292066D03*
X1337257Y678765D03*
X1322644Y1588834D03*
X1343840Y56536D03*
X1337435Y70452D03*
X1343877D03*
X1341399Y87709D03*
X1348199D03*
X1350094Y287948D03*
X1342094Y282948D03*
X1350094D03*
X1342094Y292066D03*
X1355750Y56536D03*
X1353309Y87675D03*
X1360109D03*
X1356199Y100425D03*
X1366094Y287948D03*
X1358094Y282948D03*
X1366094D03*
X1358094Y292066D03*
X1367950Y56536D03*
X1378945Y68142D03*
X1372655Y236594D03*
Y241594D03*
Y246594D03*
Y251594D03*
X1379261Y1716438D03*
X1394695Y1589550D03*
X1383800Y1695238D03*
X1392420Y1708038D03*
X1410961Y1280751D03*
X1399009Y1598883D03*
X1401552Y1594362D03*
X1398018Y1605304D03*
X1410622Y1617000D03*
X1399940Y1646967D03*
X1424271Y112849D03*
X1422807Y1541981D03*
X1417639Y1559953D03*
X1412639D03*
X1412648Y1568976D03*
Y1573976D03*
X1416000Y1617000D03*
X1418740Y1638167D03*
X1439951Y62174D03*
X1431816Y104219D03*
X1438549Y124818D03*
X1433549D03*
X1435645Y166180D03*
X1427119Y244450D03*
X1440119D03*
X1438209Y1547314D03*
X1433209D03*
X1427807Y1541981D03*
X1429800Y1557762D03*
X1433184Y1628126D03*
X1439500Y1633500D03*
X1450723Y103655D03*
X1443549Y124818D03*
X1450915Y125038D03*
X1449769Y163842D03*
X1441898Y576755D03*
X1449956Y1267923D03*
X1455314Y1267286D03*
X1452207Y1594079D03*
X1454274Y1600121D03*
X1451500Y1633500D03*
X1445500D03*
X1445079Y1677089D03*
X1451000Y1677000D03*
X1445754Y1689990D03*
X1460820Y52933D03*
X1458756Y1588834D03*
X1463231Y1676766D03*
X1472647Y539478D03*
X1473444Y555208D03*
X1478147Y547728D03*
X1484347Y580388D03*
X1481612Y1675112D03*
X1474146Y1687854D03*
X1492789Y576602D03*
X1509479Y130822D03*
X1502085Y545432D03*
X1507109Y550059D03*
X1502757Y570977D03*
X1505477Y1265844D03*
X1513046Y1286424D03*
X1530884Y62569D03*
X1526894Y209250D03*
Y221250D03*
Y214250D03*
Y249250D03*
Y244250D03*
X1519457Y556338D03*
X1522875Y1268496D03*
X1529045Y1280128D03*
X1521346Y1281136D03*
X1518081Y1296288D03*
X1530807Y1589550D03*
X1533815Y57185D03*
X1545747Y301400D03*
X1545556Y292816D03*
X1545187Y306854D03*
X1542842Y1265928D03*
X1532335Y1265721D03*
X1537295Y1274681D03*
X1531750Y1598190D03*
X1536664Y1594520D03*
X1553772Y289856D03*
X1558773Y289875D03*
X1559054Y310900D03*
X1553653Y310980D03*
X1548197Y311209D03*
X1558924Y1541975D03*
X1553751Y1559953D03*
X1548751D03*
X1563655Y290970D03*
X1561507Y1553200D03*
X1566271Y1547314D03*
X1561271D03*
X1582928Y214250D03*
Y234250D03*
Y239250D03*
Y229250D03*
Y244250D03*
X1577934Y531226D03*
X1586818Y1588834D03*
X1580269Y1594079D03*
X1580117Y1600322D03*
X1605241Y541123D03*
X1617534Y289742D03*
X1627800Y519254D03*
X1629833Y1312091D03*
X1634065Y1415729D03*
X1646010Y423702D03*
X1647377Y1385408D03*
X1646533Y1445767D03*
X1662900Y141762D03*
Y151762D03*
Y146762D03*
Y161762D03*
X1654610Y405002D03*
X1661610Y405202D03*
X1653610Y423702D03*
X1661210D03*
X1650757Y626918D03*
X1658869Y1589550D03*
X1680020Y420132D03*
X1674640Y1445639D03*
X1676819Y1541979D03*
X1665726Y1594362D03*
X1679816Y1674318D03*
X1676397Y1684818D03*
X1677930Y1679305D03*
X1676397Y1689818D03*
Y1699818D03*
Y1694818D03*
X1675360Y1716877D03*
Y1732027D03*
X1687537Y1567788D03*
X1694075Y1567158D03*
X1686064Y1573892D03*
X1684816Y1674318D03*
X1689816D03*
X1706066Y57098D03*
X1700617Y1682744D03*
Y1687744D03*
Y1692744D03*
X1722566Y57098D03*
X1717566D03*
X1712566D03*
X1717808Y108959D03*
X1716876Y120278D03*
X1721384Y135373D03*
X1717100Y377962D03*
X1718465Y660982D03*
X1718576Y666238D03*
X1718819Y1400561D03*
X1710360Y1716877D03*
X1729609Y90014D03*
X1731470Y358022D03*
X1738480Y358082D03*
X1735870Y387082D03*
X1728860Y387032D03*
X1730202Y1579277D03*
X1734589Y1666203D03*
X1735463Y1684165D03*
X1734863Y1676514D03*
X1741852Y123774D03*
X1745490Y357002D03*
X1746120Y368132D03*
X1745910Y363112D03*
Y373522D03*
X1742770Y387112D03*
X1747963Y1652565D03*
X1752963Y1652665D03*
X1740463Y1684165D03*
X1745463D03*
X1749480Y1728533D03*
X1756598Y677503D03*
X1762812D03*
X1763263Y1657865D03*
X1763163Y1679965D03*
X1775558Y1604620D03*
X1797692Y146285D03*
X1797765Y151834D03*
Y156834D03*
Y161834D03*
X1785051Y177578D03*
X1795346Y372732D03*
X1793479Y1598723D03*
X1785221Y1605473D03*
X1800212Y390411D03*
X1810924Y427432D03*
X1800979Y1583378D03*
X1815315Y145716D03*
X1814905Y156797D03*
Y166947D03*
X1818274Y366053D03*
Y385293D03*
X1839916Y161834D03*
G54D202*
X539016Y274272D03*
X549016D03*
X559016D03*
X569016D03*
X579016D03*
X589016D03*
X599016D03*
G54D220*
X694226Y144488D03*
Y225984D03*
G54D310*
X1738071Y271402D03*
G54D20*
X18848Y516951D03*
X33001Y401000D03*
X48678Y1519335D03*
X38149Y1594396D03*
Y1607896D03*
Y1598896D03*
Y1603396D03*
Y1612896D03*
Y1617396D03*
X44443Y1668587D03*
Y1663587D03*
X52143Y1681489D03*
X45143Y1681645D03*
X66741Y268223D03*
X57123Y423746D03*
X67149Y1630396D03*
X59143Y1682016D03*
X74267Y145191D03*
X74270Y149191D03*
Y153191D03*
X81890Y382219D03*
Y391391D03*
Y395865D03*
X73516Y1434000D03*
X79149Y1611896D03*
Y1625396D03*
Y1620896D03*
Y1616396D03*
X70683Y1634905D03*
X89017Y140950D03*
X96574Y1353216D03*
X87016Y1417000D03*
Y1412500D03*
Y1408000D03*
Y1421500D03*
X96016Y1426000D03*
Y1430500D03*
Y1440000D03*
Y1435500D03*
X87016D03*
X84421Y1519335D03*
X85712Y1549369D03*
X83212Y1544869D03*
X92283Y1716241D03*
X85436Y1706511D03*
X85273Y1716331D03*
X104637Y1554069D03*
X104002Y1671361D03*
Y1667361D03*
Y1679564D03*
Y1675564D03*
X107516Y1712450D03*
X123369Y1661087D03*
X141508Y521997D03*
Y530997D03*
Y534997D03*
X129174Y1353216D03*
X141016Y1417500D03*
X136936Y1701011D03*
X136834Y1705166D03*
X132783Y1718241D03*
X139783Y1726241D03*
Y1722241D03*
X151716Y438810D03*
X149763Y668361D03*
X145016Y1421500D03*
Y1425500D03*
X155831Y1726500D03*
X168366Y395040D03*
X166382Y684799D03*
Y680799D03*
X161874Y1353216D03*
X172016Y1711000D03*
Y1725000D03*
X174616Y416600D03*
X178496Y438270D03*
X176516Y672500D03*
Y676500D03*
X192936Y140962D03*
X195652Y165325D03*
X194774Y1353216D03*
X199016Y1707000D03*
X197795Y1723000D03*
X222368Y144710D03*
X230536Y159071D03*
X227574Y1353216D03*
X242236Y75862D03*
X234216Y142062D03*
X232759Y715823D03*
X255916Y58400D03*
Y54400D03*
X254816Y73400D03*
X255916Y62400D03*
X257813Y87543D03*
X247313Y115743D03*
X260859Y583999D03*
X261174Y1307070D03*
X275472Y78461D03*
X267069Y151203D03*
Y147203D03*
X267119Y137302D03*
X270016Y211000D03*
X262016Y217500D03*
X278972Y74536D03*
X283816Y136962D03*
X277016Y215000D03*
X283807Y577698D03*
X280657Y574022D03*
X276942Y570398D03*
X283807Y581298D03*
X284483Y1342705D03*
X298182Y67128D03*
X302173Y91767D03*
X295943Y85983D03*
Y82483D03*
X294070Y1307042D03*
X317115Y95852D03*
X317119Y99837D03*
X314355Y227851D03*
Y231851D03*
X310516Y241000D03*
X309016Y263000D03*
X326162Y147120D03*
Y152120D03*
Y156120D03*
Y160120D03*
X326974Y1306985D03*
X343186Y229180D03*
X345673Y586415D03*
X338755Y702203D03*
X352449Y219343D03*
X362924Y294030D03*
X353673Y582415D03*
Y578415D03*
X356073Y590415D03*
Y586415D03*
X359774Y1307185D03*
X376011Y149077D03*
X370979Y163173D03*
X374041Y235455D03*
X374071Y239615D03*
X371815Y701935D03*
X381104Y287370D03*
X387673Y565915D03*
X387473Y571115D03*
X392356Y1326516D03*
X394121Y1611022D03*
Y1607022D03*
Y1603022D03*
Y1599022D03*
X405657Y144300D03*
X402309Y157034D03*
Y152278D03*
X401516Y304000D03*
X399887Y555915D03*
Y561415D03*
X409016Y1641000D03*
X406016Y1649500D03*
X419516Y54762D03*
X413217Y99148D03*
X414456Y226323D03*
Y230323D03*
Y240501D03*
X415231Y254165D03*
Y270165D03*
Y262165D03*
X415682Y1032304D03*
X419516Y1639000D03*
Y1634000D03*
X414016Y1649500D03*
Y1653500D03*
X431267Y1285694D03*
Y1289694D03*
X451315Y206620D03*
Y210620D03*
X451368Y283318D03*
X465515Y210620D03*
Y206620D03*
X465912Y222764D03*
Y235764D03*
Y243764D03*
X462672Y1013604D03*
Y1009864D03*
Y1006123D03*
Y1017344D03*
Y1024824D03*
Y1028564D03*
Y1021084D03*
Y1032304D03*
X465016Y1655500D03*
Y1672000D03*
X465516Y1701000D03*
Y1733500D03*
X480316Y288469D03*
X476321Y309809D03*
X472516Y1668000D03*
Y1659500D03*
Y1676000D03*
Y1697000D03*
Y1710500D03*
Y1733500D03*
X485899Y60105D03*
X486059Y55095D03*
X485789Y64965D03*
X490013Y167625D03*
X489198Y201516D03*
Y197516D03*
X497748D03*
X494550Y233000D03*
Y243178D03*
X501292Y209285D03*
Y213285D03*
Y220166D03*
X511239Y280721D03*
X541712Y190256D03*
Y199256D03*
X543504Y222441D03*
Y235560D03*
Y226441D03*
X538658Y292268D03*
X544253Y659489D03*
X551352Y156667D03*
X551454Y239566D03*
X553189Y403586D03*
X546016Y459000D03*
X559016Y473500D03*
X574519Y164356D03*
Y169415D03*
X567316Y297469D03*
X563321Y318809D03*
X572016Y454500D03*
X578040Y257171D03*
X579976Y366827D03*
X583139Y415846D03*
Y427949D03*
X583158Y431976D03*
X587687Y1266668D03*
Y1262668D03*
X600285Y145640D03*
Y149640D03*
X602794Y157640D03*
X600285Y153640D03*
X591045Y213277D03*
X598239Y289721D03*
X593516Y445500D03*
Y449500D03*
X597014Y464349D03*
X590519Y474353D03*
X600287Y1270598D03*
Y1278598D03*
Y1274598D03*
X613298Y179720D03*
X605909Y260010D03*
X615976Y366827D03*
X615516Y418000D03*
X615407Y426901D03*
X628016Y427000D03*
X629519Y437881D03*
X630175Y461441D03*
X629925Y468856D03*
X619329Y1371182D03*
X619354Y1382864D03*
Y1378964D03*
X619329Y1375082D03*
X619293Y1390732D03*
X646237Y184862D03*
X634625Y230975D03*
Y226975D03*
X648676Y307089D03*
X642596Y401580D03*
X642540Y405449D03*
X647016Y418500D03*
X643016Y433862D03*
X647016Y422500D03*
X643016Y437862D03*
Y442362D03*
Y453862D03*
Y449862D03*
X643140Y461853D03*
X643027Y457746D03*
X643157Y469863D03*
X643016Y488000D03*
X647016Y519500D03*
X659516Y390000D03*
X656516Y429862D03*
Y425862D03*
Y433862D03*
Y453862D03*
Y469862D03*
Y473862D03*
X655738Y1363394D03*
X655770Y1367283D03*
X652716Y1687400D03*
X653316Y1708184D03*
X662516Y1712084D03*
X653316Y1702400D03*
X664739Y363261D03*
X672516Y417862D03*
Y413362D03*
Y433862D03*
Y429862D03*
Y425862D03*
Y421862D03*
Y442362D03*
Y449862D03*
X672548Y486942D03*
X672805Y495084D03*
X665516Y533500D03*
X671116Y1312502D03*
X677821Y1635842D03*
Y1647842D03*
X690736Y76962D03*
X690969Y91668D03*
X680469Y119868D03*
X704130Y1371225D03*
X702126Y1564523D03*
X702016Y1556500D03*
X702126Y1576523D03*
Y1572523D03*
Y1568523D03*
Y1584523D03*
X702016Y1596500D03*
X702126Y1588523D03*
Y1592523D03*
X702016Y1604500D03*
X699244Y1623062D03*
X696855Y1681996D03*
X710237Y221862D03*
X713537Y1403571D03*
X717266Y1566333D03*
X730009Y86998D03*
X730519Y105468D03*
Y101968D03*
X738249Y111252D03*
X736912Y1371325D03*
X724266Y1566333D03*
X725377Y1610743D03*
X725266Y1606733D03*
X751649Y115288D03*
X751651Y119172D03*
X745761Y137864D03*
X748251Y161463D03*
X748516Y175500D03*
X746319Y1403671D03*
X752126Y1580023D03*
X754570Y228201D03*
X756782Y269322D03*
Y265322D03*
X763153Y1570633D03*
X763166Y1574733D03*
Y1578733D03*
Y1587733D03*
X774936Y163254D03*
X773043Y303410D03*
X772958Y308755D03*
X779016Y367500D03*
X776168Y415344D03*
X775168Y431344D03*
Y427344D03*
Y423344D03*
Y447344D03*
Y443344D03*
Y439344D03*
Y435344D03*
Y451344D03*
X788282Y274822D03*
X786143Y303410D03*
X786058Y308755D03*
X789516Y403000D03*
Y399000D03*
X789618Y419344D03*
X789516Y411500D03*
X789618Y431344D03*
Y427344D03*
Y423344D03*
X789668Y435344D03*
X789618Y443344D03*
X789668Y447344D03*
X805516Y392500D03*
X812516D03*
X806551Y427344D03*
X806525Y435628D03*
X805425Y439628D03*
X806449Y459344D03*
Y455344D03*
X806516Y508000D03*
X804666Y1570633D03*
Y1578633D03*
Y1594633D03*
Y1582633D03*
Y1602633D03*
X820016Y409500D03*
X827016D03*
X820935Y427344D03*
Y431344D03*
Y443552D03*
X821062Y439279D03*
X820935Y435628D03*
Y449802D03*
Y459344D03*
X837342Y90451D03*
X839236Y129362D03*
Y135862D03*
X837074Y435552D03*
Y439552D03*
Y443552D03*
Y459578D03*
Y455578D03*
Y463578D03*
X835516Y475000D03*
X848737Y135862D03*
Y129362D03*
X856319Y265057D03*
X856829Y283527D03*
Y280027D03*
X848516Y381000D03*
Y385000D03*
X852716Y401280D03*
X852778Y524413D03*
X846666Y1570633D03*
Y1578633D03*
Y1594633D03*
Y1582633D03*
Y1602633D03*
X871236Y171362D03*
Y176862D03*
X865409Y223763D03*
X858108Y240441D03*
X865409Y227763D03*
X864559Y289311D03*
X859016Y391500D03*
X881241Y192055D03*
X877959Y293347D03*
X877982Y297365D03*
X878016Y301500D03*
X877516Y326000D03*
X902467Y597449D03*
X902316Y602182D03*
X894139Y1137843D03*
X894546Y1149069D03*
Y1153497D03*
X899410Y1159831D03*
X888666Y1570633D03*
Y1578633D03*
Y1594633D03*
Y1582633D03*
Y1602633D03*
X906688Y582412D03*
X903647Y611358D03*
X906688Y625912D03*
X906564Y1161169D03*
X926540Y570703D03*
X930666Y1590233D03*
X941461Y185052D03*
Y189052D03*
X945097Y590417D03*
X941164Y1137843D03*
X941571Y1149069D03*
Y1153497D03*
X946435Y1159831D03*
X961641Y202096D03*
X953589Y1161169D03*
X965141Y198171D03*
X991516Y152299D03*
X982440Y175483D03*
X984971Y264781D03*
Y275443D03*
X977241Y1055484D03*
X998516Y152299D03*
X994428Y217233D03*
X992900Y473675D03*
Y479175D03*
X996572Y521014D03*
Y516014D03*
Y526074D03*
Y531074D03*
X1009892Y175278D03*
Y171278D03*
X1013836Y194499D03*
X1021485Y378764D03*
Y383764D03*
Y388764D03*
X1021516Y402000D03*
X1021485Y393764D03*
X1014073Y425902D03*
X1011280Y460155D03*
Y456155D03*
Y452155D03*
Y464155D03*
Y468155D03*
Y476155D03*
Y472155D03*
Y493655D03*
Y488642D03*
Y480155D03*
X1012302Y550074D03*
Y545074D03*
X1027920Y287311D03*
Y298311D03*
X1028516Y566000D03*
X1043761Y406586D03*
X1039770Y516014D03*
Y521074D03*
Y526074D03*
Y534074D03*
X1042516Y538000D03*
X1041770Y544574D03*
Y549574D03*
X1041847Y553641D03*
X1065810Y475525D03*
X1065780Y483655D03*
Y487655D03*
X1068597Y369792D03*
X1074810Y471500D03*
Y467000D03*
X1074726Y483782D03*
Y487782D03*
X1068312Y1353197D03*
X1087027Y373187D03*
X1081751Y387226D03*
Y379226D03*
Y383226D03*
Y391226D03*
X1090454Y472105D03*
X1091630Y1687229D03*
Y1691229D03*
X1098964Y447355D03*
Y463355D03*
Y459355D03*
Y455355D03*
Y451355D03*
Y467355D03*
Y475355D03*
Y484391D03*
Y489391D03*
X1100912Y1353197D03*
X1099016Y1642500D03*
X1099580Y1696029D03*
X1108380Y1711244D03*
X1133612Y1353197D03*
X1159027Y73939D03*
X1169722Y442341D03*
Y447841D03*
Y464341D03*
Y453341D03*
Y458841D03*
Y469841D03*
Y481691D03*
X1166512Y1353197D03*
X1160291Y1454234D03*
X1178703Y61515D03*
Y57015D03*
X1178723Y52815D03*
X1185103Y99694D03*
X1185208Y574322D03*
X1192218Y177187D03*
Y173187D03*
X1188443Y432202D03*
Y448202D03*
Y440202D03*
Y460202D03*
X1188563Y470392D03*
X1188503Y465272D03*
X1199628Y582443D03*
Y587443D03*
X1199312Y1353197D03*
X1188016Y1401000D03*
Y1396500D03*
Y1405500D03*
Y1410000D03*
X1197016Y1414500D03*
Y1419000D03*
Y1428500D03*
Y1433000D03*
X1188016Y1437500D03*
X1189553Y1693850D03*
X1196553D03*
X1192703Y1689850D03*
X1199993Y1731803D03*
X1202528Y164987D03*
Y160987D03*
Y185187D03*
X1204895Y1693859D03*
X1211895D03*
X1208045Y1689859D03*
X1241709Y128239D03*
Y132739D03*
Y123739D03*
Y137239D03*
X1231209Y145239D03*
X1236970Y427255D03*
Y431255D03*
Y439255D03*
Y435255D03*
X1237303Y1307051D03*
X1240016Y1406500D03*
X1258963Y459182D03*
X1259033Y454372D03*
X1250078Y453182D03*
Y458182D03*
X1245516Y1410500D03*
Y1414500D03*
X1272627Y154030D03*
X1262715Y395125D03*
X1262718Y399125D03*
X1263016Y765000D03*
X1270199Y1307023D03*
X1260612Y1342686D03*
X1277465Y390884D03*
X1295209Y141739D03*
Y137739D03*
X1296123Y162051D03*
Y166051D03*
Y171551D03*
Y184051D03*
X1299167Y527418D03*
X1297248Y541634D03*
X1300782Y552813D03*
X1304239Y560209D03*
X1291850Y592871D03*
X1303103Y1306966D03*
X1316357Y567148D03*
X1309203Y565771D03*
X1318454Y1408282D03*
X1343312Y678393D03*
X1335903Y1307166D03*
X1378231Y236594D03*
Y241594D03*
Y246594D03*
Y251594D03*
X1368485Y1326497D03*
X1391824Y1032303D03*
X1382009Y1670391D03*
X1389009Y1674391D03*
X1384561Y1700038D03*
X1388691Y1695238D03*
X1384561Y1712038D03*
Y1708038D03*
X1387120Y1728318D03*
X1407706Y1285765D03*
Y1289765D03*
X1398149Y1622167D03*
X1405149Y1626167D03*
X1404831Y1646967D03*
X1423813Y1609904D03*
Y1623366D03*
X1418831Y1646967D03*
X1432198Y117664D03*
X1438814Y1013603D03*
Y1009863D03*
Y1006122D03*
Y1017343D03*
Y1028563D03*
Y1021083D03*
Y1024823D03*
Y1032303D03*
X1432825Y1613904D03*
X1433013Y1623504D03*
X1428902Y1647087D03*
X1462773Y537827D03*
X1466773Y580977D03*
Y572977D03*
Y568977D03*
Y576977D03*
X1458773D03*
X1482025Y702203D03*
X1510773Y547977D03*
Y551977D03*
X1500773Y556477D03*
X1500873Y561677D03*
X1510773Y563977D03*
X1514458Y130813D03*
X1519035Y209250D03*
Y213250D03*
Y221250D03*
Y225250D03*
Y231250D03*
Y238017D03*
Y249250D03*
Y244250D03*
Y253250D03*
X1515107Y702203D03*
X1539030Y288816D03*
X1539033Y292816D03*
Y296816D03*
X1553780Y284575D03*
X1547153Y1262314D03*
X1547193Y1270188D03*
Y1274188D03*
X1558064Y1302609D03*
X1570808Y1271378D03*
X1587819Y225250D03*
Y214250D03*
Y229250D03*
Y234250D03*
Y239250D03*
Y244250D03*
X1582193Y1278988D03*
X1575221Y1275454D03*
X1582193Y1292988D03*
X1581788Y1298278D03*
X1574923Y1288958D03*
X1598815Y536344D03*
Y531226D03*
X1588693Y1278988D03*
X1610581Y538723D03*
X1610464Y554664D03*
X1610527Y559092D03*
X1622425Y290742D03*
Y294742D03*
Y298742D03*
Y302742D03*
X1622482Y566803D03*
X1629744Y1432248D03*
X1629719Y1424466D03*
Y1428366D03*
X1629744Y1436148D03*
X1629683Y1448016D03*
X1635516Y381500D03*
X1644626Y414202D03*
X1634849Y1311874D03*
X1646693Y1440488D03*
X1656664Y692328D03*
X1651863Y1370514D03*
X1661270Y1402860D03*
X1666326Y1416678D03*
X1692520Y401485D03*
X1687149Y424694D03*
X1684645Y1370614D03*
X1684824Y1696427D03*
X1694052Y1402960D03*
X1722434Y116867D03*
X1715043Y424340D03*
Y420340D03*
X1732381Y53651D03*
Y57651D03*
X1733134Y89827D03*
X1723350Y656238D03*
X1735961Y1552371D03*
X1726979Y1681465D03*
Y1676965D03*
X1740325Y89264D03*
X1743825Y85339D03*
X1751103Y364048D03*
Y368048D03*
X1751236Y377452D03*
Y382952D03*
X1739593Y668216D03*
Y664216D03*
X1760554Y68637D03*
X1761064Y87107D03*
Y83607D03*
X1764943Y368148D03*
X1764736Y372452D03*
X1764943Y364148D03*
X1764939Y1635686D03*
X1768794Y92891D03*
X1778591Y186911D03*
Y194399D03*
X1781020Y182463D03*
X1778647Y197899D03*
X1771704Y1552371D03*
X1772995Y1582405D03*
X1770495Y1577905D03*
X1767979Y1661465D03*
Y1657465D03*
X1782194Y96927D03*
X1782152Y100939D03*
X1789906Y156834D03*
Y161834D03*
X1791920Y1587105D03*
X1822096Y151834D03*
X1823172Y388051D03*
X1822815Y427432D03*
X1822808Y431678D03*
X1844807Y165834D03*
X1844777Y170287D03*
G54D11*
X27559Y87795D03*
X40708Y631889D03*
Y1368908D03*
X51180Y1714961D03*
X373622Y87795D03*
X395671Y1714960D03*
X661024Y631890D03*
X707677Y1714960D03*
X800787Y87795D03*
X931693Y757874D03*
X931692Y1072835D03*
X931693Y1387795D03*
X1045866Y87795D03*
X1155709Y1714961D03*
X1271260Y631890D03*
X1461806Y1714961D03*
X1499606Y87795D03*
X1806298Y1714961D03*
X1829921Y87795D03*
X1816772Y631889D03*
Y1368897D03*
G54D212*
X606890Y461348D03*
X617204D03*
X606890Y465088D03*
Y468828D03*
X617204D03*
Y465088D03*
G54D113*
X212224Y148760D03*
X202776D03*
X212224Y156240D03*
X202776Y152500D03*
Y156240D03*
X240708Y207651D03*
Y211391D03*
Y215131D03*
X250156Y207651D03*
Y215131D03*
X380447Y135157D03*
X370999D03*
X380447Y142637D03*
X370999Y138897D03*
Y142637D03*
X599776Y417760D03*
Y425240D03*
X609224Y417760D03*
Y425240D03*
Y421500D03*
X861416Y402450D03*
X870864D03*
X861416Y409930D03*
X870864D03*
Y406190D03*
X1002126Y428366D03*
Y420886D03*
X992678D03*
Y424626D03*
Y428366D03*
X1445372Y52933D03*
Y56673D03*
Y60413D03*
X1454820D03*
Y52933D03*
G54D122*
X260128Y109803D03*
X263671D03*
X267214D03*
X270758D03*
X693284Y113928D03*
X696827D03*
X700370D03*
X703914D03*
X1735249Y110927D03*
X1738792D03*
X1742335D03*
X1745879D03*
G54D203*
X572297Y149226D03*
Y157494D03*
X589423Y149226D03*
Y157494D03*
X842562Y168064D03*
Y176332D03*
X859688D03*
Y168064D03*
X1594537Y295328D03*
Y303596D03*
X1611663Y295328D03*
Y303596D03*
G54D320*
X1797245Y212369D03*
G54D230*
X716697Y1579704D03*
Y1576160D03*
Y1581475D03*
Y1577932D03*
Y1586790D03*
Y1588562D03*
Y1583247D03*
Y1585018D03*
X742189Y1576160D03*
Y1577932D03*
Y1581475D03*
Y1579704D03*
Y1588562D03*
Y1586790D03*
Y1583247D03*
Y1585018D03*
G54D311*
X1764399Y709079D03*
X1785659D03*
G54D131*
X268312Y594420D03*
G54D104*
X181503Y1516264D03*
Y1518626D03*
Y1520988D03*
Y1513902D03*
X179598Y1511505D03*
X181961D03*
X183548Y1517445D03*
Y1519807D03*
Y1522169D03*
X184323Y1511505D03*
X181503Y1530437D03*
Y1525713D03*
Y1532799D03*
Y1523351D03*
Y1528075D03*
X183548Y1531618D03*
Y1533980D03*
Y1536343D03*
Y1524532D03*
X181503Y1535162D03*
X179598Y1538431D03*
X181961D03*
X184323D03*
X189047Y1511505D03*
X193772D03*
X198496D03*
X186685D03*
X191409D03*
X196134D03*
X200858D03*
X189047Y1538431D03*
X193772D03*
X198496D03*
X186685D03*
X191409D03*
X196134D03*
X200858D03*
X203221Y1511505D03*
X207945D03*
X212669D03*
X215032D03*
X205583D03*
X210307D03*
X203221Y1538431D03*
X207945D03*
X212669D03*
X215032D03*
X205583D03*
X210307D03*
X217394Y1511505D03*
X222118D03*
X226843D03*
X219756D03*
X224480D03*
X229205D03*
X217394Y1538431D03*
X222118D03*
X226843D03*
X219756D03*
X224480D03*
X229205D03*
X231567Y1511505D03*
X236291D03*
X241016D03*
X245740D03*
X233929D03*
X238654D03*
X243378D03*
X231567Y1538431D03*
X236291D03*
X241016D03*
X245740D03*
X233929D03*
X238654D03*
X243378D03*
X255189Y1511505D03*
X259913D03*
X260121Y1522200D03*
X261082Y1515083D03*
X250465Y1511505D03*
X248102D03*
X252827D03*
X257551D03*
X261082Y1524532D03*
Y1526894D03*
Y1529256D03*
X255189Y1538431D03*
X259913D03*
X250465D03*
X248102D03*
X252827D03*
X257551D03*
X263128Y1516264D03*
X262276Y1511505D03*
X264638D03*
X263128Y1513902D03*
Y1518626D03*
Y1530437D03*
Y1525713D03*
Y1532799D03*
Y1528075D03*
X262276Y1538431D03*
X264638D03*
X309565Y1516264D03*
Y1518626D03*
Y1520988D03*
Y1513902D03*
X307660Y1511505D03*
X310023D03*
X311610Y1517445D03*
Y1519807D03*
Y1522169D03*
X312385Y1511505D03*
X317109D03*
X314747D03*
X319471D03*
X309565Y1530437D03*
Y1525713D03*
Y1532799D03*
Y1523351D03*
Y1528075D03*
X311610Y1531618D03*
Y1533980D03*
Y1536343D03*
Y1524532D03*
X309565Y1535162D03*
X307660Y1538431D03*
X310023D03*
X312385D03*
X317109D03*
X314747D03*
X319471D03*
X321834Y1511505D03*
X326558D03*
X331283D03*
X324196D03*
X328920D03*
X333645D03*
X321834Y1538431D03*
X326558D03*
X331283D03*
X324196D03*
X328920D03*
X333645D03*
X336007Y1511505D03*
X340731D03*
X345456D03*
X350180D03*
X343094D03*
X347818D03*
X338369D03*
X336007Y1538431D03*
X340731D03*
X345456D03*
X350180D03*
X343094D03*
X347818D03*
X338369D03*
X354905Y1511505D03*
X359629D03*
X364353D03*
X352542D03*
X357267D03*
X361991D03*
X354905Y1538431D03*
X359629D03*
X364353D03*
X352542D03*
X357267D03*
X361991D03*
X369078Y1511505D03*
X373802D03*
X378527D03*
X366716D03*
X371440D03*
X376164D03*
X369078Y1538431D03*
X373802D03*
X378527D03*
X366716D03*
X371440D03*
X376164D03*
X391190Y1516264D03*
X390338Y1511505D03*
X392700D03*
X383251D03*
X387975D03*
X388183Y1522200D03*
X389144Y1515083D03*
X391190Y1513902D03*
Y1518626D03*
X380889Y1511505D03*
X385613D03*
X391190Y1530437D03*
Y1525713D03*
Y1532799D03*
X389144Y1524532D03*
Y1526894D03*
Y1529256D03*
X391190Y1528075D03*
X390338Y1538431D03*
X392700D03*
X383251D03*
X387975D03*
X380889D03*
X385613D03*
X445676Y1516264D03*
Y1518626D03*
Y1520988D03*
Y1513902D03*
X443771Y1511505D03*
X446134D03*
X447721Y1517445D03*
Y1519807D03*
Y1522169D03*
X448496Y1511505D03*
X453220D03*
X450858D03*
X445676Y1530437D03*
Y1525713D03*
Y1532799D03*
Y1523351D03*
Y1528075D03*
X447721Y1531618D03*
Y1533980D03*
Y1536343D03*
Y1524532D03*
X445676Y1535162D03*
X443771Y1538431D03*
X446134D03*
X448496D03*
X453220D03*
X450858D03*
X457945Y1511505D03*
X462669D03*
X467394D03*
X455582D03*
X460307D03*
X465031D03*
X469756D03*
X457945Y1538431D03*
X462669D03*
X467394D03*
X455582D03*
X460307D03*
X465031D03*
X469756D03*
X472118Y1511505D03*
X476842D03*
X481567D03*
X479205D03*
X483929D03*
X474480D03*
X472118Y1538431D03*
X476842D03*
X481567D03*
X479205D03*
X483929D03*
X474480D03*
X486291Y1511505D03*
X491016D03*
X495740D03*
X488653D03*
X493378D03*
X498102D03*
X486291Y1538431D03*
X491016D03*
X495740D03*
X488653D03*
X493378D03*
X498102D03*
X500464Y1511505D03*
X505189D03*
X509913D03*
X502827D03*
X507551D03*
X512275D03*
X500464Y1538431D03*
X505189D03*
X509913D03*
X502827D03*
X507551D03*
X512275D03*
X527301Y1516264D03*
X526449Y1511505D03*
X528811D03*
X519362D03*
X524086D03*
X524294Y1522200D03*
X525255Y1515083D03*
X527301Y1513902D03*
Y1518626D03*
X514638Y1511505D03*
X517000D03*
X521724D03*
X527301Y1530437D03*
Y1525713D03*
Y1532799D03*
X525255Y1524532D03*
Y1526894D03*
Y1529256D03*
X527301Y1528075D03*
X526449Y1538431D03*
X528811D03*
X519362D03*
X524086D03*
X514638D03*
X517000D03*
X521724D03*
X573738Y1516264D03*
Y1518626D03*
Y1520988D03*
Y1513902D03*
X571833Y1511505D03*
X573738Y1530437D03*
Y1525713D03*
Y1532799D03*
Y1523351D03*
Y1528075D03*
Y1535162D03*
X571833Y1538431D03*
X574196Y1511505D03*
X575783Y1517445D03*
Y1519807D03*
Y1522169D03*
X576558Y1511505D03*
X581282D03*
X586007D03*
X578920D03*
X583644D03*
X588369D03*
X575783Y1531618D03*
Y1533980D03*
Y1536343D03*
Y1524532D03*
X574196Y1538431D03*
X576558D03*
X581282D03*
X586007D03*
X578920D03*
X583644D03*
X588369D03*
X590731Y1511505D03*
X595456D03*
X600180D03*
X593093D03*
X597818D03*
X602542D03*
X590731Y1538431D03*
X595456D03*
X600180D03*
X593093D03*
X597818D03*
X602542D03*
X604904Y1511505D03*
X609629D03*
X614353D03*
X607267D03*
X611991D03*
X616715D03*
X604904Y1538431D03*
X609629D03*
X614353D03*
X607267D03*
X611991D03*
X616715D03*
X619078Y1511505D03*
X623802D03*
X628526D03*
X633251D03*
X621440D03*
X626164D03*
X630889D03*
X619078Y1538431D03*
X623802D03*
X628526D03*
X633251D03*
X621440D03*
X626164D03*
X630889D03*
X647424Y1511505D03*
X637975D03*
X642700D03*
X635613D03*
X640337D03*
X645062D03*
X647424Y1538431D03*
X637975D03*
X642700D03*
X635613D03*
X640337D03*
X645062D03*
X655363Y1516264D03*
X654511Y1511505D03*
X656873D03*
X652148D03*
X652356Y1522200D03*
X653317Y1515083D03*
X655363Y1513902D03*
Y1518626D03*
X649786Y1511505D03*
X655363Y1530437D03*
Y1525713D03*
Y1532799D03*
X653317Y1524532D03*
Y1526894D03*
Y1529256D03*
X655363Y1528075D03*
X654511Y1538431D03*
X656873D03*
X652148D03*
X649786D03*
X1189376Y1549264D03*
Y1551626D03*
Y1546902D03*
X1187471Y1544505D03*
X1189834D03*
X1191421Y1550445D03*
X1192196Y1544505D03*
X1196920D03*
X1194558D03*
X1199282D03*
X1189376Y1553988D03*
Y1563437D03*
Y1558713D03*
Y1565799D03*
Y1556351D03*
Y1561075D03*
X1191421Y1564618D03*
Y1566980D03*
Y1552807D03*
Y1555169D03*
Y1557532D03*
X1187471Y1571431D03*
X1189834D03*
X1191421Y1569343D03*
X1192196Y1571431D03*
X1196920D03*
X1189376Y1568162D03*
X1194558Y1571431D03*
X1199282D03*
X1201645Y1544505D03*
X1206369D03*
X1211094D03*
X1204007D03*
X1208731D03*
X1213456D03*
X1201645Y1571431D03*
X1206369D03*
X1211094D03*
X1204007D03*
X1208731D03*
X1213456D03*
X1215818Y1544505D03*
X1220542D03*
X1225267D03*
X1229991D03*
X1222905D03*
X1227629D03*
X1218180D03*
X1215818Y1571431D03*
X1220542D03*
X1225267D03*
X1229991D03*
X1222905D03*
X1227629D03*
X1218180D03*
X1234716Y1544505D03*
X1239440D03*
X1244164D03*
X1232353D03*
X1237078D03*
X1241802D03*
X1234716Y1571431D03*
X1239440D03*
X1244164D03*
X1232353D03*
X1237078D03*
X1241802D03*
X1248889Y1544505D03*
X1253613D03*
X1258338D03*
X1246527D03*
X1251251D03*
X1255975D03*
X1248889Y1571431D03*
X1253613D03*
X1258338D03*
X1246527D03*
X1251251D03*
X1255975D03*
X1271001Y1549264D03*
X1270149Y1544505D03*
X1272511D03*
X1263062D03*
X1267786D03*
X1268955Y1548083D03*
X1271001Y1546902D03*
Y1551626D03*
X1260700Y1544505D03*
X1265424D03*
X1271001Y1563437D03*
Y1558713D03*
Y1565799D03*
X1267994Y1555200D03*
X1268955Y1557532D03*
Y1559894D03*
Y1562256D03*
X1271001Y1561075D03*
X1270149Y1571431D03*
X1272511D03*
X1263062D03*
X1267786D03*
X1260700D03*
X1265424D03*
X1317438Y1549264D03*
Y1551626D03*
Y1546902D03*
X1315533Y1544505D03*
X1317896D03*
X1319483Y1550445D03*
X1317438Y1553988D03*
Y1563437D03*
Y1558713D03*
Y1565799D03*
Y1556351D03*
Y1561075D03*
X1319483Y1564618D03*
Y1566980D03*
Y1552807D03*
Y1555169D03*
Y1557532D03*
X1315533Y1571431D03*
X1317896D03*
X1319483Y1569343D03*
X1317438Y1568162D03*
X1320258Y1544505D03*
X1324982D03*
X1329707D03*
X1334431D03*
X1322620D03*
X1327344D03*
X1332069D03*
X1320258Y1571431D03*
X1324982D03*
X1329707D03*
X1334431D03*
X1322620D03*
X1327344D03*
X1332069D03*
X1339156Y1544505D03*
X1343880D03*
X1348604D03*
X1336793D03*
X1341518D03*
X1346242D03*
X1339156Y1571431D03*
X1343880D03*
X1348604D03*
X1336793D03*
X1341518D03*
X1346242D03*
X1353329Y1544505D03*
X1358053D03*
X1362778D03*
X1350967D03*
X1355691D03*
X1360415D03*
X1353329Y1571431D03*
X1358053D03*
X1362778D03*
X1350967D03*
X1355691D03*
X1360415D03*
X1367502Y1544505D03*
X1372226D03*
X1376951D03*
X1365140D03*
X1369864D03*
X1374589D03*
X1367502Y1571431D03*
X1372226D03*
X1376951D03*
X1365140D03*
X1369864D03*
X1374589D03*
X1391124Y1544505D03*
X1381675D03*
X1386400D03*
X1379313D03*
X1384037D03*
X1388762D03*
X1393486D03*
X1391124Y1571431D03*
X1381675D03*
X1386400D03*
X1379313D03*
X1384037D03*
X1388762D03*
X1393486D03*
X1399063Y1549264D03*
X1398211Y1544505D03*
X1400573D03*
X1395848D03*
X1397017Y1548083D03*
X1399063Y1546902D03*
Y1551626D03*
Y1563437D03*
Y1558713D03*
Y1565799D03*
X1396056Y1555200D03*
X1397017Y1557532D03*
Y1559894D03*
Y1562256D03*
X1399063Y1561075D03*
X1398211Y1571431D03*
X1400573D03*
X1395848D03*
X1453550Y1549264D03*
Y1551626D03*
Y1546902D03*
X1451645Y1544505D03*
X1453550Y1553988D03*
Y1563437D03*
Y1558713D03*
Y1565799D03*
Y1556351D03*
Y1561075D03*
X1451645Y1571431D03*
X1453550Y1568162D03*
X1454008Y1544505D03*
X1455595Y1550445D03*
X1456370Y1544505D03*
X1461094D03*
X1465819D03*
X1458732D03*
X1463456D03*
X1468181D03*
X1455595Y1564618D03*
Y1566980D03*
Y1552807D03*
Y1555169D03*
Y1557532D03*
X1454008Y1571431D03*
X1455595Y1569343D03*
X1456370Y1571431D03*
X1461094D03*
X1465819D03*
X1458732D03*
X1463456D03*
X1468181D03*
X1470543Y1544505D03*
X1475268D03*
X1479992D03*
X1472905D03*
X1477630D03*
X1482354D03*
X1470543Y1571431D03*
X1475268D03*
X1479992D03*
X1472905D03*
X1477630D03*
X1482354D03*
X1484716Y1544505D03*
X1489441D03*
X1494165D03*
X1487079D03*
X1491803D03*
X1496527D03*
X1484716Y1571431D03*
X1489441D03*
X1494165D03*
X1487079D03*
X1491803D03*
X1496527D03*
X1498890Y1544505D03*
X1503614D03*
X1508338D03*
X1513063D03*
X1501252D03*
X1505976D03*
X1510701D03*
X1498890Y1571431D03*
X1503614D03*
X1508338D03*
X1513063D03*
X1501252D03*
X1505976D03*
X1510701D03*
X1527236Y1544505D03*
X1517787D03*
X1522512D03*
X1515425D03*
X1520149D03*
X1524874D03*
X1527236Y1571431D03*
X1517787D03*
X1522512D03*
X1515425D03*
X1520149D03*
X1524874D03*
X1535175Y1549264D03*
X1534323Y1544505D03*
X1536685D03*
X1531960D03*
X1533129Y1548083D03*
X1535175Y1546902D03*
Y1551626D03*
X1529598Y1544505D03*
X1535175Y1563437D03*
Y1558713D03*
Y1565799D03*
X1532168Y1555200D03*
X1533129Y1557532D03*
Y1559894D03*
Y1562256D03*
X1535175Y1561075D03*
X1534323Y1571431D03*
X1536685D03*
X1531960D03*
X1529598D03*
X1581612Y1549264D03*
Y1551626D03*
Y1546902D03*
X1579707Y1544505D03*
X1582070D03*
X1583657Y1550445D03*
X1584432Y1544505D03*
X1586794D03*
X1581612Y1553988D03*
Y1563437D03*
Y1558713D03*
Y1565799D03*
Y1556351D03*
Y1561075D03*
X1583657Y1564618D03*
Y1566980D03*
Y1552807D03*
Y1555169D03*
Y1557532D03*
X1579707Y1571431D03*
X1582070D03*
X1583657Y1569343D03*
X1584432Y1571431D03*
X1581612Y1568162D03*
X1586794Y1571431D03*
X1589156Y1544505D03*
X1593881D03*
X1598605D03*
X1591518D03*
X1596243D03*
X1600967D03*
X1589156Y1571431D03*
X1593881D03*
X1598605D03*
X1591518D03*
X1596243D03*
X1600967D03*
X1603330Y1544505D03*
X1608054D03*
X1612778D03*
X1617503D03*
X1615141D03*
X1605692D03*
X1610416D03*
X1603330Y1571431D03*
X1608054D03*
X1612778D03*
X1617503D03*
X1615141D03*
X1605692D03*
X1610416D03*
X1622227Y1544505D03*
X1626952D03*
X1631676D03*
X1619865D03*
X1624589D03*
X1629314D03*
X1622227Y1571431D03*
X1626952D03*
X1631676D03*
X1619865D03*
X1624589D03*
X1629314D03*
X1636400Y1544505D03*
X1641125D03*
X1645849D03*
X1634038D03*
X1638763D03*
X1643487D03*
X1636400Y1571431D03*
X1641125D03*
X1645849D03*
X1634038D03*
X1638763D03*
X1643487D03*
X1662385Y1544505D03*
X1655298D03*
X1660022D03*
X1661191Y1548083D03*
X1650574Y1544505D03*
X1648211D03*
X1652936D03*
X1657660D03*
X1660230Y1555200D03*
X1661191Y1557532D03*
Y1559894D03*
Y1562256D03*
X1662385Y1571431D03*
X1655298D03*
X1660022D03*
X1650574D03*
X1648211D03*
X1652936D03*
X1657660D03*
X1663237Y1549264D03*
X1664747Y1544505D03*
X1663237Y1546902D03*
Y1551626D03*
Y1563437D03*
Y1558713D03*
Y1565799D03*
Y1561075D03*
X1664747Y1571431D03*
G54D221*
G01X0Y54252D02*
G03X7874Y46378I7874J0D01*
G01X0Y305794D02*
Y54252D01*
G01X2306Y311361D02*
G03X0Y305794I5567J-5567D01*
G01X7874Y320191D02*
G02X5568Y314623I-7874J0D01*
G01D02*
X2306Y311361D01*
G01X7874Y46378D02*
X43709D01*
G01X7874Y1588077D02*
Y320191D01*
G01X23284Y1606749D02*
X10180Y1593645D01*
G01D02*
G03X7874Y1588077I5568J-5568D01*
G01X25591Y1612317D02*
G02X23284Y1606749I-7875J1D01*
G01X25591Y1732244D02*
Y1612317D01*
G01X765768Y1740118D02*
X33465D01*
G01D02*
G03X25591Y1732244I0J-7874D01*
G01X51583Y38504D02*
Y1969D01*
G01D02*
G03X53551Y0I1968J0D01*
G01X43709Y46378D02*
G02X51583Y38504I0J-7874D01*
G01X53551Y0D02*
X319693D01*
G01X137618Y605378D02*
G02X98248I-19685J0D01*
G01D02*
G02X137618I19685J0D01*
G01X197098Y260083D02*
G02X157728I-19685J0D01*
G01D02*
Y294335D01*
G01D02*
G02X197098I19685J0D01*
G01D02*
Y260083D01*
G01X319693Y0D02*
G03X321661Y1969I0J1969D01*
G01D02*
Y38504D01*
G01D02*
G02X329535Y46378I7874J0D01*
G01D02*
X488591D01*
G01X496465Y38504D02*
Y22756D01*
G01D02*
G03X498433Y20787I1968J-1D01*
G01D02*
X764575D01*
G01X488591Y46378D02*
G02X496465Y38504I0J-7874D01*
G01X723870Y260110D02*
G02X684500I-19685J0D01*
G01D02*
Y294362D01*
G01D02*
G02X723870I19685J0D01*
G01D02*
Y260110D01*
G01X783287Y605413D02*
G02X743917I-19685J0D01*
G01D02*
G02X783287I19685J0D01*
G01X764575Y20787D02*
G03X766543Y22756I-1J1969D01*
G01D02*
Y38504D01*
G01D02*
G02X774417Y46378I7874J0D01*
G01X769705Y1734921D02*
G02X767736Y1736890I0J1969D01*
G01D02*
Y1738150D01*
G01D02*
G03X765768Y1740118I-1968J0D01*
G01X774417Y46378D02*
X871260D01*
G01X1087854Y1734921D02*
X769705D01*
G01X871260Y46378D02*
G03X879134Y54252I0J7874D01*
G01D02*
Y134331D01*
G01D02*
G02X887008Y142205I7874J0D01*
G01D02*
X1011024D01*
G01X1018898Y134331D02*
Y54252D01*
G01D02*
G03X1026772Y46378I7874J0D01*
G01X1011024Y142205D02*
G02X1018898Y134331I0J-7874D01*
G01X1026772Y46378D02*
X1518118D01*
G01X1113760Y605378D02*
G02X1074390I-19685J0D01*
G01D02*
G02X1113760I19685J0D01*
G01X1824016Y1740118D02*
X1091791D01*
G01D02*
G03X1089823Y1738150I0J-1968D01*
G01D02*
Y1736890D01*
G01D02*
G02X1087854Y1734921I-1969J0D01*
G01X1173240Y260083D02*
G02X1133870I-19685J0D01*
G01D02*
Y294335D01*
G01D02*
G02X1173240I19685J0D01*
G01D02*
Y260083D01*
G01X1525992Y38504D02*
Y1969D01*
G01D02*
G03X1527961Y0I1969J0D01*
G01D02*
X1794102D01*
G01X1518118Y46378D02*
G02X1525992Y38504I0J-7874D01*
G01X1700012Y260110D02*
G02X1660642I-19685J0D01*
G01D02*
Y294362D01*
G01D02*
G02X1700012I19685J0D01*
G01D02*
Y260110D01*
G01X1759429Y605413D02*
G02X1720059I-19685J0D01*
G01D02*
G02X1759429I19685J0D01*
G01X1794102Y0D02*
G03X1796071Y1969I0J1969D01*
G01D02*
Y38504D01*
G01D02*
G02X1803945Y46378I7874J0D01*
G01D02*
X1849606D01*
G01X1831890Y1732244D02*
G03X1824016Y1740118I-7874J0D01*
G01X1843701Y1593983D02*
G03X1841395Y1599550I-7873J0D01*
G01D02*
X1834196Y1606749D01*
G01D02*
G02X1831890Y1612317I5568J5568D01*
G01D02*
Y1732244D01*
G01X1849606Y46378D02*
G03X1857480Y54252I0J7874D01*
G01Y305794D02*
G03X1855174Y311361I-7873J0D01*
G01D02*
X1846007Y320528D01*
G01D02*
G02X1843701Y326096I5568J5568D01*
G01D02*
Y1593983D01*
G01X1857480Y54252D02*
Y305794D01*
X706780Y432492D03*
Y429342D03*
Y426192D03*
Y423043D03*
Y419893D03*
X703630Y432492D03*
Y429342D03*
Y426192D03*
Y423043D03*
Y419893D03*
X700481Y432492D03*
Y429342D03*
Y426192D03*
Y423043D03*
Y419893D03*
X697331Y432492D03*
Y429342D03*
Y426192D03*
Y423043D03*
Y419893D03*
X706780Y448240D03*
Y445090D03*
Y441940D03*
Y438791D03*
Y435641D03*
X703630Y448240D03*
Y445090D03*
Y441940D03*
Y438791D03*
Y435641D03*
X700481Y448240D03*
Y445090D03*
Y441940D03*
Y438791D03*
Y435641D03*
X697331Y448240D03*
Y445090D03*
Y441940D03*
Y438791D03*
Y435641D03*
X706780Y463988D03*
Y460838D03*
Y457688D03*
Y454539D03*
Y451389D03*
X703630Y463988D03*
Y460838D03*
Y457688D03*
Y454539D03*
Y451389D03*
X700481Y463988D03*
Y460838D03*
Y457688D03*
Y454539D03*
Y451389D03*
X697331Y463988D03*
Y460838D03*
Y457688D03*
Y454539D03*
Y451389D03*
X706780Y476586D03*
Y473436D03*
Y470287D03*
Y467137D03*
X703630Y476586D03*
Y473436D03*
Y470287D03*
Y467137D03*
X700481Y476586D03*
Y473436D03*
Y470287D03*
Y467137D03*
X697331Y476586D03*
Y473436D03*
Y470287D03*
Y467137D03*
X706780Y486035D03*
Y482885D03*
Y479736D03*
X703630Y486035D03*
Y482885D03*
Y479736D03*
X700481Y486035D03*
Y482885D03*
Y479736D03*
X697331Y486035D03*
Y482885D03*
Y479736D03*
X722528Y432492D03*
Y429342D03*
Y426192D03*
Y423043D03*
Y419893D03*
X719378Y432492D03*
Y429342D03*
Y426192D03*
Y423043D03*
Y419893D03*
X716229Y432492D03*
Y429342D03*
Y426192D03*
Y423043D03*
Y419893D03*
X713079Y432492D03*
Y429342D03*
Y426192D03*
Y423043D03*
Y419893D03*
X709930Y432492D03*
Y429342D03*
Y426192D03*
Y423043D03*
Y419893D03*
X722528Y448240D03*
Y445090D03*
Y441940D03*
Y438791D03*
Y435641D03*
X719378Y448240D03*
Y445090D03*
Y441940D03*
Y438791D03*
Y435641D03*
X716229Y448240D03*
Y445090D03*
Y441940D03*
Y438791D03*
Y435641D03*
X713079Y448240D03*
Y445090D03*
Y441940D03*
Y438791D03*
Y435641D03*
X709930Y448240D03*
Y445090D03*
Y441940D03*
Y438791D03*
Y435641D03*
X722528Y463988D03*
Y460838D03*
Y457688D03*
Y454539D03*
Y451389D03*
X719378Y463988D03*
Y460838D03*
Y457688D03*
Y454539D03*
Y451389D03*
X716229Y463988D03*
Y460838D03*
Y457688D03*
Y454539D03*
Y451389D03*
X713079Y463988D03*
Y460838D03*
Y457688D03*
Y454539D03*
Y451389D03*
X709930Y463988D03*
Y460838D03*
Y457688D03*
Y454539D03*
Y451389D03*
X722528Y476586D03*
Y473436D03*
Y470287D03*
Y467137D03*
X719378Y476586D03*
Y473436D03*
Y470287D03*
Y467137D03*
X716229Y476586D03*
Y473436D03*
Y470287D03*
Y467137D03*
X713079Y476586D03*
Y473436D03*
Y470287D03*
Y467137D03*
X709930Y476586D03*
Y473436D03*
Y470287D03*
Y467137D03*
X722528Y486035D03*
Y482885D03*
Y479736D03*
X719378Y486035D03*
Y482885D03*
Y479736D03*
X716229Y486035D03*
Y482885D03*
Y479736D03*
X713079Y486035D03*
Y482885D03*
Y479736D03*
X709930Y486035D03*
Y482885D03*
Y479736D03*
X738276Y432492D03*
Y429342D03*
Y426192D03*
Y423043D03*
Y419893D03*
X735126Y432492D03*
Y429342D03*
Y426192D03*
Y423043D03*
Y419893D03*
X731977Y432492D03*
Y429342D03*
Y426192D03*
Y423043D03*
Y419893D03*
X728827Y432492D03*
Y429342D03*
Y426192D03*
Y423043D03*
Y419893D03*
X725678Y432492D03*
Y429342D03*
Y426192D03*
Y423043D03*
Y419893D03*
X738276Y448240D03*
Y445090D03*
Y441940D03*
Y438791D03*
Y435641D03*
X735126Y448240D03*
Y445090D03*
Y441940D03*
Y438791D03*
Y435641D03*
X731977Y448240D03*
Y445090D03*
Y441940D03*
Y438791D03*
Y435641D03*
X728827Y448240D03*
Y445090D03*
Y441940D03*
Y438791D03*
Y435641D03*
X725678Y448240D03*
Y445090D03*
Y441940D03*
Y438791D03*
Y435641D03*
X738276Y463988D03*
Y460838D03*
Y457688D03*
Y454539D03*
Y451389D03*
X735126Y463988D03*
Y460838D03*
Y457688D03*
Y454539D03*
Y451389D03*
X731977Y463988D03*
Y460838D03*
Y457688D03*
Y454539D03*
Y451389D03*
X728827Y463988D03*
Y460838D03*
Y457688D03*
Y454539D03*
Y451389D03*
X725678Y463988D03*
Y460838D03*
Y457688D03*
Y454539D03*
Y451389D03*
X738276Y476586D03*
Y473436D03*
Y470287D03*
Y467137D03*
X735126Y476586D03*
Y473436D03*
Y470287D03*
Y467137D03*
X731977Y476586D03*
Y473436D03*
Y470287D03*
Y467137D03*
X728827Y476586D03*
Y473436D03*
Y470287D03*
Y467137D03*
X725678Y476586D03*
Y473436D03*
Y470287D03*
Y467137D03*
X738276Y486035D03*
Y482885D03*
Y479736D03*
X735126Y486035D03*
Y482885D03*
Y479736D03*
X731977Y486035D03*
Y482885D03*
Y479736D03*
X728827Y486035D03*
Y482885D03*
Y479736D03*
X725678Y486035D03*
Y482885D03*
Y479736D03*
X750874Y432492D03*
Y429342D03*
Y426192D03*
Y423043D03*
Y419893D03*
X747725Y432492D03*
Y429342D03*
Y426192D03*
Y423043D03*
Y419893D03*
X744575Y432492D03*
Y429342D03*
Y426192D03*
Y423043D03*
Y419893D03*
X741426Y432492D03*
Y429342D03*
Y426192D03*
Y423043D03*
Y419893D03*
X750874Y448240D03*
Y445090D03*
Y441940D03*
Y438791D03*
Y435641D03*
X747725Y448240D03*
Y445090D03*
Y441940D03*
Y438791D03*
Y435641D03*
X744575Y448240D03*
Y445090D03*
Y441940D03*
Y438791D03*
Y435641D03*
X741426Y448240D03*
Y445090D03*
Y441940D03*
Y438791D03*
Y435641D03*
X750874Y463988D03*
Y460838D03*
Y457688D03*
Y454539D03*
Y451389D03*
X747725Y463988D03*
Y460838D03*
Y457688D03*
Y454539D03*
Y451389D03*
X744575Y463988D03*
Y460838D03*
Y457688D03*
Y454539D03*
Y451389D03*
X741426Y463988D03*
Y460838D03*
Y457688D03*
Y454539D03*
Y451389D03*
X750874Y476586D03*
Y473436D03*
Y470287D03*
Y467137D03*
X747725Y476586D03*
Y473436D03*
Y470287D03*
Y467137D03*
X744575Y476586D03*
Y473436D03*
Y470287D03*
Y467137D03*
X741426Y476586D03*
Y473436D03*
Y470287D03*
Y467137D03*
X750874Y486035D03*
Y482885D03*
Y479736D03*
X747725Y486035D03*
Y482885D03*
Y479736D03*
X744575Y486035D03*
Y482885D03*
Y479736D03*
X741426Y486035D03*
Y482885D03*
Y479736D03*
X763473Y432492D03*
Y429342D03*
Y426192D03*
Y423043D03*
Y419893D03*
X760323Y432492D03*
Y429342D03*
Y426192D03*
Y423043D03*
Y419893D03*
X757174Y432492D03*
Y429342D03*
Y426192D03*
Y423043D03*
Y419893D03*
X754024Y432492D03*
Y429342D03*
Y426192D03*
Y423043D03*
Y419893D03*
X763473Y448240D03*
Y445090D03*
Y441940D03*
Y438791D03*
Y435641D03*
X760323Y448240D03*
Y445090D03*
Y441940D03*
Y438791D03*
Y435641D03*
X757174Y448240D03*
Y445090D03*
Y441940D03*
Y438791D03*
Y435641D03*
X754024Y448240D03*
Y445090D03*
Y441940D03*
Y438791D03*
Y435641D03*
X763473Y463988D03*
Y460838D03*
Y457688D03*
Y454539D03*
Y451389D03*
X760323Y463988D03*
Y460838D03*
Y457688D03*
Y454539D03*
Y451389D03*
X757174Y463988D03*
Y460838D03*
Y457688D03*
Y454539D03*
Y451389D03*
X754024Y463988D03*
Y460838D03*
Y457688D03*
Y454539D03*
Y451389D03*
X763473Y476586D03*
Y473436D03*
Y470287D03*
Y467137D03*
X760323Y476586D03*
Y473436D03*
Y470287D03*
Y467137D03*
X757174Y476586D03*
Y473436D03*
Y470287D03*
Y467137D03*
X754024Y476586D03*
Y473436D03*
Y470287D03*
Y467137D03*
X763473Y486035D03*
Y482885D03*
Y479736D03*
X760323Y486035D03*
Y482885D03*
Y479736D03*
X757174Y486035D03*
Y482885D03*
Y479736D03*
X754024Y486035D03*
Y482885D03*
Y479736D03*
G54D140*
X280810Y1545361D03*
X295180D03*
X416921D03*
X431291D03*
X544983D03*
X559353D03*
X714349Y1423623D03*
X728719D03*
X880297Y1068533D03*
X894667D03*
X971040Y1067984D03*
X985410D03*
X1288683Y1578361D03*
X1303053D03*
X1424795D03*
X1439165D03*
X1552857D03*
X1567227D03*
X1721146Y1419712D03*
X1735516D03*
G54D302*
X1545620Y209250D03*
Y224250D03*
Y219250D03*
Y214250D03*
Y239250D03*
Y234250D03*
Y229250D03*
Y254250D03*
Y249250D03*
Y244250D03*
X1564202Y209250D03*
Y224250D03*
Y219250D03*
Y214250D03*
Y239250D03*
Y234250D03*
Y229250D03*
Y254250D03*
Y249250D03*
Y244250D03*
G54D240*
X771220Y1534963D03*
G54D21*
X21815Y516951D03*
X35968Y401000D03*
X51645Y1519335D03*
X41116Y1594396D03*
Y1607896D03*
Y1598896D03*
Y1603396D03*
Y1612896D03*
Y1617396D03*
X47410Y1668587D03*
Y1663587D03*
X48110Y1681645D03*
X60090Y423746D03*
X62110Y1682016D03*
X55110Y1681489D03*
X77234Y145191D03*
X77237Y149191D03*
Y153191D03*
X69708Y268223D03*
X76483Y1434000D03*
X82116Y1611896D03*
Y1625396D03*
Y1620896D03*
Y1616396D03*
X70116Y1630396D03*
X73650Y1634905D03*
X91984Y140950D03*
X84857Y382219D03*
Y391391D03*
Y395865D03*
X89983Y1417000D03*
Y1412500D03*
Y1408000D03*
Y1421500D03*
Y1435500D03*
X87388Y1519335D03*
X88679Y1549369D03*
X86179Y1544869D03*
X95250Y1716241D03*
X88403Y1706511D03*
X88240Y1716331D03*
X99541Y1353216D03*
X98983Y1426000D03*
Y1430500D03*
Y1440000D03*
Y1435500D03*
X107604Y1554069D03*
X106969Y1671361D03*
Y1667361D03*
Y1679564D03*
Y1675564D03*
X110483Y1712450D03*
X126336Y1661087D03*
X132141Y1353216D03*
X139903Y1701011D03*
X139801Y1705166D03*
X135750Y1718241D03*
X154683Y438810D03*
X144475Y521997D03*
Y530997D03*
Y534997D03*
X152730Y668361D03*
X143983Y1417500D03*
X147983Y1421500D03*
Y1425500D03*
X142750Y1726241D03*
Y1722241D03*
X171333Y395040D03*
X169349Y684799D03*
Y680799D03*
X164841Y1353216D03*
X158798Y1726500D03*
X177583Y416600D03*
X181463Y438270D03*
X179483Y672500D03*
Y676500D03*
X174983Y1711000D03*
Y1725000D03*
X195903Y140962D03*
X198619Y165325D03*
X197741Y1353216D03*
X200762Y1723000D03*
X201983Y1707000D03*
X225335Y144710D03*
X230541Y1353216D03*
X245203Y75862D03*
X237183Y142062D03*
X233503Y159071D03*
X235726Y715823D03*
X258883Y58400D03*
Y54400D03*
X257783Y73400D03*
X258883Y62400D03*
X260780Y87543D03*
X250280Y115743D03*
X270036Y151203D03*
Y147203D03*
X270086Y137302D03*
X272983Y211000D03*
X264983Y217500D03*
X263826Y583999D03*
X264141Y1307070D03*
X281939Y74536D03*
X278439Y78461D03*
X286783Y136962D03*
X279983Y215000D03*
X286774Y577698D03*
X283624Y574022D03*
X279909Y570398D03*
X286774Y581298D03*
X287450Y1342705D03*
X301149Y67128D03*
X305140Y91767D03*
X298910Y85983D03*
Y82483D03*
X297037Y1307042D03*
X320082Y95852D03*
X320086Y99837D03*
X317322Y227851D03*
Y231851D03*
X313483Y241000D03*
X311983Y263000D03*
X329129Y147120D03*
Y152120D03*
Y156120D03*
Y160120D03*
X329941Y1306985D03*
X346153Y229180D03*
X348640Y586415D03*
X341722Y702203D03*
X355416Y219343D03*
X356640Y582415D03*
Y578415D03*
X359040Y590415D03*
Y586415D03*
X362741Y1307185D03*
X378978Y149077D03*
X373946Y163173D03*
X377008Y235455D03*
X377038Y239615D03*
X365891Y294030D03*
X374782Y701935D03*
X384071Y287370D03*
X390640Y565915D03*
X390440Y571115D03*
X395323Y1326516D03*
X408624Y144300D03*
X405276Y157034D03*
Y152278D03*
X404483Y304000D03*
X402854Y555915D03*
Y561415D03*
X397088Y1611022D03*
Y1607022D03*
Y1603022D03*
Y1599022D03*
X408983Y1649500D03*
X422483Y54762D03*
X416184Y99148D03*
X417423Y226323D03*
Y230323D03*
Y240501D03*
X418198Y254165D03*
Y270165D03*
Y262165D03*
X418649Y1032304D03*
X422483Y1639000D03*
Y1634000D03*
X411983Y1641000D03*
X416983Y1649500D03*
Y1653500D03*
X434234Y1285694D03*
Y1289694D03*
X454282Y206620D03*
Y210620D03*
X454335Y283318D03*
X468482Y210620D03*
Y206620D03*
X468879Y222764D03*
Y235764D03*
Y243764D03*
X465639Y1013604D03*
Y1009864D03*
Y1006123D03*
Y1017344D03*
Y1024824D03*
Y1028564D03*
Y1021084D03*
Y1032304D03*
X467983Y1655500D03*
Y1672000D03*
X468483Y1701000D03*
Y1733500D03*
X483283Y288469D03*
X479288Y309809D03*
X475483Y1668000D03*
Y1659500D03*
Y1676000D03*
Y1697000D03*
Y1710500D03*
Y1733500D03*
X488866Y60105D03*
X489026Y55095D03*
X488756Y64965D03*
X492980Y167625D03*
X492165Y201516D03*
Y197516D03*
X497517Y233000D03*
Y243178D03*
X504259Y209285D03*
X500715Y197516D03*
X504259Y213285D03*
Y220166D03*
X514206Y280721D03*
X544679Y190256D03*
Y199256D03*
X541625Y292268D03*
X554319Y156667D03*
X546471Y222441D03*
Y235560D03*
X554421Y239566D03*
X546471Y226441D03*
X556156Y403586D03*
X548983Y459000D03*
X547220Y659489D03*
X570283Y297469D03*
X566288Y318809D03*
X561983Y473500D03*
X577486Y164356D03*
Y169415D03*
X581007Y257171D03*
X582943Y366827D03*
X586106Y415846D03*
Y427949D03*
X586125Y431976D03*
X574983Y454500D03*
X603252Y145640D03*
Y149640D03*
Y153640D03*
X594012Y213277D03*
X601206Y289721D03*
X596483Y445500D03*
Y449500D03*
X599981Y464349D03*
X593486Y474353D03*
X590654Y1266668D03*
Y1262668D03*
X603254Y1270598D03*
Y1278598D03*
Y1274598D03*
X605761Y157640D03*
X616265Y179720D03*
X608876Y260010D03*
X618943Y366827D03*
X618483Y418000D03*
X618374Y426901D03*
X630983Y427000D03*
X632486Y437881D03*
X633142Y461441D03*
X632892Y468856D03*
X622296Y1371182D03*
X622321Y1382864D03*
Y1378964D03*
X622296Y1375082D03*
X622260Y1390732D03*
X637592Y230975D03*
Y226975D03*
X645563Y401580D03*
X645507Y405449D03*
X645983Y433862D03*
Y437862D03*
Y442362D03*
Y453862D03*
Y449862D03*
X646107Y461853D03*
X645994Y457746D03*
X646124Y469863D03*
X645983Y488000D03*
X649204Y184862D03*
X651643Y307089D03*
X662483Y390000D03*
X649983Y418500D03*
X659483Y429862D03*
Y425862D03*
Y433862D03*
X649983Y422500D03*
X659483Y453862D03*
Y469862D03*
Y473862D03*
X649983Y519500D03*
X658705Y1363394D03*
X658737Y1367283D03*
X655683Y1687400D03*
X656283Y1708184D03*
Y1702400D03*
X667706Y363261D03*
X675483Y417862D03*
Y413362D03*
Y433862D03*
Y429862D03*
Y425862D03*
Y421862D03*
Y442362D03*
Y449862D03*
X675515Y486942D03*
X675772Y495084D03*
X668483Y533500D03*
X674083Y1312502D03*
X665483Y1712084D03*
X693703Y76962D03*
X683436Y119868D03*
X680788Y1635842D03*
Y1647842D03*
X693936Y91668D03*
X707097Y1371225D03*
X705093Y1564523D03*
X704983Y1556500D03*
X705093Y1576523D03*
Y1572523D03*
Y1568523D03*
Y1584523D03*
X704983Y1596500D03*
X705093Y1588523D03*
Y1592523D03*
X704983Y1604500D03*
X702211Y1623062D03*
X699822Y1681996D03*
X713204Y221862D03*
X716504Y1403571D03*
X720233Y1566333D03*
X732976Y86998D03*
X733486Y105468D03*
Y101968D03*
X727233Y1566333D03*
X728344Y1610743D03*
X728233Y1606733D03*
X741216Y111252D03*
X748728Y137864D03*
X751218Y161463D03*
X751483Y175500D03*
X739879Y1371325D03*
X749286Y1403671D03*
X754616Y115288D03*
X754618Y119172D03*
X757537Y228201D03*
X759749Y269322D03*
Y265322D03*
X766120Y1570633D03*
X755093Y1580023D03*
X766133Y1574733D03*
Y1578733D03*
Y1587733D03*
X777903Y163254D03*
X776010Y303410D03*
X775925Y308755D03*
X781983Y367500D03*
X779135Y415344D03*
X778135Y431344D03*
Y427344D03*
Y423344D03*
Y447344D03*
Y443344D03*
Y439344D03*
Y435344D03*
Y451344D03*
X791249Y274822D03*
X789110Y303410D03*
X789025Y308755D03*
X792483Y403000D03*
Y399000D03*
X792585Y419344D03*
X792483Y411500D03*
X792585Y431344D03*
Y427344D03*
Y423344D03*
X792635Y435344D03*
X792585Y443344D03*
X792635Y447344D03*
X808483Y392500D03*
X809518Y427344D03*
X809492Y435628D03*
X808392Y439628D03*
X809416Y459344D03*
Y455344D03*
X809483Y508000D03*
X807633Y1570633D03*
Y1578633D03*
Y1594633D03*
Y1582633D03*
Y1602633D03*
X815483Y392500D03*
X822983Y409500D03*
X823902Y427344D03*
Y431344D03*
Y443552D03*
X824029Y439279D03*
X823902Y435628D03*
Y449802D03*
Y459344D03*
X840309Y90451D03*
X842203Y129362D03*
Y135862D03*
X829983Y409500D03*
X840041Y435552D03*
Y439552D03*
Y443552D03*
Y459578D03*
Y455578D03*
Y463578D03*
X838483Y475000D03*
X851704Y135862D03*
Y129362D03*
X851483Y381000D03*
Y385000D03*
X855683Y401280D03*
X855745Y524413D03*
X849633Y1570633D03*
Y1578633D03*
Y1594633D03*
Y1582633D03*
Y1602633D03*
X868376Y223763D03*
X861075Y240441D03*
X868376Y227763D03*
X859286Y265057D03*
X859796Y283527D03*
Y280027D03*
X867526Y289311D03*
X861983Y391500D03*
X874203Y171362D03*
Y176862D03*
X884208Y192055D03*
X880926Y293347D03*
X880949Y297365D03*
X880983Y301500D03*
X880483Y326000D03*
X897106Y1137843D03*
X897513Y1149069D03*
Y1153497D03*
X902377Y1159831D03*
X891633Y1570633D03*
Y1578633D03*
Y1594633D03*
Y1582633D03*
Y1602633D03*
X909655Y582412D03*
X905434Y597449D03*
X906614Y611358D03*
X905283Y602182D03*
X909655Y625912D03*
X909531Y1161169D03*
X929507Y570703D03*
X944428Y185052D03*
Y189052D03*
X944131Y1137843D03*
X944538Y1149069D03*
Y1153497D03*
X933633Y1590233D03*
X948064Y590417D03*
X956556Y1161169D03*
X949402Y1159831D03*
X964608Y202096D03*
X968108Y198171D03*
X985407Y175483D03*
X987938Y264781D03*
Y275443D03*
X980208Y1055484D03*
X1001483Y152299D03*
X994483D03*
X997395Y217233D03*
X995867Y473675D03*
Y479175D03*
X999539Y521014D03*
Y516014D03*
Y526074D03*
Y531074D03*
X1012859Y175278D03*
Y171278D03*
X1016803Y194499D03*
X1017040Y425902D03*
X1014247Y460155D03*
Y456155D03*
Y452155D03*
Y464155D03*
Y468155D03*
Y476155D03*
Y472155D03*
Y493655D03*
Y488642D03*
Y480155D03*
X1015269Y550074D03*
Y545074D03*
X1030887Y287311D03*
Y298311D03*
X1024452Y378764D03*
Y383764D03*
Y388764D03*
X1024483Y402000D03*
X1024452Y393764D03*
X1031483Y566000D03*
X1046728Y406586D03*
X1042737Y516014D03*
Y521074D03*
Y526074D03*
Y534074D03*
X1045483Y538000D03*
X1044737Y544574D03*
Y549574D03*
X1044814Y553641D03*
X1071564Y369792D03*
X1068777Y475525D03*
X1077777Y471500D03*
Y467000D03*
X1077693Y483782D03*
Y487782D03*
X1068747Y483655D03*
Y487655D03*
X1071279Y1353197D03*
X1089994Y373187D03*
X1084718Y387226D03*
Y379226D03*
Y383226D03*
Y391226D03*
X1093421Y472105D03*
X1094597Y1687229D03*
Y1691229D03*
X1101931Y447355D03*
Y463355D03*
Y459355D03*
Y455355D03*
Y451355D03*
Y467355D03*
Y475355D03*
Y484391D03*
Y489391D03*
X1103879Y1353197D03*
X1101983Y1642500D03*
X1102547Y1696029D03*
X1111347Y1711244D03*
X1136579Y1353197D03*
X1161994Y73939D03*
X1169479Y1353197D03*
X1163258Y1454234D03*
X1181670Y61515D03*
Y57015D03*
X1181690Y52815D03*
X1172689Y442341D03*
Y447841D03*
Y464341D03*
Y453341D03*
Y458841D03*
Y469841D03*
Y481691D03*
X1188070Y99694D03*
X1195185Y177187D03*
Y173187D03*
X1191410Y432202D03*
Y448202D03*
Y440202D03*
Y460202D03*
X1191530Y470392D03*
X1191470Y465272D03*
X1188175Y574322D03*
X1190983Y1401000D03*
Y1396500D03*
Y1405500D03*
Y1410000D03*
X1199983Y1414500D03*
Y1419000D03*
Y1428500D03*
Y1433000D03*
X1190983Y1437500D03*
X1192520Y1693850D03*
X1199520D03*
X1195670Y1689850D03*
X1205495Y164987D03*
Y160987D03*
Y185187D03*
X1202595Y582443D03*
Y587443D03*
X1202279Y1353197D03*
X1207862Y1693859D03*
X1214862D03*
X1211012Y1689859D03*
X1202960Y1731803D03*
X1244676Y128239D03*
Y132739D03*
Y123739D03*
Y137239D03*
X1234176Y145239D03*
X1239937Y427255D03*
Y431255D03*
Y439255D03*
Y435255D03*
X1240270Y1307051D03*
X1242983Y1406500D03*
X1253045Y453182D03*
Y458182D03*
X1248483Y1410500D03*
Y1414500D03*
X1265682Y395125D03*
X1265685Y399125D03*
X1261930Y459182D03*
X1262000Y454372D03*
X1265983Y765000D03*
X1273166Y1307023D03*
X1263579Y1342686D03*
X1275594Y154030D03*
X1280432Y390884D03*
X1298176Y141739D03*
Y137739D03*
X1299090Y162051D03*
Y166051D03*
Y171551D03*
Y184051D03*
X1302134Y527418D03*
X1300215Y541634D03*
X1303749Y552813D03*
X1294817Y592871D03*
X1319324Y567148D03*
X1307206Y560209D03*
X1312170Y565771D03*
X1306070Y1306966D03*
X1321421Y1408282D03*
X1346279Y678393D03*
X1338870Y1307166D03*
X1371452Y1326497D03*
X1381198Y236594D03*
Y241594D03*
Y246594D03*
Y251594D03*
X1384976Y1670391D03*
X1391976Y1674391D03*
X1387528Y1700038D03*
X1391658Y1695238D03*
X1387528Y1712038D03*
Y1708038D03*
X1390087Y1728318D03*
X1394791Y1032303D03*
X1401116Y1622167D03*
X1408116Y1626167D03*
X1407798Y1646967D03*
X1410673Y1285765D03*
Y1289765D03*
X1421798Y1646967D03*
X1435165Y117664D03*
X1426780Y1609904D03*
X1435792Y1613904D03*
X1435980Y1623504D03*
X1426780Y1623366D03*
X1431869Y1647087D03*
X1441781Y1013603D03*
Y1009863D03*
Y1006122D03*
Y1017343D03*
Y1028563D03*
Y1021083D03*
Y1024823D03*
Y1032303D03*
X1465740Y537827D03*
X1461740Y576977D03*
X1469740Y580977D03*
Y572977D03*
Y568977D03*
Y576977D03*
X1484992Y702203D03*
X1513740Y547977D03*
Y551977D03*
X1503740Y556477D03*
X1503840Y561677D03*
X1513740Y563977D03*
X1517425Y130813D03*
X1522002Y209250D03*
Y213250D03*
Y221250D03*
Y225250D03*
Y231250D03*
Y238017D03*
Y249250D03*
Y244250D03*
Y253250D03*
X1518074Y702203D03*
X1541997Y288816D03*
X1542000Y292816D03*
Y296816D03*
X1556747Y284575D03*
X1550120Y1262314D03*
X1550160Y1270188D03*
Y1274188D03*
X1561031Y1302609D03*
X1585160Y1278988D03*
X1573775Y1271378D03*
X1578188Y1275454D03*
X1585160Y1292988D03*
X1584755Y1298278D03*
X1577890Y1288958D03*
X1590786Y225250D03*
Y214250D03*
Y229250D03*
Y234250D03*
Y239250D03*
Y244250D03*
X1601782Y536344D03*
Y531226D03*
X1591660Y1278988D03*
X1613548Y538723D03*
X1613431Y554664D03*
X1613494Y559092D03*
X1625392Y290742D03*
Y294742D03*
Y298742D03*
Y302742D03*
X1625449Y566803D03*
X1632711Y1432248D03*
X1632686Y1424466D03*
Y1428366D03*
X1632711Y1436148D03*
X1632650Y1448016D03*
X1638483Y381500D03*
X1647593Y414202D03*
X1637816Y1311874D03*
X1659631Y692328D03*
X1654830Y1370514D03*
X1649660Y1440488D03*
X1664237Y1402860D03*
X1669293Y1416678D03*
X1690116Y424694D03*
X1687612Y1370614D03*
X1687791Y1696427D03*
X1695487Y401485D03*
X1697019Y1402960D03*
X1718010Y424340D03*
Y420340D03*
X1735348Y53651D03*
Y57651D03*
X1736101Y89827D03*
X1725401Y116867D03*
X1726317Y656238D03*
X1729946Y1681465D03*
Y1676965D03*
X1743292Y89264D03*
X1746792Y85339D03*
X1742560Y668216D03*
Y664216D03*
X1738928Y1552371D03*
X1763521Y68637D03*
X1764031Y87107D03*
Y83607D03*
X1754070Y364048D03*
Y368048D03*
X1754203Y377452D03*
Y382952D03*
X1771761Y92891D03*
X1781558Y186911D03*
Y194399D03*
X1781614Y197899D03*
X1767910Y368148D03*
X1767703Y372452D03*
X1767910Y364148D03*
X1774671Y1552371D03*
X1775962Y1582405D03*
X1773462Y1577905D03*
X1767906Y1635686D03*
X1770946Y1661465D03*
Y1657465D03*
X1785161Y96927D03*
X1785119Y100939D03*
X1792873Y156834D03*
Y161834D03*
X1783987Y182463D03*
X1794887Y1587105D03*
X1825063Y151834D03*
X1826139Y388051D03*
X1825782Y427432D03*
X1825775Y431678D03*
X1847774Y165834D03*
X1847744Y170287D03*
G54D30*
X55374Y390301D03*
G54D114*
X220523Y594408D03*
X252019D03*
X1322165Y577505D03*
Y609001D03*
G54D12*
X20709Y139746D03*
X23563Y1590338D03*
X409259Y412106D03*
X864625Y1368522D03*
X925009Y1014595D03*
X1088663Y299646D03*
X1148239Y554216D03*
X1489957Y1403002D03*
X1568792Y178239D03*
X1704930Y1649379D03*
G54D141*
X306753Y112844D03*
Y124262D03*
X1021924Y150805D03*
Y162223D03*
X1776878Y113968D03*
Y125386D03*
G54D222*
X705660Y588934D03*
X697392D03*
Y606060D03*
X705660D03*
G54D231*
X716780Y1643326D03*
X721898D03*
X719339D03*
X714221D03*
Y1666358D03*
X716780D03*
X721898D03*
X719339D03*
X737253Y1643326D03*
X734694D03*
X732135D03*
X729576D03*
X727017D03*
X724457D03*
Y1666358D03*
X727017D03*
X729576D03*
X732135D03*
X734694D03*
X737253D03*
G54D123*
X256978Y107835D03*
Y111771D03*
X690134Y111960D03*
Y115896D03*
X993943Y194419D03*
Y196387D03*
Y198356D03*
Y200325D03*
Y202293D03*
Y204261D03*
Y206230D03*
Y208199D03*
Y210167D03*
X1004967D03*
Y208199D03*
Y206230D03*
Y204261D03*
Y202293D03*
Y200325D03*
Y198356D03*
Y196387D03*
X1732099Y108959D03*
Y112895D03*
G54D132*
X275005Y594223D03*
X273430D03*
X271855D03*
X270281D03*
X279729D03*
X278155D03*
X276580D03*
X483967Y218408D03*
X485541D03*
Y212896D03*
X512076Y209742D03*
X510501D03*
Y216828D03*
X512076D03*
X513651D03*
X576672Y222740D03*
X575098D03*
Y228252D03*
G54D105*
X180780Y1509459D03*
X183142D03*
X185504D03*
X180780Y1540477D03*
X183142D03*
X185504D03*
X187866Y1509459D03*
X192591D03*
X197315D03*
X190228D03*
X194953D03*
X199677D03*
X187866Y1540477D03*
X192591D03*
X197315D03*
X190228D03*
X194953D03*
X199677D03*
X202039Y1509459D03*
X206764D03*
X211488D03*
X216213D03*
X213850D03*
X204402D03*
X209126D03*
X202039Y1540477D03*
X206764D03*
X211488D03*
X216213D03*
X213850D03*
X204402D03*
X209126D03*
X220937Y1509459D03*
X225661D03*
X230386D03*
X218575D03*
X223299D03*
X228024D03*
X220937Y1540477D03*
X225661D03*
X230386D03*
X218575D03*
X223299D03*
X228024D03*
X235110Y1509459D03*
X239835D03*
X244559D03*
X232748D03*
X237472D03*
X242197D03*
X235110Y1540477D03*
X239835D03*
X244559D03*
X232748D03*
X237472D03*
X242197D03*
X254008Y1509459D03*
X258732D03*
X249283D03*
X246921D03*
X251646D03*
X256370D03*
X254008Y1540477D03*
X258732D03*
X249283D03*
X246921D03*
X251646D03*
X256370D03*
X263457Y1509459D03*
X265819D03*
X261095D03*
Y1540477D03*
X263457D03*
X265819D03*
X308842Y1509459D03*
X311204D03*
X315928D03*
X313566D03*
X318290D03*
X308842Y1540477D03*
X311204D03*
X315928D03*
X313566D03*
X318290D03*
X320653Y1509459D03*
X325377D03*
X330101D03*
X334826D03*
X323015D03*
X327739D03*
X332464D03*
X320653Y1540477D03*
X325377D03*
X330101D03*
X334826D03*
X323015D03*
X327739D03*
X332464D03*
X339550Y1509459D03*
X344275D03*
X348999D03*
X341912D03*
X346637D03*
X337188D03*
X339550Y1540477D03*
X344275D03*
X348999D03*
X341912D03*
X346637D03*
X337188D03*
X353723Y1509459D03*
X358448D03*
X363172D03*
X351361D03*
X356086D03*
X360810D03*
X353723Y1540477D03*
X358448D03*
X363172D03*
X351361D03*
X356086D03*
X360810D03*
X367897Y1509459D03*
X372621D03*
X377345D03*
X365534D03*
X370259D03*
X374983D03*
X379708D03*
X367897Y1540477D03*
X372621D03*
X377345D03*
X365534D03*
X370259D03*
X374983D03*
X379708D03*
X391519Y1509459D03*
X393881D03*
X382070D03*
X386794D03*
X389157D03*
X384432D03*
X389157Y1540477D03*
X391519D03*
X393881D03*
X382070D03*
X386794D03*
X384432D03*
X444953Y1509459D03*
X447315D03*
X452039D03*
X449677D03*
X454401D03*
X444953Y1540477D03*
X447315D03*
X452039D03*
X449677D03*
X454401D03*
X456764Y1509459D03*
X461488D03*
X466212D03*
X459126D03*
X463850D03*
X468575D03*
X456764Y1540477D03*
X461488D03*
X466212D03*
X459126D03*
X463850D03*
X468575D03*
X470937Y1509459D03*
X475661D03*
X480386D03*
X478023D03*
X482748D03*
X473299D03*
X470937Y1540477D03*
X475661D03*
X480386D03*
X478023D03*
X482748D03*
X473299D03*
X485110Y1509459D03*
X489834D03*
X494559D03*
X499283D03*
X487472D03*
X492197D03*
X496921D03*
X485110Y1540477D03*
X489834D03*
X494559D03*
X499283D03*
X487472D03*
X492197D03*
X496921D03*
X504008Y1509459D03*
X508732D03*
X513456D03*
X501645D03*
X506370D03*
X511094D03*
X504008Y1540477D03*
X508732D03*
X513456D03*
X501645D03*
X506370D03*
X511094D03*
X527630Y1509459D03*
X518181D03*
X522905D03*
X525268D03*
X515819D03*
X520543D03*
X525268Y1540477D03*
X527630D03*
X518181D03*
X522905D03*
X515819D03*
X520543D03*
X529992Y1509459D03*
Y1540477D03*
X573015Y1509459D03*
Y1540477D03*
X575377Y1509459D03*
X580101D03*
X584826D03*
X577739D03*
X582463D03*
X587188D03*
X575377Y1540477D03*
X580101D03*
X584826D03*
X577739D03*
X582463D03*
X587188D03*
X589550Y1509459D03*
X594274D03*
X598999D03*
X603723D03*
X591912D03*
X596637D03*
X601361D03*
X589550Y1540477D03*
X594274D03*
X598999D03*
X603723D03*
X591912D03*
X596637D03*
X601361D03*
X608448Y1509459D03*
X613172D03*
X617896D03*
X606085D03*
X610810D03*
X615534D03*
X608448Y1540477D03*
X613172D03*
X617896D03*
X606085D03*
X610810D03*
X615534D03*
X622621Y1509459D03*
X627345D03*
X632070D03*
X620259D03*
X624983D03*
X629707D03*
X622621Y1540477D03*
X627345D03*
X632070D03*
X620259D03*
X624983D03*
X629707D03*
X646243Y1509459D03*
X636794D03*
X641518D03*
X634432D03*
X639156D03*
X643881D03*
X648605D03*
X646243Y1540477D03*
X636794D03*
X641518D03*
X634432D03*
X639156D03*
X643881D03*
X648605D03*
X655692Y1509459D03*
X658054D03*
X650967D03*
X653330D03*
Y1540477D03*
X655692D03*
X658054D03*
X650967D03*
X1188653Y1542459D03*
X1191015D03*
X1195739D03*
X1193377D03*
X1198101D03*
X1188653Y1573477D03*
X1191015D03*
X1195739D03*
X1193377D03*
X1198101D03*
X1200464Y1542459D03*
X1205188D03*
X1209912D03*
X1214637D03*
X1202826D03*
X1207550D03*
X1212275D03*
X1200464Y1573477D03*
X1205188D03*
X1209912D03*
X1214637D03*
X1202826D03*
X1207550D03*
X1212275D03*
X1219361Y1542459D03*
X1224086D03*
X1228810D03*
X1221723D03*
X1226448D03*
X1216999D03*
X1219361Y1573477D03*
X1224086D03*
X1228810D03*
X1221723D03*
X1226448D03*
X1216999D03*
X1233534Y1542459D03*
X1238259D03*
X1242983D03*
X1231172D03*
X1235897D03*
X1240621D03*
X1233534Y1573477D03*
X1238259D03*
X1242983D03*
X1231172D03*
X1235897D03*
X1240621D03*
X1247708Y1542459D03*
X1252432D03*
X1257156D03*
X1245345D03*
X1250070D03*
X1254794D03*
X1259519D03*
X1247708Y1573477D03*
X1252432D03*
X1257156D03*
X1245345D03*
X1250070D03*
X1254794D03*
X1259519D03*
X1271330Y1542459D03*
X1273692D03*
X1261881D03*
X1266605D03*
X1268968D03*
X1264243D03*
X1268968Y1573477D03*
X1271330D03*
X1273692D03*
X1261881D03*
X1266605D03*
X1264243D03*
X1316715Y1542459D03*
X1319077D03*
X1316715Y1573477D03*
X1319077D03*
X1323801Y1542459D03*
X1328526D03*
X1333250D03*
X1321439D03*
X1326163D03*
X1330888D03*
X1323801Y1573477D03*
X1328526D03*
X1333250D03*
X1321439D03*
X1326163D03*
X1330888D03*
X1337974Y1542459D03*
X1342699D03*
X1347423D03*
X1335612D03*
X1340337D03*
X1345061D03*
X1337974Y1573477D03*
X1342699D03*
X1347423D03*
X1335612D03*
X1340337D03*
X1345061D03*
X1352148Y1542459D03*
X1356872D03*
X1361596D03*
X1349785D03*
X1354510D03*
X1359234D03*
X1363959D03*
X1352148Y1573477D03*
X1356872D03*
X1361596D03*
X1349785D03*
X1354510D03*
X1359234D03*
X1363959D03*
X1366321Y1542459D03*
X1371045D03*
X1375770D03*
X1368683D03*
X1373407D03*
X1378132D03*
X1366321Y1573477D03*
X1371045D03*
X1375770D03*
X1368683D03*
X1373407D03*
X1378132D03*
X1389943Y1542459D03*
X1380494D03*
X1385218D03*
X1382856D03*
X1387581D03*
X1392305D03*
X1389943Y1573477D03*
X1380494D03*
X1385218D03*
X1382856D03*
X1387581D03*
X1392305D03*
X1399392Y1542459D03*
X1401754D03*
X1394667D03*
X1397030D03*
Y1573477D03*
X1399392D03*
X1401754D03*
X1394667D03*
X1452827Y1542459D03*
Y1573477D03*
X1455189Y1542459D03*
X1459913D03*
X1464638D03*
X1457551D03*
X1462275D03*
X1467000D03*
X1455189Y1573477D03*
X1459913D03*
X1464638D03*
X1457551D03*
X1462275D03*
X1467000D03*
X1469362Y1542459D03*
X1474086D03*
X1478811D03*
X1471724D03*
X1476449D03*
X1481173D03*
X1469362Y1573477D03*
X1474086D03*
X1478811D03*
X1471724D03*
X1476449D03*
X1481173D03*
X1483535Y1542459D03*
X1488260D03*
X1492984D03*
X1497708D03*
X1485897D03*
X1490622D03*
X1495346D03*
X1483535Y1573477D03*
X1488260D03*
X1492984D03*
X1497708D03*
X1485897D03*
X1490622D03*
X1495346D03*
X1502433Y1542459D03*
X1507157D03*
X1511882D03*
X1500071D03*
X1504795D03*
X1509519D03*
X1502433Y1573477D03*
X1507157D03*
X1511882D03*
X1500071D03*
X1504795D03*
X1509519D03*
X1526055Y1542459D03*
X1516606D03*
X1521330D03*
X1514244D03*
X1518968D03*
X1523693D03*
X1526055Y1573477D03*
X1516606D03*
X1521330D03*
X1514244D03*
X1518968D03*
X1523693D03*
X1535504Y1542459D03*
X1537866D03*
X1530779D03*
X1533142D03*
X1528417D03*
X1533142Y1573477D03*
X1535504D03*
X1537866D03*
X1530779D03*
X1528417D03*
X1580889Y1542459D03*
X1583251D03*
X1585613D03*
X1580889Y1573477D03*
X1583251D03*
X1585613D03*
X1587975Y1542459D03*
X1592700D03*
X1597424D03*
X1602148D03*
X1590337D03*
X1595062D03*
X1599786D03*
X1587975Y1573477D03*
X1592700D03*
X1597424D03*
X1602148D03*
X1590337D03*
X1595062D03*
X1599786D03*
X1606873Y1542459D03*
X1611597D03*
X1616322D03*
X1613959D03*
X1604511D03*
X1609235D03*
X1606873Y1573477D03*
X1611597D03*
X1616322D03*
X1613959D03*
X1604511D03*
X1609235D03*
X1621046Y1542459D03*
X1625770D03*
X1630495D03*
X1618684D03*
X1623408D03*
X1628133D03*
X1621046Y1573477D03*
X1625770D03*
X1630495D03*
X1618684D03*
X1623408D03*
X1628133D03*
X1635219Y1542459D03*
X1639944D03*
X1644668D03*
X1632857D03*
X1637581D03*
X1642306D03*
X1647030D03*
X1635219Y1573477D03*
X1639944D03*
X1644668D03*
X1632857D03*
X1637581D03*
X1642306D03*
X1647030D03*
X1654117Y1542459D03*
X1658841D03*
X1649392D03*
X1661204D03*
X1651755D03*
X1656479D03*
X1661204Y1573477D03*
X1654117D03*
X1658841D03*
X1649392D03*
X1651755D03*
X1656479D03*
X1663566Y1542459D03*
X1665928D03*
X1663566Y1573477D03*
X1665928D03*
G54D204*
X572297Y152080D03*
Y154640D03*
X589423D03*
Y152080D03*
X842562Y170918D03*
Y173478D03*
X859688D03*
Y170918D03*
X1594537Y298182D03*
Y300742D03*
X1611663Y298182D03*
Y300742D03*
G54D312*
X1762824Y709079D03*
G54D321*
X1795796Y222241D03*
Y266533D03*
G54D150*
X326731Y653394D03*
X363731D03*
X433624Y594259D03*
X754645Y1426892D03*
X1166535Y1412479D03*
X1291146Y1375715D03*
X1320516D03*
X1415690Y601230D03*
X1487677Y640145D03*
X1524437Y640365D03*
X1701285Y198612D03*
X1700840Y1424519D03*
X1731660Y198612D03*
X1770442Y284934D03*
X1800002D03*
G54D213*
X628988Y1415094D03*
X637447Y1421755D03*
X1307050Y546690D03*
G54D303*
X1592133Y581522D03*
G54D160*
X391703Y1616822D03*
X399183D03*
X434260Y1634000D03*
X441740D03*
X666860Y1514200D03*
X674340D03*
X1674734Y1547200D03*
X1682214D03*
G54D232*
X711269Y1643326D03*
Y1666358D03*
X740205Y1643326D03*
Y1666358D03*
G54D205*
X573782Y373868D03*
X565908D03*
X573782Y378986D03*
Y376427D03*
X565908D03*
Y378986D03*
X573782Y387227D03*
Y384668D03*
X565908D03*
Y387227D03*
X573782Y389786D03*
X565908D03*
X573782Y403717D03*
Y401158D03*
Y398599D03*
X565908D03*
Y401158D03*
Y403717D03*
X601908Y373868D03*
Y384668D03*
Y387227D03*
Y376427D03*
Y378986D03*
Y389786D03*
X609782Y373868D03*
Y387227D03*
Y384668D03*
Y378986D03*
Y376427D03*
Y389786D03*
G54D250*
X789583Y1336044D03*
X791945Y1346280D03*
Y1336044D03*
X909949Y1143551D03*
X912311Y1153787D03*
X909949D03*
X956974Y1143551D03*
X959336Y1153787D03*
X956974D03*
X1319742Y549491D03*
X1322104Y559727D03*
X1319742D03*
X1625867Y549146D03*
X1628229Y559382D03*
X1625867D03*
G54D214*
X641437Y1692156D03*
X643997D03*
X646556D03*
X638878D03*
Y1709734D03*
X641437D03*
X643997D03*
X646556D03*
G54D241*
X782624Y1573554D03*
X780656D03*
Y1591172D03*
X782624D03*
X790498Y1573554D03*
X788530D03*
X786561D03*
X784593D03*
Y1591172D03*
X786561D03*
X788530D03*
X790498D03*
X826593Y1573554D03*
X824624D03*
X822656D03*
Y1591172D03*
X824624D03*
X826593D03*
X832498Y1573554D03*
X830530D03*
X828561D03*
Y1591172D03*
X830530D03*
X832498D03*
X870561Y1573554D03*
X868593D03*
X866624D03*
X864656D03*
Y1591172D03*
X866624D03*
X868593D03*
X870561D03*
X874498Y1573554D03*
X872530D03*
Y1591172D03*
X874498D03*
X916498Y1573554D03*
X914530D03*
X912561D03*
X910593D03*
X908624D03*
X906656D03*
Y1591172D03*
X908624D03*
X910593D03*
X912561D03*
X914530D03*
X916498D03*
G54D313*
X1766929Y1714960D03*
G54D151*
X347673Y130005D03*
Y126265D03*
Y122525D03*
X357319D03*
Y130005D03*
X1492797Y134562D03*
Y127082D03*
X1502443D03*
Y130822D03*
Y134562D03*
G54D22*
X20587Y528693D03*
Y537355D03*
X26887D03*
Y528693D03*
X414963Y83352D03*
Y92014D03*
X421655D03*
Y83352D03*
G54D31*
X51437Y380803D03*
X49468D03*
Y399799D03*
X51437D03*
X61280Y380803D03*
X59311D03*
X57342D03*
X55374D03*
X53406D03*
Y399799D03*
X55374D03*
X57342D03*
X59311D03*
X61280D03*
G54D40*
X50318Y1608318D03*
Y1609893D03*
Y1611468D03*
Y1613043D03*
Y1614618D03*
Y1616192D03*
Y1617767D03*
Y1619342D03*
Y1620917D03*
Y1622492D03*
X69216Y1611468D03*
Y1609893D03*
Y1608318D03*
Y1622492D03*
Y1620917D03*
Y1619342D03*
Y1617767D03*
Y1616192D03*
Y1614618D03*
Y1613043D03*
X629246Y1373044D03*
Y1366745D03*
Y1365170D03*
Y1369895D03*
Y1368320D03*
Y1371470D03*
Y1374619D03*
Y1377769D03*
Y1379344D03*
Y1376194D03*
X648144Y1366745D03*
Y1371470D03*
Y1373044D03*
Y1365170D03*
Y1368320D03*
Y1369895D03*
Y1374619D03*
Y1376194D03*
Y1379344D03*
Y1377769D03*
X1639834Y1426328D03*
Y1420029D03*
Y1418454D03*
Y1423179D03*
Y1421604D03*
Y1427903D03*
Y1424754D03*
Y1431053D03*
Y1432628D03*
Y1429478D03*
X1658732Y1420029D03*
Y1427903D03*
Y1429478D03*
Y1432628D03*
Y1431053D03*
Y1424754D03*
Y1426328D03*
Y1418454D03*
Y1421604D03*
Y1423179D03*
X1739880Y1661869D03*
Y1663444D03*
Y1665019D03*
Y1666594D03*
Y1668169D03*
Y1669743D03*
Y1671318D03*
Y1672893D03*
Y1674468D03*
Y1676043D03*
X1758778Y1671318D03*
Y1669743D03*
Y1668169D03*
Y1666594D03*
Y1665019D03*
Y1663444D03*
Y1661869D03*
Y1676043D03*
Y1674468D03*
Y1672893D03*
G54D106*
X179457Y1515083D03*
Y1517445D03*
Y1519807D03*
Y1522169D03*
Y1526894D03*
Y1531618D03*
Y1533980D03*
Y1524532D03*
Y1529256D03*
Y1536343D03*
X265173Y1517445D03*
Y1515083D03*
Y1519807D03*
Y1522169D03*
Y1526894D03*
Y1529256D03*
Y1531618D03*
Y1533980D03*
Y1536343D03*
Y1524532D03*
X307519Y1515083D03*
Y1517445D03*
Y1519807D03*
Y1522169D03*
Y1526894D03*
Y1531618D03*
Y1533980D03*
Y1524532D03*
Y1529256D03*
Y1536343D03*
X393235Y1517445D03*
Y1515083D03*
Y1519807D03*
Y1522169D03*
Y1526894D03*
Y1529256D03*
Y1531618D03*
Y1533980D03*
Y1536343D03*
Y1524532D03*
X443630Y1515083D03*
Y1517445D03*
Y1519807D03*
Y1522169D03*
Y1526894D03*
Y1531618D03*
Y1533980D03*
Y1524532D03*
Y1529256D03*
Y1536343D03*
X529346Y1517445D03*
Y1515083D03*
Y1519807D03*
Y1522169D03*
Y1526894D03*
Y1529256D03*
Y1531618D03*
Y1533980D03*
Y1536343D03*
Y1524532D03*
X571692Y1515083D03*
Y1517445D03*
Y1519807D03*
Y1522169D03*
Y1526894D03*
Y1531618D03*
Y1533980D03*
Y1524532D03*
Y1529256D03*
Y1536343D03*
X657408Y1517445D03*
Y1515083D03*
Y1519807D03*
Y1522169D03*
Y1526894D03*
Y1529256D03*
Y1531618D03*
Y1533980D03*
Y1536343D03*
Y1524532D03*
X1187330Y1548083D03*
Y1550445D03*
Y1559894D03*
Y1564618D03*
Y1552807D03*
Y1555169D03*
Y1566980D03*
Y1557532D03*
Y1562256D03*
Y1569343D03*
X1273046Y1550445D03*
Y1548083D03*
Y1552807D03*
Y1555169D03*
Y1559894D03*
Y1562256D03*
Y1564618D03*
Y1566980D03*
Y1557532D03*
Y1569343D03*
X1315392Y1548083D03*
Y1550445D03*
Y1559894D03*
Y1564618D03*
Y1552807D03*
Y1555169D03*
Y1566980D03*
Y1557532D03*
Y1562256D03*
Y1569343D03*
X1401108Y1550445D03*
Y1548083D03*
Y1552807D03*
Y1555169D03*
Y1559894D03*
Y1562256D03*
Y1564618D03*
Y1566980D03*
Y1557532D03*
Y1569343D03*
X1451504Y1548083D03*
Y1550445D03*
Y1559894D03*
Y1564618D03*
Y1552807D03*
Y1555169D03*
Y1566980D03*
Y1557532D03*
Y1562256D03*
Y1569343D03*
X1537220Y1550445D03*
Y1548083D03*
Y1552807D03*
Y1555169D03*
Y1559894D03*
Y1562256D03*
Y1564618D03*
Y1566980D03*
Y1557532D03*
Y1569343D03*
X1579566Y1548083D03*
Y1550445D03*
Y1559894D03*
Y1564618D03*
Y1552807D03*
Y1555169D03*
Y1566980D03*
Y1557532D03*
Y1562256D03*
Y1569343D03*
X1665282Y1550445D03*
Y1548083D03*
Y1552807D03*
Y1555169D03*
Y1559894D03*
Y1562256D03*
Y1564618D03*
Y1566980D03*
Y1557532D03*
Y1569343D03*
G54D304*
X1576680Y574022D03*
Y579022D03*
Y584022D03*
Y589022D03*
G54D133*
X276088Y605247D03*
G54D223*
X702806Y588934D03*
X700246D03*
Y606060D03*
X702806D03*
G54D13*
X11782Y174960D03*
X18691Y175132D03*
X33180Y301266D03*
X36524Y395255D03*
X32847Y537524D03*
X36372Y534279D03*
X50304Y61804D03*
X39008Y366396D03*
X51114D03*
X42809D03*
X48502Y507756D03*
X48626Y549744D03*
X52040Y1502281D03*
X48662Y1526319D03*
X50631Y1540155D03*
X50696Y1547353D03*
X51996Y1554426D03*
X46133Y1636380D03*
X51133D03*
X54616Y61804D03*
X63780Y301266D03*
X67681Y366396D03*
X59322D03*
X63429D03*
X56163Y416987D03*
X52902Y507569D03*
X58402D03*
X58633Y1593380D03*
X63633D03*
X56133Y1639480D03*
X61133D03*
X64427Y1649871D03*
X55427D03*
X69523Y416987D03*
X80378Y1412139D03*
X68768Y1550280D03*
X68133Y1593380D03*
X72660D03*
X81006Y1599391D03*
X77427Y1649871D03*
X78127Y1684871D03*
X70127D03*
X74127D03*
X94158Y1311085D03*
X90601Y1385773D03*
X94713Y1385821D03*
X84405Y1526319D03*
X86374Y1540655D03*
X82606Y1607691D03*
X86127Y1684871D03*
X92500Y1701934D03*
X98124Y1359700D03*
X98101Y1377021D03*
X101995Y1385652D03*
X107000Y1410484D03*
X104511Y1549980D03*
X112353Y1652071D03*
X120016Y297681D03*
Y318115D03*
X115590Y1384842D03*
X115353Y1693450D03*
X119353D03*
X130724Y1359700D03*
X130701Y1377021D03*
X134595Y1385652D03*
X141028Y1452096D03*
X137120Y1452142D03*
X133120D03*
X132353Y1652071D03*
X136353D03*
X139353Y1693571D03*
X131353D03*
X135353D03*
X132420Y1704495D03*
X144610Y427064D03*
X148190Y1384842D03*
X148000Y1417484D03*
X151000Y1445484D03*
X145028Y1452096D03*
X149028D03*
X152353Y1652071D03*
X151353Y1693571D03*
X143353D03*
X155353D03*
X163424Y1359700D03*
X163401Y1377021D03*
X167295Y1385652D03*
X158740Y1710484D03*
X183890Y393644D03*
X180890Y1384842D03*
X185760Y1710372D03*
X181760Y1728860D03*
X195979Y101126D03*
X190861Y128561D03*
X197645Y133671D03*
X196324Y1359700D03*
X196301Y1377021D03*
X200195Y1385652D03*
X189760Y1728860D03*
X208179Y101126D03*
X203061Y128561D03*
X213790Y1384842D03*
X229516Y155043D03*
X225090Y156454D03*
X229124Y1359700D03*
X229101Y1377021D03*
X243487Y107744D03*
X246297Y127027D03*
X242297D03*
X233595Y155055D03*
X244125Y666222D03*
X232995Y1385652D03*
X247487Y107744D03*
X261297Y127027D03*
X254297D03*
X250297D03*
X260100Y156946D03*
X254756Y159786D03*
X251424Y648243D03*
X246590Y1384842D03*
X271797Y127027D03*
X268297Y130527D03*
X275500Y233984D03*
X273069Y585054D03*
X272955Y666564D03*
X262724Y1313554D03*
X266595Y1339506D03*
X262701Y1330875D03*
X273597Y1522904D03*
X289357Y118987D03*
X284154Y682484D03*
X276855Y700463D03*
X280190Y1338696D03*
X279499Y1522904D03*
X302500Y253484D03*
X297815Y585938D03*
X305685Y700805D03*
X295620Y1313526D03*
X295597Y1330847D03*
X299491Y1339478D03*
X314602Y274075D03*
X316924Y702634D03*
X309655Y720323D03*
X313086Y1338668D03*
X325617Y84227D03*
X328524Y1313469D03*
X328501Y1330790D03*
X332395Y1339421D03*
X339811Y126161D03*
X346153Y273370D03*
X349984Y702366D03*
X342710Y720296D03*
X338455Y720955D03*
X345990Y1338611D03*
X352628Y286774D03*
X357582Y558274D03*
X353582D03*
X361324Y1313669D03*
X361301Y1330990D03*
X365195Y1339621D03*
X370064Y242620D03*
X371412Y275061D03*
X371962Y537151D03*
X375704Y720447D03*
X371515Y720687D03*
X378790Y1338811D03*
X395048Y126662D03*
X382184Y471835D03*
X393376Y472181D03*
X383024Y702434D03*
X393906Y1333000D03*
X393883Y1350321D03*
X384824Y1627197D03*
X394824D03*
X389824D03*
X384824Y1664604D03*
X394824D03*
X389824D03*
X406243Y105560D03*
X399264Y126628D03*
X400632Y144209D03*
X399299Y217555D03*
X402184Y471953D03*
Y504585D03*
X408739Y702578D03*
X404771Y696122D03*
X404555Y720755D03*
X397777Y1358952D03*
X401659Y1522904D03*
X407561D03*
X402969Y1625808D03*
X399824Y1664604D03*
X405000Y1680484D03*
X411299Y209604D03*
Y217555D03*
X415984Y471876D03*
Y504508D03*
X412771Y534122D03*
X416024Y684634D03*
X423921Y1009407D03*
X411372Y1358142D03*
X417000Y1667984D03*
Y1680484D03*
X433673Y80184D03*
X429997Y163609D03*
X433997Y156609D03*
X437997D03*
X439299Y217555D03*
X429784Y471799D03*
X439500Y496484D03*
X437309Y677911D03*
X437555Y702955D03*
X435141Y1009407D03*
X438882D03*
X427661D03*
X431401D03*
X427251Y1289178D03*
X441997Y163609D03*
X451299Y217555D03*
X443500Y489484D03*
X448424Y660034D03*
X441137Y677897D03*
X450102Y1009407D03*
X442622D03*
X446362D03*
X453842D03*
X453085Y1646917D03*
X466600Y145859D03*
X457997Y163609D03*
X465997D03*
X461931Y218162D03*
X458115Y244012D03*
X469038Y303622D03*
X469881Y651521D03*
X469955Y678355D03*
X457582Y1009407D03*
X461000Y1646984D03*
X475435Y209619D03*
X484754Y226436D03*
X481024Y633534D03*
X473732Y651523D03*
X483500Y1267846D03*
X478500Y1267984D03*
X474500D03*
X498314Y118402D03*
X485997Y163609D03*
X489997D03*
X494144Y218711D03*
X487107Y288213D03*
X488544Y295008D03*
X488538Y301687D03*
X487500Y1267846D03*
X492500D03*
X496500D03*
X501500Y429484D03*
X512000Y432484D03*
X501500Y422484D03*
X514324Y599434D03*
X502998Y617397D03*
X506964Y617405D03*
X502555Y651855D03*
X515539Y85626D03*
X522088Y207344D03*
X543131Y126314D03*
X536177Y246689D03*
X535855Y617755D03*
X537770Y1522904D03*
X543672D03*
X554196Y187740D03*
X556038Y312622D03*
X566460Y160553D03*
X574107Y297213D03*
X570216Y767496D03*
X582193Y86157D03*
Y93157D03*
X588194Y178034D03*
X575538Y310687D03*
X575567Y304152D03*
X579385Y379486D03*
X585585Y377536D03*
X579385Y390286D03*
Y404217D03*
X585585Y390286D03*
X575216Y767496D03*
X595260Y160553D03*
X602293Y209245D03*
X598294Y201245D03*
X602294D03*
X608793Y209245D03*
X608794Y201245D03*
X618705Y295789D03*
X615385Y379486D03*
Y390286D03*
Y409905D03*
X625310Y178593D03*
X626705Y295789D03*
X622705D03*
X621585Y377536D03*
Y390286D03*
X619500Y441984D03*
X626703Y1353168D03*
X630000Y1404484D03*
X635060Y146127D03*
X646231Y153035D03*
X638000Y425484D03*
X642500Y421984D03*
X643563Y1389881D03*
X647445Y1389905D03*
X635000Y1404484D03*
X637794Y1721454D03*
X653821Y87246D03*
X649500Y379484D03*
X655702Y1388407D03*
X659559Y1388349D03*
X651877Y1388374D03*
X652800Y1694284D03*
X656800D03*
X675843Y107169D03*
X666885Y408239D03*
X665832Y1530484D03*
X673113Y1722083D03*
Y1732745D03*
X680623Y111869D03*
X687453Y131152D03*
X683453D03*
X689440Y366388D03*
X690800Y379846D03*
X687500Y396346D03*
X679500Y523984D03*
X687310Y510846D03*
X692500D03*
X688500Y543346D03*
X688120Y1519510D03*
X704953Y131152D03*
X694453D03*
X700963Y131212D03*
X707545Y366305D03*
X703520Y366388D03*
X708300Y379846D03*
X704300D03*
X700300D03*
X707500Y396346D03*
X699500D03*
X695500D03*
X703500D03*
X700500Y510846D03*
X696500D03*
Y527346D03*
X700500Y543346D03*
X704500Y553346D03*
X704056Y580565D03*
X698996D03*
X708056D03*
X694996D03*
X698699Y1348854D03*
X705680Y1377709D03*
X705657Y1395030D03*
X701661Y1395052D03*
X697731Y1395022D03*
X698500Y1593984D03*
X696030Y1630761D03*
X699799Y1630677D03*
X723500Y366346D03*
X715395Y366336D03*
X712300Y379846D03*
X720300D03*
X715500Y396346D03*
X711500D03*
X720500Y553346D03*
Y543346D03*
X720787Y633815D03*
X716721Y633751D03*
X711702Y652240D03*
X709551Y1403661D03*
X723146Y1402661D03*
X710217Y1438722D03*
X723050Y1602417D03*
X717110Y1602507D03*
X715152Y1630565D03*
X729380Y78002D03*
X734380D03*
X723933Y138472D03*
X731500Y366346D03*
X727564Y379846D03*
X735500Y396346D03*
X732500Y510846D03*
X728500D03*
X736500D03*
X728500Y543346D03*
X736500D03*
X732500Y543484D03*
X738462Y1377809D03*
X738439Y1395130D03*
X732723Y1630004D03*
X736723D03*
X728723D03*
X737468Y1690187D03*
X732434Y1688157D03*
X728454Y1687988D03*
X745500Y202484D03*
X747500Y379846D03*
X743500Y396346D03*
X747500D03*
X751500D03*
X739652Y396328D03*
X744500Y510846D03*
X752500D03*
X748500D03*
X740895Y527365D03*
X748500Y527346D03*
X752500D03*
X744500D03*
X752500Y543346D03*
X742333Y1403761D03*
X740723Y1630004D03*
X741326Y1686796D03*
X752187Y1688478D03*
X760193Y103712D03*
X761000Y215484D03*
X759500Y379846D03*
Y396346D03*
X755500D03*
X764500Y510846D03*
X756500D03*
X760500D03*
X756500Y527346D03*
X760500D03*
X764500D03*
X765000Y543346D03*
X755928Y1402761D03*
X757770Y1631267D03*
X761770D03*
X754030Y1659067D03*
Y1666067D03*
X762030D03*
X767368Y1665546D03*
X767381Y1673225D03*
X773766Y284306D03*
X781456Y381101D03*
X775500Y396346D03*
X771500D03*
X773000Y543346D03*
X768700Y543484D03*
X779447Y1337240D03*
X770450Y1584017D03*
X789277Y1527313D03*
X809817Y564921D03*
X807669Y1304700D03*
X812750Y1584917D03*
X819114Y120682D03*
X823114D03*
X827114D03*
X826614Y150182D03*
X824500Y511484D03*
X820500D03*
X831114Y120682D03*
X839360Y120566D03*
X840221Y187846D03*
X840220Y200846D03*
X839000Y388984D03*
X841872Y538169D03*
X844936Y93235D03*
X844221Y187846D03*
X844220Y200846D03*
X848500Y457984D03*
X852000Y488984D03*
X848762Y527472D03*
X854750Y1584917D03*
X871500Y319484D03*
X867190Y387744D03*
X871190D03*
X864065Y519020D03*
X886503Y281771D03*
X876923Y1245404D03*
X889368Y1144562D03*
X893368D03*
X895394Y1162815D03*
X896750Y1584917D03*
X916268Y275343D03*
X945263Y277640D03*
X936393Y1144562D03*
X940393D03*
X942419Y1162815D03*
X935907Y1245404D03*
X965442Y174869D03*
X981445Y182567D03*
X977195Y210907D03*
X1005699Y174327D03*
X999915Y182057D03*
X996415D03*
X1005395Y221407D03*
X1009735Y160927D03*
X1014828Y264749D03*
Y273911D03*
X1015334Y294295D03*
X1007011Y544983D03*
X1019961Y560416D03*
X1023220Y189083D03*
X1024961Y560416D03*
X1039000Y560484D03*
X1064915Y1310972D03*
X1066363Y1385534D03*
X1062405Y1385502D03*
X1063751Y1650978D03*
X1064221Y1659904D03*
X1069322Y404032D03*
X1069862Y1359681D03*
X1073733Y1385633D03*
X1069839Y1377002D03*
X1068094Y1650979D03*
X1068221Y1659904D03*
X1087328Y1384823D03*
X1094514Y1725900D03*
X1102462Y1359681D03*
X1102439Y1377002D03*
X1106333Y1385633D03*
X1108747Y1531864D03*
X1109558Y1547570D03*
X1105000Y1679484D03*
X1098514Y1718900D03*
X1119928Y1384823D03*
X1114617Y1531864D03*
X1115005Y1582535D03*
X1116000Y1668484D03*
X1120303Y1679419D03*
X1119361Y1719218D03*
X1135162Y1359681D03*
X1135139Y1377002D03*
X1139033Y1385633D03*
X1129846Y1459432D03*
X1131256Y1572011D03*
X1140117Y1668636D03*
X1152628Y1384823D03*
X1144107Y1668550D03*
X1168062Y1359681D03*
X1168039Y1377002D03*
X1178340Y472649D03*
X1180849Y464674D03*
X1171933Y1385633D03*
X1185528Y1384823D03*
X1195488Y91034D03*
X1215581Y88830D03*
X1200862Y1359681D03*
X1200839Y1377002D03*
X1204733Y1385633D03*
X1208000Y1396984D03*
X1210254Y1709920D03*
Y1730920D03*
Y1716920D03*
Y1723920D03*
X1206254Y1727770D03*
X1223455Y88830D03*
X1218328Y1384823D03*
X1238853Y1313535D03*
X1242724Y1339487D03*
X1238830Y1330856D03*
X1245000Y1429984D03*
Y1436984D03*
Y1443984D03*
X1241000D03*
X1253152Y90379D03*
Y101009D03*
X1256319Y1338677D03*
X1247000Y1406484D03*
X1256859Y1422984D03*
X1249000Y1429984D03*
Y1436984D03*
X1253000D03*
X1263472Y90348D03*
X1271749Y1313507D03*
X1271726Y1330828D03*
X1275620Y1339459D03*
X1289215Y1338649D03*
X1281470Y1555904D03*
X1287372D03*
X1296386Y548307D03*
X1299986D03*
X1296156Y558932D03*
X1304653Y1313450D03*
X1304630Y1330771D03*
X1307857Y108837D03*
X1305187Y568755D03*
X1308524Y1339402D03*
X1331930Y64429D03*
X1322119Y1338592D03*
X1343840Y64395D03*
X1337453Y1313650D03*
X1337430Y1330971D03*
X1341324Y1339602D03*
X1355750Y64395D03*
X1361976Y617577D03*
X1350261Y635565D03*
X1354597D03*
X1354919Y1338792D03*
X1367950Y64395D03*
X1370035Y1332981D03*
X1373906Y1358933D03*
X1370012Y1350302D03*
X1383507Y635898D03*
X1387297Y668465D03*
X1387501Y1358123D03*
X1394676Y650477D03*
X1407543Y1009406D03*
X1403803D03*
X1400063D03*
X1416207Y668798D03*
X1420007Y700715D03*
X1415024Y1009406D03*
X1411283D03*
X1418764D03*
X1422504D03*
X1417711Y1261850D03*
X1421211D03*
X1409532Y1555904D03*
X1415434D03*
X1415622Y1613251D03*
X1410622D03*
X1413622Y1640826D03*
X1434262Y58376D03*
X1439049Y112927D03*
X1429169Y112797D03*
X1427276Y683057D03*
X1433724Y1009406D03*
X1429984D03*
X1426244D03*
X1438532Y1278244D03*
X1448549Y120127D03*
X1443049Y112927D03*
X1448807Y701378D03*
X1452765Y720391D03*
X1449334Y1274976D03*
X1453334D03*
X1442532Y1278244D03*
X1450500Y1620484D03*
Y1629984D03*
X1445500D03*
X1440500D03*
X1442579Y1670787D03*
X1447579D03*
X1452579D03*
X1459896Y61472D03*
X1454549Y112927D03*
X1460194Y702634D03*
X1457579Y1670787D03*
X1481725Y720955D03*
X1493276Y702634D03*
X1485897Y720622D03*
X1513644Y249409D03*
X1505477Y1273872D03*
X1526076Y702634D03*
X1518697Y720622D03*
X1514807Y720955D03*
X1533454Y91205D03*
X1537454D03*
X1542697Y565071D03*
X1547827Y698514D03*
X1551827D03*
X1547607Y720955D03*
X1556178Y1265847D03*
X1558077Y1276272D03*
X1554377D03*
X1545644Y1555904D03*
X1551546D03*
X1559206Y680694D03*
X1560157Y1265847D03*
X1584597Y664913D03*
X1580597D03*
X1580737Y699015D03*
X1583177Y1265272D03*
X1587177D03*
X1575680Y1302963D03*
X1588800Y306655D03*
X1591976Y646925D03*
X1591177Y1265272D03*
X1617400Y306655D03*
X1617506Y567910D03*
X1617597Y645913D03*
X1613597D03*
X1613507Y665246D03*
X1629000Y388984D03*
Y395984D03*
X1624976Y627925D03*
X1646510Y431528D03*
X1646507Y646246D03*
X1645155Y1394304D03*
X1634327Y1409424D03*
X1662000Y220984D03*
X1651910Y232971D03*
X1652610Y400186D03*
X1661110Y431686D03*
X1653413Y1376998D03*
X1657284Y1402950D03*
X1653390Y1394319D03*
X1649197Y1394252D03*
X1653667Y1443225D03*
X1658167D03*
X1662465Y1441658D03*
X1657892Y1455344D03*
X1653614Y1455323D03*
X1650513Y1711668D03*
Y1726818D03*
Y1718668D03*
Y1733818D03*
X1673872Y431129D03*
X1670879Y1401950D03*
X1666290Y1441691D03*
X1670147Y1441633D03*
X1673706Y1563484D03*
X1675360Y1711986D03*
Y1726736D03*
X1684942Y231396D03*
X1686154Y431669D03*
X1686195Y1377098D03*
X1690066Y1403050D03*
X1686172Y1394419D03*
X1688243Y1669286D03*
X1692415Y1669224D03*
X1679816Y1669287D03*
X1685513Y1711668D03*
Y1718668D03*
X1704624Y431159D03*
X1701124D03*
X1703661Y1402050D03*
X1718608Y104068D03*
X1721418Y128151D03*
X1717418D03*
X1713312Y141206D03*
X1715044Y410029D03*
X1718931Y410021D03*
X1710408Y423429D03*
X1720845Y1676818D03*
X1710360Y1711986D03*
X1722608Y108868D03*
X1736418Y128151D03*
X1729418D03*
X1725418D03*
X1730364Y174435D03*
X1722500Y371846D03*
X1725500Y380846D03*
X1735945Y1559355D03*
X1728633Y1708174D03*
X1724633Y1715174D03*
Y1708174D03*
Y1723324D03*
Y1730324D03*
X1746918Y128151D03*
X1743418Y131651D03*
X1740688Y1534088D03*
X1737914Y1573191D03*
X1737979Y1580389D03*
X1739279Y1587462D03*
X1750380Y1713292D03*
X1749480Y1723642D03*
X1764478Y120111D03*
X1756051Y1583316D03*
X1758963Y1688949D03*
X1763463D03*
X1771688Y1559355D03*
X1773657Y1573691D03*
X1790738Y85351D03*
X1784133Y165883D03*
Y158794D03*
X1783448Y210441D03*
X1791794Y1583016D03*
X1819705Y166856D03*
G54D124*
X258455Y669601D03*
X291185Y703842D03*
X323955Y723992D03*
X357015Y723724D03*
X390055Y723792D03*
X423055Y705992D03*
X455455Y681392D03*
X488055Y654892D03*
X521355Y620792D03*
X1369007Y638935D03*
X1401707Y671835D03*
X1434307Y704415D03*
X1467225Y723992D03*
X1500307Y724160D03*
X1533107Y723992D03*
X1566237Y702052D03*
X1599007Y668283D03*
X1632007Y649283D03*
G54D142*
X304992Y880671D03*
Y887049D03*
Y893427D03*
Y899805D03*
Y906182D03*
Y912560D03*
Y918938D03*
Y925316D03*
Y931694D03*
Y938072D03*
Y944450D03*
Y950828D03*
Y957206D03*
Y963584D03*
Y969962D03*
Y976340D03*
Y982718D03*
Y989096D03*
Y995474D03*
Y1001852D03*
Y1008230D03*
X319795Y874293D03*
X316094D03*
X312393D03*
X317944Y877482D03*
X314244D03*
X310543D03*
X319795Y880671D03*
X316094D03*
X312393D03*
X308693D03*
X317944Y883860D03*
X314244D03*
X310543D03*
X306842D03*
X319795Y887049D03*
X316094D03*
X312393D03*
X308693D03*
X317944Y890238D03*
X314244D03*
X310543D03*
X306842D03*
X319795Y893427D03*
X316094D03*
X312393D03*
X308693D03*
X317944Y896616D03*
X314244D03*
X310543D03*
X306842D03*
X319795Y899805D03*
X316094D03*
X312393D03*
X308693D03*
X317944Y902994D03*
X314244D03*
X310543D03*
X306842D03*
X319795Y906182D03*
X316094D03*
X312393D03*
X308693D03*
X317944Y909371D03*
X314244D03*
X310543D03*
X306842D03*
X319795Y912560D03*
X316094D03*
X312393D03*
X308693D03*
X317944Y915749D03*
X314244D03*
X310543D03*
X306842D03*
X319795Y918938D03*
X316094D03*
X312393D03*
X308693D03*
X317944Y922127D03*
X314244D03*
X310543D03*
X306842D03*
X319795Y925316D03*
X316094D03*
X312393D03*
X308693D03*
X317944Y928505D03*
X314244D03*
X310543D03*
X306842D03*
X319795Y931694D03*
X316094D03*
X312393D03*
X308693D03*
X317944Y934883D03*
X314244D03*
X310543D03*
X306842D03*
X319795Y938072D03*
X316094D03*
X312393D03*
X308693D03*
X317944Y941261D03*
X314244D03*
X310543D03*
X306842D03*
X319795Y944450D03*
X316094D03*
X312393D03*
X308693D03*
X317944Y947639D03*
X314244D03*
X310543D03*
X306842D03*
X319795Y950828D03*
X316094D03*
X312393D03*
X308693D03*
X317944Y954017D03*
X314244D03*
X310543D03*
X306842D03*
X319795Y957206D03*
X316094D03*
X312393D03*
X308693D03*
X317944Y960395D03*
X314244D03*
X310543D03*
X306842D03*
X319795Y963584D03*
X316094D03*
X312393D03*
X308693D03*
X317944Y966773D03*
X314244D03*
X310543D03*
X306842D03*
X319795Y969962D03*
X316094D03*
X312393D03*
X308693D03*
X317944Y973151D03*
X314244D03*
X310543D03*
X306842D03*
X319795Y976340D03*
X316094D03*
X312393D03*
X308693D03*
X317944Y979529D03*
X314244D03*
X310543D03*
X306842D03*
X319795Y982718D03*
X316094D03*
X312393D03*
X308693D03*
X317944Y985907D03*
X314244D03*
X310543D03*
X306842D03*
X319795Y989096D03*
X316094D03*
X312393D03*
X308693D03*
X317944Y992285D03*
X314244D03*
X310543D03*
X306842D03*
X319795Y995474D03*
X316094D03*
X312393D03*
X308693D03*
X317944Y998663D03*
X314244D03*
X310543D03*
X306842D03*
X319795Y1001852D03*
X316094D03*
X312393D03*
X308693D03*
X317944Y1005041D03*
X314244D03*
X310543D03*
X306842D03*
X319795Y1008230D03*
X316094D03*
X312393D03*
X308693D03*
X317944Y1011419D03*
X314244D03*
X310543D03*
X306842D03*
X319126Y1027009D03*
X315425D03*
X311724D03*
X308023D03*
X320976Y1030198D03*
X317275D03*
X313574D03*
X309874D03*
X306173D03*
X319126Y1033387D03*
X315425D03*
X311724D03*
X308023D03*
X320976Y1036576D03*
X317275D03*
X313574D03*
X309874D03*
X306173D03*
X319126Y1039765D03*
X315425D03*
X311724D03*
X308023D03*
X320976Y1042954D03*
X317275D03*
X313574D03*
X309874D03*
X306173D03*
X319126Y1046143D03*
X315425D03*
X311724D03*
X308023D03*
X320976Y1049332D03*
X317275D03*
X313574D03*
X309874D03*
X306173D03*
X319126Y1052521D03*
X315425D03*
X311724D03*
X308023D03*
X320976Y1055710D03*
X317275D03*
X313574D03*
X309874D03*
X306173D03*
X319126Y1058899D03*
X315425D03*
X311724D03*
X308023D03*
X320976Y1062088D03*
X317275D03*
X313574D03*
X309874D03*
X306173D03*
X319126Y1065277D03*
X315425D03*
X311724D03*
X308023D03*
X320976Y1068466D03*
X317275D03*
X313574D03*
X309874D03*
X306173D03*
X319126Y1071655D03*
X315425D03*
X311724D03*
X308023D03*
X320976Y1074844D03*
X317275D03*
X313574D03*
X309874D03*
X306173D03*
X319126Y1078033D03*
X315425D03*
X311724D03*
X308023D03*
X320976Y1081222D03*
X317275D03*
X313574D03*
X309874D03*
X306173D03*
X319126Y1084411D03*
X315425D03*
X311724D03*
X308023D03*
X320976Y1087600D03*
X317275D03*
X313574D03*
X309874D03*
X306173D03*
X319126Y1090789D03*
X315425D03*
X311724D03*
X308023D03*
X320976Y1093978D03*
X317275D03*
X313574D03*
X309874D03*
X306173D03*
X319126Y1097167D03*
X315425D03*
X311724D03*
X308023D03*
X320976Y1100356D03*
X317275D03*
X313574D03*
X309874D03*
X306173D03*
X319126Y1103545D03*
X315425D03*
X311724D03*
X308023D03*
X320976Y1106734D03*
X317275D03*
X313574D03*
X309874D03*
X306173D03*
X319126Y1109923D03*
X315425D03*
X311724D03*
X308023D03*
X320976Y1113112D03*
X317275D03*
X313574D03*
X309874D03*
X306173D03*
X319126Y1116301D03*
X315425D03*
X311724D03*
X308023D03*
X320976Y1119490D03*
X317275D03*
X313574D03*
X309874D03*
X306173D03*
X319126Y1122679D03*
X315425D03*
X311724D03*
X308023D03*
X320976Y1125868D03*
X317275D03*
X313574D03*
X309874D03*
X306173D03*
X319126Y1129057D03*
X315425D03*
X311724D03*
X308023D03*
X320976Y1132246D03*
X317275D03*
X313574D03*
X309874D03*
X306173D03*
X319126Y1135434D03*
X315425D03*
X311724D03*
X308023D03*
X320976Y1138623D03*
X317275D03*
X313574D03*
X309874D03*
X306173D03*
X319126Y1141812D03*
X315425D03*
X311724D03*
X308023D03*
X320976Y1145001D03*
X317275D03*
X313574D03*
X309874D03*
X306173D03*
X319126Y1148190D03*
X315425D03*
X311724D03*
X308023D03*
X320976Y1151379D03*
X317275D03*
X313574D03*
X309874D03*
X306173D03*
X319126Y1154568D03*
X315425D03*
X311724D03*
X308023D03*
X320976Y1157757D03*
X317275D03*
X313574D03*
X309874D03*
X306173D03*
X319126Y1160946D03*
X315425D03*
X311724D03*
X320976Y1164135D03*
X317275D03*
X313574D03*
X334598Y874293D03*
X330897D03*
X327196D03*
X332748Y877482D03*
X329047D03*
X325346D03*
X321645D03*
X334598Y880671D03*
X330897D03*
X327196D03*
X323496D03*
X332748Y883860D03*
X329047D03*
X325346D03*
X321645D03*
X334598Y887049D03*
X330897D03*
X327196D03*
X323496D03*
X332748Y890238D03*
X329047D03*
X325346D03*
X321645D03*
X334598Y893427D03*
X330897D03*
X327196D03*
X323496D03*
X332748Y896616D03*
X329047D03*
X325346D03*
X321645D03*
X334598Y899805D03*
X330897D03*
X327196D03*
X323496D03*
X332748Y902994D03*
X329047D03*
X325346D03*
X321645D03*
X334598Y906182D03*
X330897D03*
X327196D03*
X323496D03*
X332748Y909371D03*
X329047D03*
X325346D03*
X321645D03*
X334598Y912560D03*
X330897D03*
X327196D03*
X323496D03*
X332748Y915749D03*
X329047D03*
X325346D03*
X321645D03*
X334598Y918938D03*
X330897D03*
X327196D03*
X323496D03*
X332748Y922127D03*
X329047D03*
X325346D03*
X321645D03*
X334598Y925316D03*
X330897D03*
X327196D03*
X323496D03*
X332748Y928505D03*
X329047D03*
X325346D03*
X321645D03*
X334598Y931694D03*
X330897D03*
X327196D03*
X323496D03*
X332748Y934883D03*
X329047D03*
X325346D03*
X321645D03*
X334598Y938072D03*
X330897D03*
X327196D03*
X323496D03*
X332748Y941261D03*
X329047D03*
X325346D03*
X321645D03*
X334598Y944450D03*
X330897D03*
X327196D03*
X323496D03*
X332748Y947639D03*
X329047D03*
X325346D03*
X321645D03*
X334598Y950828D03*
X330897D03*
X327196D03*
X323496D03*
X332748Y954017D03*
X329047D03*
X325346D03*
X321645D03*
X334598Y957206D03*
X330897D03*
X327196D03*
X323496D03*
X332748Y960395D03*
X329047D03*
X325346D03*
X321645D03*
X334598Y963584D03*
X330897D03*
X327196D03*
X323496D03*
X332748Y966773D03*
X329047D03*
X325346D03*
X321645D03*
X334598Y969962D03*
X330897D03*
X327196D03*
X323496D03*
X332748Y973151D03*
X329047D03*
X325346D03*
X321645D03*
X334598Y976340D03*
X330897D03*
X327196D03*
X323496D03*
X332748Y979529D03*
X329047D03*
X325346D03*
X321645D03*
X334598Y982718D03*
X330897D03*
X327196D03*
X323496D03*
X332748Y985907D03*
X329047D03*
X325346D03*
X321645D03*
X334598Y989096D03*
X330897D03*
X327196D03*
X323496D03*
X332748Y992285D03*
X329047D03*
X325346D03*
X321645D03*
X334598Y995474D03*
X330897D03*
X327196D03*
X323496D03*
X332748Y998663D03*
X329047D03*
X325346D03*
X321645D03*
X334598Y1001852D03*
X330897D03*
X327196D03*
X323496D03*
X332748Y1005041D03*
X329047D03*
X325346D03*
X321645D03*
X334598Y1008230D03*
X330897D03*
X327196D03*
X323496D03*
X332748Y1011419D03*
X329047D03*
X325346D03*
X321645D03*
X333929Y1027009D03*
X330228D03*
X326527D03*
X322826D03*
X335779Y1030198D03*
X332078D03*
X328378D03*
X324677D03*
X333929Y1033387D03*
X330228D03*
X326527D03*
X322826D03*
X335779Y1036576D03*
X332078D03*
X328378D03*
X324677D03*
X333929Y1039765D03*
X330228D03*
X326527D03*
X322826D03*
X335779Y1042954D03*
X332078D03*
X328378D03*
X324677D03*
X333929Y1046143D03*
X330228D03*
X326527D03*
X322826D03*
X335779Y1049332D03*
X332078D03*
X328378D03*
X324677D03*
X333929Y1052521D03*
X330228D03*
X326527D03*
X322826D03*
X335779Y1055710D03*
X332078D03*
X328378D03*
X324677D03*
X333929Y1058899D03*
X330228D03*
X326527D03*
X322826D03*
X335779Y1062088D03*
X332078D03*
X328378D03*
X324677D03*
X333929Y1065277D03*
X330228D03*
X326527D03*
X322826D03*
X335779Y1068466D03*
X332078D03*
X328378D03*
X324677D03*
X333929Y1071655D03*
X330228D03*
X326527D03*
X322826D03*
X335779Y1074844D03*
X332078D03*
X328378D03*
X324677D03*
X333929Y1078033D03*
X330228D03*
X326527D03*
X322826D03*
X335779Y1081222D03*
X332078D03*
X328378D03*
X324677D03*
X333929Y1084411D03*
X330228D03*
X326527D03*
X322826D03*
X335779Y1087600D03*
X332078D03*
X328378D03*
X324677D03*
X333929Y1090789D03*
X330228D03*
X326527D03*
X322826D03*
X335779Y1093978D03*
X332078D03*
X328378D03*
X324677D03*
X333929Y1097167D03*
X330228D03*
X326527D03*
X322826D03*
X335779Y1100356D03*
X332078D03*
X328378D03*
X324677D03*
X333929Y1103545D03*
X330228D03*
X326527D03*
X322826D03*
X335779Y1106734D03*
X332078D03*
X328378D03*
X324677D03*
X333929Y1109923D03*
X330228D03*
X326527D03*
X322826D03*
X335779Y1113112D03*
X332078D03*
X328378D03*
X324677D03*
X333929Y1116301D03*
X330228D03*
X326527D03*
X322826D03*
X335779Y1119490D03*
X332078D03*
X328378D03*
X324677D03*
X333929Y1122679D03*
X330228D03*
X326527D03*
X322826D03*
X335779Y1125868D03*
X332078D03*
X328378D03*
X324677D03*
X333929Y1129057D03*
X330228D03*
X326527D03*
X322826D03*
X335779Y1132246D03*
X332078D03*
X328378D03*
X324677D03*
X333929Y1135434D03*
X330228D03*
X326527D03*
X322826D03*
X335779Y1138623D03*
X332078D03*
X328378D03*
X324677D03*
X333929Y1141812D03*
X330228D03*
X326527D03*
X322826D03*
X335779Y1145001D03*
X332078D03*
X328378D03*
X324677D03*
X333929Y1148190D03*
X330228D03*
X326527D03*
X322826D03*
X335779Y1151379D03*
X332078D03*
X328378D03*
X324677D03*
X333929Y1154568D03*
X330228D03*
X326527D03*
X322826D03*
X335779Y1157757D03*
X332078D03*
X328378D03*
X324677D03*
X333929Y1160946D03*
X330228D03*
X326527D03*
X322826D03*
X335779Y1164135D03*
X332078D03*
X328378D03*
X349401Y874293D03*
X342000D03*
X338299D03*
X347551Y877482D03*
X343850D03*
X340149D03*
X336448D03*
X349401Y880671D03*
X345700D03*
X342000D03*
X338299D03*
X347551Y883860D03*
X343850D03*
X340149D03*
X336448D03*
X349401Y887049D03*
X345700D03*
X342000D03*
X338299D03*
X347551Y890238D03*
X343850D03*
X340149D03*
X336448D03*
X349401Y893427D03*
X345700D03*
X342000D03*
X338299D03*
X347551Y896616D03*
X343850D03*
X340149D03*
X336448D03*
X349401Y899805D03*
X345700D03*
X342000D03*
X338299D03*
X347551Y902994D03*
X343850D03*
X340149D03*
X336448D03*
X349401Y906182D03*
X345700D03*
X342000D03*
X338299D03*
X347551Y909371D03*
X343850D03*
X340149D03*
X336448D03*
X349401Y912560D03*
X345700D03*
X342000D03*
X338299D03*
X347551Y915749D03*
X343850D03*
X340149D03*
X336448D03*
X349401Y918938D03*
X345700D03*
X342000D03*
X338299D03*
X347551Y922127D03*
X343850D03*
X340149D03*
X336448D03*
X349401Y925316D03*
X345700D03*
X342000D03*
X338299D03*
X347551Y928505D03*
X343850D03*
X340149D03*
X336448D03*
X349401Y931694D03*
X345700D03*
X342000D03*
X338299D03*
X347551Y934883D03*
X343850D03*
X340149D03*
X336448D03*
X349401Y938072D03*
X345700D03*
X342000D03*
X338299D03*
X347551Y941261D03*
X343850D03*
X340149D03*
X336448D03*
X349401Y944450D03*
X345700D03*
X342000D03*
X338299D03*
X347551Y947639D03*
X343850D03*
X340149D03*
X336448D03*
X349401Y950828D03*
X345700D03*
X342000D03*
X338299D03*
X347551Y954017D03*
X343850D03*
X340149D03*
X336448D03*
X349401Y957206D03*
X345700D03*
X342000D03*
X338299D03*
X347551Y960395D03*
X343850D03*
X340149D03*
X336448D03*
X349401Y963584D03*
X345700D03*
X342000D03*
X338299D03*
X347551Y966773D03*
X343850D03*
X340149D03*
X336448D03*
X349401Y969962D03*
X345700D03*
X342000D03*
X338299D03*
X347551Y973151D03*
X343850D03*
X340149D03*
X336448D03*
X349401Y976340D03*
X345700D03*
X342000D03*
X338299D03*
X347551Y979529D03*
X343850D03*
X340149D03*
X336448D03*
X349401Y982718D03*
X345700D03*
X342000D03*
X338299D03*
X347551Y985907D03*
X343850D03*
X340149D03*
X336448D03*
X349401Y989096D03*
X345700D03*
X342000D03*
X338299D03*
X347551Y992285D03*
X343850D03*
X340149D03*
X336448D03*
X349401Y995474D03*
X345700D03*
X342000D03*
X338299D03*
X347551Y998663D03*
X343850D03*
X340149D03*
X336448D03*
X349401Y1001852D03*
X345700D03*
X342000D03*
X338299D03*
X347551Y1005041D03*
X343850D03*
X340149D03*
X336448D03*
X349401Y1008230D03*
X345700D03*
X342000D03*
X338299D03*
X347551Y1011419D03*
X343850D03*
X340149D03*
X336448D03*
X348732Y1027009D03*
X345031D03*
X341330D03*
X337629D03*
X350582Y1030198D03*
X346881D03*
X343181D03*
X339480D03*
X348732Y1033387D03*
X345031D03*
X341330D03*
X337629D03*
X350582Y1036576D03*
X346881D03*
X343181D03*
X339480D03*
X348732Y1039765D03*
X345031D03*
X341330D03*
X337629D03*
X350582Y1042954D03*
X346881D03*
X343181D03*
X339480D03*
X348732Y1046143D03*
X345031D03*
X341330D03*
X337629D03*
X350582Y1049332D03*
X346881D03*
X343181D03*
X339480D03*
X348732Y1052521D03*
X345031D03*
X341330D03*
X337629D03*
X350582Y1055710D03*
X346881D03*
X343181D03*
X339480D03*
X348732Y1058899D03*
X345031D03*
X341330D03*
X337629D03*
X350582Y1062088D03*
X346881D03*
X343181D03*
X339480D03*
X348732Y1065277D03*
X345031D03*
X341330D03*
X337629D03*
X350582Y1068466D03*
X346881D03*
X343181D03*
X339480D03*
X348732Y1071655D03*
X345031D03*
X341330D03*
X337629D03*
X350582Y1074844D03*
X346881D03*
X343181D03*
X339480D03*
X348732Y1078033D03*
X345031D03*
X341330D03*
X337629D03*
X350582Y1081222D03*
X346881D03*
X343181D03*
X339480D03*
X348732Y1084411D03*
X345031D03*
X341330D03*
X337629D03*
X350582Y1087600D03*
X346881D03*
X343181D03*
X339480D03*
X348732Y1090789D03*
X345031D03*
X341330D03*
X337629D03*
X350582Y1093978D03*
X346881D03*
X343181D03*
X339480D03*
X348732Y1097167D03*
X345031D03*
X341330D03*
X337629D03*
X350582Y1100356D03*
X346881D03*
X343181D03*
X339480D03*
X348732Y1103545D03*
X345031D03*
X341330D03*
X337629D03*
X350582Y1106734D03*
X346881D03*
X343181D03*
X339480D03*
X348732Y1109923D03*
X345031D03*
X341330D03*
X337629D03*
X350582Y1113112D03*
X346881D03*
X343181D03*
X339480D03*
X348732Y1116301D03*
X345031D03*
X341330D03*
X337629D03*
X350582Y1119490D03*
X346881D03*
X343181D03*
X339480D03*
X348732Y1122679D03*
X345031D03*
X341330D03*
X337629D03*
X350582Y1125868D03*
X346881D03*
X343181D03*
X339480D03*
X348732Y1129057D03*
X345031D03*
X341330D03*
X337629D03*
X350582Y1132246D03*
X346881D03*
X343181D03*
X339480D03*
X348732Y1135434D03*
X345031D03*
X341330D03*
X337629D03*
X350582Y1138623D03*
X346881D03*
X343181D03*
X339480D03*
X348732Y1141812D03*
X345031D03*
X341330D03*
X337629D03*
X350582Y1145001D03*
X346881D03*
X343181D03*
X339480D03*
X348732Y1148190D03*
X345031D03*
X341330D03*
X337629D03*
X350582Y1151379D03*
X346881D03*
X343181D03*
X339480D03*
X348732Y1154568D03*
X345031D03*
X341330D03*
X337629D03*
X350582Y1157757D03*
X346881D03*
X343181D03*
X339480D03*
X348732Y1160946D03*
X345031D03*
X341330D03*
X337629D03*
X350582Y1164135D03*
X343181D03*
X339480D03*
X364204Y874293D03*
X360504D03*
X356803D03*
X353102D03*
X362354Y877482D03*
X358653D03*
X354952D03*
X351252D03*
X364204Y880671D03*
X360504D03*
X356803D03*
X353102D03*
X362354Y883860D03*
X358653D03*
X354952D03*
X351252D03*
X364204Y887049D03*
X360504D03*
X356803D03*
X353102D03*
X362354Y890238D03*
X358653D03*
X354952D03*
X351252D03*
X364204Y893427D03*
X360504D03*
X356803D03*
X353102D03*
X362354Y896616D03*
X358653D03*
X354952D03*
X351252D03*
X364204Y899805D03*
X360504D03*
X356803D03*
X353102D03*
X362354Y902994D03*
X358653D03*
X354952D03*
X351252D03*
X364204Y906182D03*
X360504D03*
X356803D03*
X353102D03*
X362354Y909371D03*
X358653D03*
X354952D03*
X351252D03*
X364204Y912560D03*
X360504D03*
X356803D03*
X353102D03*
X362354Y915749D03*
X358653D03*
X354952D03*
X351252D03*
X364204Y918938D03*
X360504D03*
X356803D03*
X353102D03*
X362354Y922127D03*
X358653D03*
X354952D03*
X351252D03*
X364204Y925316D03*
X360504D03*
X356803D03*
X353102D03*
X362354Y928505D03*
X358653D03*
X354952D03*
X351252D03*
X364204Y931694D03*
X360504D03*
X356803D03*
X353102D03*
X362354Y934883D03*
X358653D03*
X354952D03*
X351252D03*
X364204Y938072D03*
X360504D03*
X356803D03*
X353102D03*
X362354Y941261D03*
X358653D03*
X354952D03*
X351252D03*
X364204Y944450D03*
X360504D03*
X356803D03*
X353102D03*
X362354Y947639D03*
X358653D03*
X354952D03*
X351252D03*
X364204Y950828D03*
X360504D03*
X356803D03*
X353102D03*
X362354Y954017D03*
X358653D03*
X354952D03*
X351252D03*
X364204Y957206D03*
X360504D03*
X356803D03*
X353102D03*
X362354Y960395D03*
X358653D03*
X354952D03*
X351252D03*
X364204Y963584D03*
X360504D03*
X356803D03*
X353102D03*
X362354Y966773D03*
X358653D03*
X354952D03*
X351252D03*
X364204Y969962D03*
X360504D03*
X356803D03*
X353102D03*
X362354Y973151D03*
X358653D03*
X354952D03*
X351252D03*
X364204Y976340D03*
X360504D03*
X356803D03*
X353102D03*
X362354Y979529D03*
X358653D03*
X354952D03*
X351252D03*
X364204Y982718D03*
X360504D03*
X356803D03*
X353102D03*
X362354Y985907D03*
X358653D03*
X354952D03*
X351252D03*
X364204Y989096D03*
X360504D03*
X356803D03*
X353102D03*
X362354Y992285D03*
X358653D03*
X354952D03*
X351252D03*
X364204Y995474D03*
X360504D03*
X356803D03*
X353102D03*
X362354Y998663D03*
X358653D03*
X354952D03*
X351252D03*
X364204Y1001852D03*
X360504D03*
X356803D03*
X353102D03*
X362354Y1005041D03*
X358653D03*
X354952D03*
X351252D03*
X364204Y1008230D03*
X360504D03*
X356803D03*
X353102D03*
X362354Y1011419D03*
X358653D03*
X354952D03*
X351252D03*
X363535Y1027009D03*
X359834D03*
X356133D03*
X352433D03*
X365385Y1030198D03*
X361685D03*
X357984D03*
X354283D03*
X363535Y1033387D03*
X359834D03*
X356133D03*
X352433D03*
X365385Y1036576D03*
X361685D03*
X357984D03*
X354283D03*
X363535Y1039765D03*
X359834D03*
X356133D03*
X352433D03*
X365385Y1042954D03*
X361685D03*
X357984D03*
X354283D03*
X363535Y1046143D03*
X359834D03*
X356133D03*
X352433D03*
X365385Y1049332D03*
X361685D03*
X357984D03*
X354283D03*
X363535Y1052521D03*
X359834D03*
X356133D03*
X352433D03*
X365385Y1055710D03*
X361685D03*
X357984D03*
X354283D03*
X363535Y1058899D03*
X359834D03*
X356133D03*
X352433D03*
X365385Y1062088D03*
X361685D03*
X357984D03*
X354283D03*
X363535Y1065277D03*
X359834D03*
X356133D03*
X352433D03*
X365385Y1068466D03*
X361685D03*
X357984D03*
X354283D03*
X363535Y1071655D03*
X359834D03*
X356133D03*
X352433D03*
X365385Y1074844D03*
X361685D03*
X357984D03*
X354283D03*
X363535Y1078033D03*
X359834D03*
X356133D03*
X352433D03*
X365385Y1081222D03*
X361685D03*
X357984D03*
X354283D03*
X363535Y1084411D03*
X359834D03*
X356133D03*
X352433D03*
X365385Y1087600D03*
X361685D03*
X357984D03*
X354283D03*
X363535Y1090789D03*
X359834D03*
X356133D03*
X352433D03*
X365385Y1093978D03*
X361685D03*
X357984D03*
X354283D03*
X363535Y1097167D03*
X359834D03*
X356133D03*
X352433D03*
X365385Y1100356D03*
X361685D03*
X357984D03*
X354283D03*
X363535Y1103545D03*
X359834D03*
X356133D03*
X352433D03*
X365385Y1106734D03*
X361685D03*
X357984D03*
X354283D03*
X363535Y1109923D03*
X359834D03*
X356133D03*
X352433D03*
X365385Y1113112D03*
X361685D03*
X357984D03*
X354283D03*
X363535Y1116301D03*
X359834D03*
X356133D03*
X352433D03*
X365385Y1119490D03*
X361685D03*
X357984D03*
X354283D03*
X363535Y1122679D03*
X359834D03*
X356133D03*
X352433D03*
X365385Y1125868D03*
X361685D03*
X357984D03*
X354283D03*
X363535Y1129057D03*
X359834D03*
X356133D03*
X352433D03*
X365385Y1132246D03*
X361685D03*
X357984D03*
X354283D03*
X363535Y1135434D03*
X359834D03*
X356133D03*
X352433D03*
X365385Y1138623D03*
X361685D03*
X357984D03*
X354283D03*
X363535Y1141812D03*
X359834D03*
X356133D03*
X352433D03*
X365385Y1145001D03*
X361685D03*
X357984D03*
X354283D03*
X363535Y1148190D03*
X359834D03*
X356133D03*
X352433D03*
X365385Y1151379D03*
X361685D03*
X357984D03*
X354283D03*
X363535Y1154568D03*
X359834D03*
X356133D03*
X352433D03*
X365385Y1157757D03*
X361685D03*
X357984D03*
X354283D03*
X363535Y1160946D03*
X359834D03*
X356133D03*
X352433D03*
X365385Y1164135D03*
X361685D03*
X357984D03*
X354283D03*
X379007Y874293D03*
X375307D03*
X371606D03*
X377157Y877482D03*
X373456D03*
X369755D03*
X366055D03*
X379007Y880671D03*
X375307D03*
X371606D03*
X367905D03*
X377157Y883860D03*
X373456D03*
X369755D03*
X366055D03*
X379007Y887049D03*
X375307D03*
X371606D03*
X367905D03*
X377157Y890238D03*
X373456D03*
X369755D03*
X366055D03*
X379007Y893427D03*
X375307D03*
X371606D03*
X367905D03*
X377157Y896616D03*
X373456D03*
X369755D03*
X366055D03*
X379007Y899805D03*
X375307D03*
X371606D03*
X367905D03*
X377157Y902994D03*
X373456D03*
X369755D03*
X366055D03*
X379007Y906182D03*
X375307D03*
X371606D03*
X367905D03*
X377157Y909371D03*
X373456D03*
X369755D03*
X366055D03*
X379007Y912560D03*
X375307D03*
X371606D03*
X367905D03*
X377157Y915749D03*
X373456D03*
X369755D03*
X366055D03*
X379007Y918938D03*
X375307D03*
X371606D03*
X367905D03*
X377157Y922127D03*
X373456D03*
X369755D03*
X366055D03*
X379007Y925316D03*
X375307D03*
X371606D03*
X367905D03*
X377157Y928505D03*
X373456D03*
X369755D03*
X366055D03*
X379007Y931694D03*
X375307D03*
X371606D03*
X367905D03*
X377157Y934883D03*
X373456D03*
X369755D03*
X366055D03*
X379007Y938072D03*
X375307D03*
X371606D03*
X367905D03*
X377157Y941261D03*
X373456D03*
X369755D03*
X366055D03*
X379007Y944450D03*
X375307D03*
X371606D03*
X367905D03*
X377157Y947639D03*
X373456D03*
X369755D03*
X366055D03*
X379007Y950828D03*
X375307D03*
X371606D03*
X367905D03*
X377157Y954017D03*
X373456D03*
X369755D03*
X366055D03*
X379007Y957206D03*
X375307D03*
X371606D03*
X367905D03*
X377157Y960395D03*
X373456D03*
X369755D03*
X366055D03*
X379007Y963584D03*
X375307D03*
X371606D03*
X367905D03*
X377157Y966773D03*
X373456D03*
X369755D03*
X366055D03*
X379007Y969962D03*
X375307D03*
X371606D03*
X367905D03*
X377157Y973151D03*
X373456D03*
X369755D03*
X366055D03*
X379007Y976340D03*
X375307D03*
X371606D03*
X367905D03*
X377157Y979529D03*
X373456D03*
X369755D03*
X366055D03*
X379007Y982718D03*
X375307D03*
X371606D03*
X367905D03*
X377157Y985907D03*
X373456D03*
X369755D03*
X366055D03*
X379007Y989096D03*
X375307D03*
X371606D03*
X367905D03*
X377157Y992285D03*
X373456D03*
X369755D03*
X366055D03*
X379007Y995474D03*
X375307D03*
X371606D03*
X367905D03*
X377157Y998663D03*
X373456D03*
X369755D03*
X366055D03*
X379007Y1001852D03*
X375307D03*
X371606D03*
X367905D03*
X377157Y1005041D03*
X373456D03*
X369755D03*
X366055D03*
X379007Y1008230D03*
X375307D03*
X371606D03*
X367905D03*
X377157Y1011419D03*
X373456D03*
X369755D03*
X366055D03*
X378338Y1027009D03*
X374637D03*
X370937D03*
X367236D03*
X380189Y1030198D03*
X376488D03*
X372787D03*
X369086D03*
X378338Y1033387D03*
X374637D03*
X370937D03*
X367236D03*
X380189Y1036576D03*
X376488D03*
X372787D03*
X369086D03*
X378338Y1039765D03*
X374637D03*
X370937D03*
X367236D03*
X380189Y1042954D03*
X376488D03*
X372787D03*
X369086D03*
X378338Y1046143D03*
X374637D03*
X370937D03*
X367236D03*
X380189Y1049332D03*
X376488D03*
X372787D03*
X369086D03*
X378338Y1052521D03*
X374637D03*
X370937D03*
X367236D03*
X380189Y1055710D03*
X376488D03*
X372787D03*
X369086D03*
X378338Y1058899D03*
X374637D03*
X370937D03*
X367236D03*
X380189Y1062088D03*
X376488D03*
X372787D03*
X369086D03*
X378338Y1065277D03*
X374637D03*
X370937D03*
X367236D03*
X380189Y1068466D03*
X376488D03*
X372787D03*
X369086D03*
X378338Y1071655D03*
X374637D03*
X370937D03*
X367236D03*
X380189Y1074844D03*
X376488D03*
X372787D03*
X369086D03*
X378338Y1078033D03*
X374637D03*
X370937D03*
X367236D03*
X380189Y1081222D03*
X376488D03*
X372787D03*
X369086D03*
X378338Y1084411D03*
X374637D03*
X370937D03*
X367236D03*
X380189Y1087600D03*
X376488D03*
X372787D03*
X369086D03*
X378338Y1090789D03*
X374637D03*
X370937D03*
X367236D03*
X380189Y1093978D03*
X376488D03*
X372787D03*
X369086D03*
X378338Y1097167D03*
X374637D03*
X370937D03*
X367236D03*
X380189Y1100356D03*
X376488D03*
X372787D03*
X369086D03*
X378338Y1103545D03*
X374637D03*
X370937D03*
X367236D03*
X380189Y1106734D03*
X376488D03*
X372787D03*
X369086D03*
X378338Y1109923D03*
X374637D03*
X370937D03*
X367236D03*
X380189Y1113112D03*
X376488D03*
X372787D03*
X369086D03*
X378338Y1116301D03*
X374637D03*
X370937D03*
X367236D03*
X380189Y1119490D03*
X376488D03*
X372787D03*
X369086D03*
X378338Y1122679D03*
X374637D03*
X370937D03*
X367236D03*
X380189Y1125868D03*
X376488D03*
X372787D03*
X369086D03*
X378338Y1129057D03*
X374637D03*
X370937D03*
X367236D03*
X380189Y1132246D03*
X376488D03*
X372787D03*
X369086D03*
X378338Y1135434D03*
X374637D03*
X370937D03*
X367236D03*
X380189Y1138623D03*
X376488D03*
X372787D03*
X369086D03*
X378338Y1141812D03*
X374637D03*
X370937D03*
X367236D03*
X380189Y1145001D03*
X376488D03*
X372787D03*
X369086D03*
X378338Y1148190D03*
X374637D03*
X370937D03*
X367236D03*
X380189Y1151379D03*
X376488D03*
X372787D03*
X369086D03*
X378338Y1154568D03*
X374637D03*
X370937D03*
X367236D03*
X380189Y1157757D03*
X376488D03*
X372787D03*
X369086D03*
X378338Y1160946D03*
X374637D03*
X370937D03*
X367236D03*
X380189Y1164135D03*
X376488D03*
X372787D03*
X393811Y874293D03*
X386409D03*
X382708D03*
X391960Y877482D03*
X388259D03*
X384559D03*
X380858D03*
X393811Y880671D03*
X390110D03*
X386409D03*
X382708D03*
X391960Y883860D03*
X388259D03*
X384559D03*
X380858D03*
X393811Y887049D03*
X390110D03*
X386409D03*
X382708D03*
X391960Y890238D03*
X388259D03*
X384559D03*
X380858D03*
X393811Y893427D03*
X390110D03*
X386409D03*
X382708D03*
X391960Y896616D03*
X388259D03*
X384559D03*
X380858D03*
X393811Y899805D03*
X390110D03*
X386409D03*
X382708D03*
X391960Y902994D03*
X388259D03*
X384559D03*
X380858D03*
X393811Y906182D03*
X390110D03*
X386409D03*
X382708D03*
X391960Y909371D03*
X388259D03*
X384559D03*
X380858D03*
X393811Y912560D03*
X390110D03*
X386409D03*
X382708D03*
X391960Y915749D03*
X388259D03*
X384559D03*
X380858D03*
X393811Y918938D03*
X390110D03*
X386409D03*
X382708D03*
X391960Y922127D03*
X388259D03*
X384559D03*
X380858D03*
X393811Y925316D03*
X390110D03*
X386409D03*
X382708D03*
X391960Y928505D03*
X388259D03*
X384559D03*
X380858D03*
X393811Y931694D03*
X390110D03*
X386409D03*
X382708D03*
X391960Y934883D03*
X388259D03*
X384559D03*
X380858D03*
X393811Y938072D03*
X390110D03*
X386409D03*
X382708D03*
X391960Y941261D03*
X388259D03*
X384559D03*
X380858D03*
X393811Y944450D03*
X390110D03*
X386409D03*
X382708D03*
X391960Y947639D03*
X388259D03*
X384559D03*
X380858D03*
X393811Y950828D03*
X390110D03*
X386409D03*
X382708D03*
X391960Y954017D03*
X388259D03*
X384559D03*
X380858D03*
X393811Y957206D03*
X390110D03*
X386409D03*
X382708D03*
X391960Y960395D03*
X388259D03*
X384559D03*
X380858D03*
X393811Y963584D03*
X390110D03*
X386409D03*
X382708D03*
X391960Y966773D03*
X388259D03*
X384559D03*
X380858D03*
X393811Y969962D03*
X390110D03*
X386409D03*
X382708D03*
X391960Y973151D03*
X388259D03*
X384559D03*
X380858D03*
X393811Y976340D03*
X390110D03*
X386409D03*
X382708D03*
X391960Y979529D03*
X388259D03*
X384559D03*
X380858D03*
X393811Y982718D03*
X390110D03*
X386409D03*
X382708D03*
X391960Y985907D03*
X388259D03*
X384559D03*
X380858D03*
X393811Y989096D03*
X390110D03*
X386409D03*
X382708D03*
X391960Y992285D03*
X388259D03*
X384559D03*
X380858D03*
X393811Y995474D03*
X390110D03*
X386409D03*
X382708D03*
X391960Y998663D03*
X388259D03*
X384559D03*
X380858D03*
X393811Y1001852D03*
X390110D03*
X386409D03*
X382708D03*
X391960Y1005041D03*
X388259D03*
X384559D03*
X380858D03*
X393811Y1008230D03*
X390110D03*
X386409D03*
X382708D03*
X391960Y1011419D03*
X388259D03*
X384559D03*
X380858D03*
X393141Y1027009D03*
X389441D03*
X385740D03*
X382039D03*
X394992Y1030198D03*
X391291D03*
X387590D03*
X383889D03*
X393141Y1033387D03*
X389441D03*
X385740D03*
X382039D03*
X394992Y1036576D03*
X391291D03*
X387590D03*
X383889D03*
X393141Y1039765D03*
X389441D03*
X385740D03*
X382039D03*
X394992Y1042954D03*
X391291D03*
X387590D03*
X383889D03*
X393141Y1046143D03*
X389441D03*
X385740D03*
X382039D03*
X394992Y1049332D03*
X391291D03*
X387590D03*
X383889D03*
X393141Y1052521D03*
X389441D03*
X385740D03*
X382039D03*
X394992Y1055710D03*
X391291D03*
X387590D03*
X383889D03*
X393141Y1058899D03*
X389441D03*
X385740D03*
X382039D03*
X394992Y1062088D03*
X391291D03*
X387590D03*
X383889D03*
X393141Y1065277D03*
X389441D03*
X385740D03*
X382039D03*
X394992Y1068466D03*
X391291D03*
X387590D03*
X383889D03*
X393141Y1071655D03*
X389441D03*
X385740D03*
X382039D03*
X394992Y1074844D03*
X391291D03*
X387590D03*
X383889D03*
X393141Y1078033D03*
X389441D03*
X385740D03*
X382039D03*
X394992Y1081222D03*
X391291D03*
X387590D03*
X383889D03*
X393141Y1084411D03*
X389441D03*
X385740D03*
X382039D03*
X394992Y1087600D03*
X391291D03*
X387590D03*
X383889D03*
X393141Y1090789D03*
X389441D03*
X385740D03*
X382039D03*
X394992Y1093978D03*
X391291D03*
X387590D03*
X383889D03*
X393141Y1097167D03*
X389441D03*
X385740D03*
X382039D03*
X394992Y1100356D03*
X391291D03*
X387590D03*
X383889D03*
X393141Y1103545D03*
X389441D03*
X385740D03*
X382039D03*
X394992Y1106734D03*
X391291D03*
X387590D03*
X383889D03*
X393141Y1109923D03*
X389441D03*
X385740D03*
X382039D03*
X394992Y1113112D03*
X391291D03*
X387590D03*
X383889D03*
X393141Y1116301D03*
X389441D03*
X385740D03*
X382039D03*
X394992Y1119490D03*
X391291D03*
X387590D03*
X383889D03*
X393141Y1122679D03*
X389441D03*
X385740D03*
X382039D03*
X394992Y1125868D03*
X391291D03*
X387590D03*
X383889D03*
X393141Y1129057D03*
X389441D03*
X385740D03*
X382039D03*
X394992Y1132246D03*
X391291D03*
X387590D03*
X383889D03*
X393141Y1135434D03*
X389441D03*
X385740D03*
X382039D03*
X394992Y1138623D03*
X391291D03*
X387590D03*
X383889D03*
X393141Y1141812D03*
X389441D03*
X385740D03*
X382039D03*
X394992Y1145001D03*
X391291D03*
X387590D03*
X383889D03*
X393141Y1148190D03*
X389441D03*
X385740D03*
X382039D03*
X394992Y1151379D03*
X391291D03*
X387590D03*
X383889D03*
X393141Y1154568D03*
X389441D03*
X385740D03*
X382039D03*
X394992Y1157757D03*
X391291D03*
X387590D03*
X383889D03*
X393141Y1160946D03*
X389441D03*
X385740D03*
X382039D03*
X394992Y1164135D03*
X387590D03*
X383889D03*
X408614Y874293D03*
X404913D03*
X401212D03*
X397511D03*
X410464Y877482D03*
X406763D03*
X403063D03*
X399362D03*
X395661D03*
X408614Y880671D03*
X404913D03*
X401212D03*
X397511D03*
X410464Y883860D03*
X406763D03*
X403063D03*
X399362D03*
X395661D03*
X408614Y887049D03*
X404913D03*
X401212D03*
X397511D03*
X410464Y890238D03*
X406763D03*
X403063D03*
X399362D03*
X395661D03*
X408614Y893427D03*
X404913D03*
X401212D03*
X397511D03*
X410464Y896616D03*
X406763D03*
X403063D03*
X399362D03*
X395661D03*
X408614Y899805D03*
X404913D03*
X401212D03*
X397511D03*
X410464Y902994D03*
X406763D03*
X403063D03*
X399362D03*
X395661D03*
X408614Y906182D03*
X404913D03*
X401212D03*
X397511D03*
X410464Y909371D03*
X406763D03*
X403063D03*
X399362D03*
X395661D03*
X408614Y912560D03*
X404913D03*
X401212D03*
X397511D03*
X410464Y915749D03*
X406763D03*
X403063D03*
X399362D03*
X395661D03*
X408614Y918938D03*
X404913D03*
X401212D03*
X397511D03*
X410464Y922127D03*
X406763D03*
X403063D03*
X399362D03*
X395661D03*
X408614Y925316D03*
X404913D03*
X401212D03*
X397511D03*
X410464Y928505D03*
X406763D03*
X403063D03*
X399362D03*
X395661D03*
X408614Y931694D03*
X404913D03*
X401212D03*
X397511D03*
X410464Y934883D03*
X406763D03*
X403063D03*
X399362D03*
X395661D03*
X408614Y938072D03*
X404913D03*
X401212D03*
X397511D03*
X410464Y941261D03*
X406763D03*
X403063D03*
X399362D03*
X395661D03*
X408614Y944450D03*
X404913D03*
X401212D03*
X397511D03*
X410464Y947639D03*
X406763D03*
X403063D03*
X399362D03*
X395661D03*
X408614Y950828D03*
X404913D03*
X401212D03*
X397511D03*
X410464Y954017D03*
X406763D03*
X403063D03*
X399362D03*
X395661D03*
X408614Y957206D03*
X404913D03*
X401212D03*
X397511D03*
X410464Y960395D03*
X406763D03*
X403063D03*
X399362D03*
X395661D03*
X408614Y963584D03*
X404913D03*
X401212D03*
X397511D03*
X410464Y966773D03*
X406763D03*
X403063D03*
X399362D03*
X395661D03*
X408614Y969962D03*
X404913D03*
X401212D03*
X397511D03*
X410464Y973151D03*
X406763D03*
X403063D03*
X399362D03*
X395661D03*
X408614Y976340D03*
X404913D03*
X401212D03*
X397511D03*
X410464Y979529D03*
X406763D03*
X403063D03*
X399362D03*
X395661D03*
X408614Y982718D03*
X404913D03*
X401212D03*
X397511D03*
X410464Y985907D03*
X406763D03*
X403063D03*
X399362D03*
X395661D03*
X408614Y989096D03*
X404913D03*
X401212D03*
X397511D03*
X410464Y992285D03*
X406763D03*
X403063D03*
X399362D03*
X395661D03*
X404913Y995474D03*
X401212D03*
X397511D03*
X403063Y998663D03*
X399362D03*
X395661D03*
X404913Y1001852D03*
X401212D03*
X397511D03*
X403063Y1005041D03*
X399362D03*
X395661D03*
X404913Y1008230D03*
X401212D03*
X397511D03*
X403063Y1011419D03*
X399362D03*
X395661D03*
X404244Y1027009D03*
X400543D03*
X396842D03*
X406094Y1030198D03*
X402393D03*
X398693D03*
X404244Y1033387D03*
X400543D03*
X396842D03*
X406094Y1036576D03*
X402393D03*
X398693D03*
X404244Y1039765D03*
X400543D03*
X396842D03*
X406094Y1042954D03*
X402393D03*
X398693D03*
X407944Y1046143D03*
X404244D03*
X400543D03*
X396842D03*
X409795Y1049332D03*
X406094D03*
X402393D03*
X398693D03*
X407944Y1052521D03*
X404244D03*
X400543D03*
X396842D03*
X409795Y1055710D03*
X406094D03*
X402393D03*
X398693D03*
X407944Y1058899D03*
X404244D03*
X400543D03*
X396842D03*
X409795Y1062088D03*
X406094D03*
X402393D03*
X398693D03*
X407944Y1065277D03*
X404244D03*
X400543D03*
X396842D03*
X409795Y1068466D03*
X406094D03*
X402393D03*
X398693D03*
X407944Y1071655D03*
X404244D03*
X400543D03*
X396842D03*
X409795Y1074844D03*
X406094D03*
X402393D03*
X398693D03*
X407944Y1078033D03*
X404244D03*
X400543D03*
X396842D03*
X409795Y1081222D03*
X406094D03*
X402393D03*
X398693D03*
X407944Y1084411D03*
X404244D03*
X400543D03*
X396842D03*
X409795Y1087600D03*
X406094D03*
X402393D03*
X398693D03*
X407944Y1090789D03*
X404244D03*
X400543D03*
X396842D03*
X409795Y1093978D03*
X406094D03*
X402393D03*
X398693D03*
X407944Y1097167D03*
X404244D03*
X400543D03*
X396842D03*
X409795Y1100356D03*
X406094D03*
X402393D03*
X398693D03*
X407944Y1103545D03*
X404244D03*
X400543D03*
X396842D03*
X409795Y1106734D03*
X406094D03*
X402393D03*
X398693D03*
X407944Y1109923D03*
X404244D03*
X400543D03*
X396842D03*
X409795Y1113112D03*
X406094D03*
X402393D03*
X398693D03*
X407944Y1116301D03*
X404244D03*
X400543D03*
X396842D03*
X409795Y1119490D03*
X406094D03*
X402393D03*
X398693D03*
X407944Y1122679D03*
X404244D03*
X400543D03*
X396842D03*
X409795Y1125868D03*
X406094D03*
X402393D03*
X398693D03*
X407944Y1129057D03*
X404244D03*
X400543D03*
X396842D03*
X409795Y1132246D03*
X406094D03*
X402393D03*
X398693D03*
X407944Y1135434D03*
X404244D03*
X400543D03*
X396842D03*
X409795Y1138623D03*
X406094D03*
X402393D03*
X398693D03*
X407944Y1141812D03*
X404244D03*
X400543D03*
X396842D03*
X409795Y1145001D03*
X406094D03*
X402393D03*
X398693D03*
X407944Y1148190D03*
X404244D03*
X400543D03*
X396842D03*
X409795Y1151379D03*
X406094D03*
X402393D03*
X398693D03*
X407944Y1154568D03*
X404244D03*
X400543D03*
X396842D03*
X409795Y1157757D03*
X406094D03*
X402393D03*
X398693D03*
X407944Y1160946D03*
X404244D03*
X400543D03*
X396842D03*
X409795Y1164135D03*
X406094D03*
X402393D03*
X398693D03*
X423417Y874293D03*
X419716D03*
X416015D03*
X425267Y877482D03*
X421567D03*
X417866D03*
X414165D03*
X423417Y880671D03*
X419716D03*
X416015D03*
X412315D03*
X425267Y883860D03*
X421567D03*
X417866D03*
X414165D03*
X423417Y887049D03*
X419716D03*
X416015D03*
X412315D03*
X425267Y890238D03*
X421567D03*
X417866D03*
X414165D03*
X423417Y893427D03*
X419716D03*
X416015D03*
X412315D03*
X425267Y896616D03*
X421567D03*
X417866D03*
X414165D03*
X423417Y899805D03*
X419716D03*
X416015D03*
X412315D03*
X425267Y902994D03*
X421567D03*
X417866D03*
X414165D03*
X423417Y906182D03*
X419716D03*
X416015D03*
X412315D03*
X425267Y909371D03*
X421567D03*
X417866D03*
X414165D03*
X423417Y912560D03*
X419716D03*
X416015D03*
X412315D03*
X425267Y915749D03*
X421567D03*
X417866D03*
X414165D03*
X423417Y918938D03*
X419716D03*
X416015D03*
X412315D03*
X425267Y922127D03*
X421567D03*
X417866D03*
X414165D03*
X423417Y925316D03*
X419716D03*
X416015D03*
X412315D03*
X425267Y928505D03*
X421567D03*
X417866D03*
X414165D03*
X423417Y931694D03*
X419716D03*
X416015D03*
X412315D03*
X425267Y934883D03*
X421567D03*
X417866D03*
X414165D03*
X423417Y938072D03*
X419716D03*
X416015D03*
X412315D03*
X425267Y941261D03*
X421567D03*
X417866D03*
X414165D03*
X423417Y944450D03*
X419716D03*
X416015D03*
X412315D03*
X425267Y947639D03*
X421567D03*
X417866D03*
X414165D03*
X423417Y950828D03*
X419716D03*
X416015D03*
X412315D03*
X425267Y954017D03*
X421567D03*
X417866D03*
X414165D03*
X423417Y957206D03*
X419716D03*
X416015D03*
X412315D03*
X425267Y960395D03*
X421567D03*
X417866D03*
X414165D03*
X423417Y963584D03*
X419716D03*
X416015D03*
X412315D03*
X425267Y966773D03*
X421567D03*
X417866D03*
X414165D03*
X423417Y969962D03*
X419716D03*
X416015D03*
X412315D03*
X425267Y973151D03*
X421567D03*
X417866D03*
X414165D03*
X423417Y976340D03*
X419716D03*
X416015D03*
X412315D03*
X425267Y979529D03*
X421567D03*
X417866D03*
X414165D03*
X423417Y982718D03*
X419716D03*
X416015D03*
X412315D03*
X425267Y985907D03*
X421567D03*
X417866D03*
X414165D03*
X423417Y989096D03*
X419716D03*
X416015D03*
X412315D03*
X425267Y992285D03*
X421567D03*
X417866D03*
X414165D03*
X422748Y1046143D03*
X419047D03*
X415346D03*
X411645D03*
X424598Y1049332D03*
X420897D03*
X417196D03*
X413496D03*
X422748Y1052521D03*
X419047D03*
X415346D03*
X411645D03*
X424598Y1055710D03*
X420897D03*
X417196D03*
X413496D03*
X422748Y1058899D03*
X419047D03*
X415346D03*
X411645D03*
X424598Y1062088D03*
X420897D03*
X417196D03*
X413496D03*
X422748Y1065277D03*
X419047D03*
X415346D03*
X411645D03*
X424598Y1068466D03*
X420897D03*
X417196D03*
X413496D03*
X422748Y1071655D03*
X419047D03*
X415346D03*
X411645D03*
X424598Y1074844D03*
X420897D03*
X417196D03*
X413496D03*
X422748Y1078033D03*
X419047D03*
X415346D03*
X411645D03*
X424598Y1081222D03*
X420897D03*
X417196D03*
X413496D03*
X422748Y1084411D03*
X419047D03*
X415346D03*
X411645D03*
X424598Y1087600D03*
X420897D03*
X417196D03*
X413496D03*
X422748Y1090789D03*
X419047D03*
X415346D03*
X411645D03*
X424598Y1093978D03*
X420897D03*
X417196D03*
X413496D03*
X422748Y1097167D03*
X419047D03*
X415346D03*
X411645D03*
X424598Y1100356D03*
X420897D03*
X417196D03*
X413496D03*
X422748Y1103545D03*
X419047D03*
X415346D03*
X411645D03*
X424598Y1106734D03*
X420897D03*
X417196D03*
X413496D03*
X422748Y1109923D03*
X419047D03*
X415346D03*
X411645D03*
X424598Y1113112D03*
X420897D03*
X417196D03*
X413496D03*
X422748Y1116301D03*
X419047D03*
X415346D03*
X411645D03*
X424598Y1119490D03*
X420897D03*
X417196D03*
X413496D03*
X422748Y1122679D03*
X419047D03*
X415346D03*
X411645D03*
X424598Y1125868D03*
X420897D03*
X417196D03*
X413496D03*
X422748Y1129057D03*
X419047D03*
X415346D03*
X411645D03*
X424598Y1132246D03*
X420897D03*
X417196D03*
X413496D03*
X422748Y1135434D03*
X419047D03*
X415346D03*
X411645D03*
X424598Y1138623D03*
X420897D03*
X417196D03*
X413496D03*
X422748Y1141812D03*
X419047D03*
X415346D03*
X411645D03*
X424598Y1145001D03*
X420897D03*
X417196D03*
X413496D03*
X422748Y1148190D03*
X419047D03*
X415346D03*
X411645D03*
X424598Y1151379D03*
X420897D03*
X417196D03*
X413496D03*
X422748Y1154568D03*
X419047D03*
X415346D03*
X411645D03*
X424598Y1157757D03*
X420897D03*
X417196D03*
X413496D03*
X422748Y1160946D03*
X419047D03*
X415346D03*
X411645D03*
X424598Y1164135D03*
X420897D03*
X417196D03*
X430818Y874293D03*
X427118D03*
X436370Y877482D03*
X432669D03*
X428968D03*
X434519Y880671D03*
X430818D03*
X427118D03*
X436370Y883860D03*
X432669D03*
X428968D03*
X434519Y887049D03*
X430818D03*
X427118D03*
X436370Y890238D03*
X432669D03*
X428968D03*
X434519Y893427D03*
X430818D03*
X427118D03*
X436370Y896616D03*
X432669D03*
X428968D03*
X434519Y899805D03*
X430818D03*
X427118D03*
X436370Y902994D03*
X432669D03*
X428968D03*
X434519Y906182D03*
X430818D03*
X427118D03*
X436370Y909371D03*
X432669D03*
X428968D03*
X434519Y912560D03*
X430818D03*
X427118D03*
X436370Y915749D03*
X432669D03*
X428968D03*
X434519Y918938D03*
X430818D03*
X427118D03*
X436370Y922127D03*
X432669D03*
X428968D03*
X434519Y925316D03*
X430818D03*
X427118D03*
X436370Y928505D03*
X432669D03*
X428968D03*
X434519Y931694D03*
X430818D03*
X427118D03*
X436370Y934883D03*
X432669D03*
X428968D03*
X434519Y938072D03*
X430818D03*
X427118D03*
X436370Y941261D03*
X432669D03*
X428968D03*
X434519Y944450D03*
X430818D03*
X427118D03*
X436370Y947639D03*
X432669D03*
X428968D03*
X434519Y950828D03*
X430818D03*
X427118D03*
X436370Y954017D03*
X432669D03*
X428968D03*
X434519Y957206D03*
X430818D03*
X427118D03*
X436370Y960395D03*
X432669D03*
X428968D03*
X434519Y963584D03*
X430818D03*
X427118D03*
X436370Y966773D03*
X432669D03*
X428968D03*
X434519Y969962D03*
X430818D03*
X427118D03*
X436370Y973151D03*
X432669D03*
X428968D03*
X434519Y976340D03*
X430818D03*
X427118D03*
X436370Y979529D03*
X432669D03*
X428968D03*
X434519Y982718D03*
X430818D03*
X427118D03*
X436370Y985907D03*
X432669D03*
X428968D03*
X434519Y989096D03*
X430818D03*
X427118D03*
X436370Y992285D03*
X432669D03*
X428968D03*
X437551Y1046143D03*
X433850D03*
X430149D03*
X426448D03*
X435700Y1049332D03*
X432000D03*
X428299D03*
X437551Y1052521D03*
X433850D03*
X430149D03*
X426448D03*
X435700Y1055710D03*
X432000D03*
X428299D03*
X437551Y1058899D03*
X433850D03*
X430149D03*
X426448D03*
X435700Y1062088D03*
X432000D03*
X428299D03*
X437551Y1065277D03*
X433850D03*
X430149D03*
X426448D03*
X435700Y1068466D03*
X432000D03*
X428299D03*
X437551Y1071655D03*
X433850D03*
X430149D03*
X426448D03*
X435700Y1074844D03*
X432000D03*
X428299D03*
X437551Y1078033D03*
X433850D03*
X430149D03*
X426448D03*
X435700Y1081222D03*
X432000D03*
X428299D03*
X437551Y1084411D03*
X433850D03*
X430149D03*
X426448D03*
X435700Y1087600D03*
X432000D03*
X428299D03*
X437551Y1090789D03*
X433850D03*
X430149D03*
X426448D03*
X435700Y1093978D03*
X432000D03*
X428299D03*
X437551Y1097167D03*
X433850D03*
X430149D03*
X426448D03*
X435700Y1100356D03*
X432000D03*
X428299D03*
X437551Y1103545D03*
X433850D03*
X430149D03*
X426448D03*
X435700Y1106734D03*
X432000D03*
X428299D03*
X437551Y1109923D03*
X433850D03*
X430149D03*
X426448D03*
X435700Y1113112D03*
X432000D03*
X428299D03*
X437551Y1116301D03*
X433850D03*
X430149D03*
X426448D03*
X435700Y1119490D03*
X432000D03*
X428299D03*
X437551Y1122679D03*
X433850D03*
X430149D03*
X426448D03*
X435700Y1125868D03*
X432000D03*
X428299D03*
X437551Y1129057D03*
X433850D03*
X430149D03*
X426448D03*
X435700Y1132246D03*
X432000D03*
X428299D03*
X437551Y1135434D03*
X433850D03*
X430149D03*
X426448D03*
X435700Y1138623D03*
X432000D03*
X428299D03*
X437551Y1141812D03*
X433850D03*
X430149D03*
X426448D03*
X435700Y1145001D03*
X432000D03*
X428299D03*
X437551Y1148190D03*
X433850D03*
X430149D03*
X426448D03*
X435700Y1151379D03*
X432000D03*
X428299D03*
X437551Y1154568D03*
X433850D03*
X430149D03*
X426448D03*
X435700Y1157757D03*
X432000D03*
X428299D03*
X437551Y1160946D03*
X433850D03*
X430149D03*
X426448D03*
X432000Y1164135D03*
X428299D03*
X453023Y874293D03*
X449322D03*
X454874Y877482D03*
X451173D03*
X447472D03*
X443771D03*
X453023Y880671D03*
X449322D03*
X445622D03*
X454874Y883860D03*
X451173D03*
X447472D03*
X443771D03*
X453023Y887049D03*
X449322D03*
X445622D03*
X454874Y890238D03*
X451173D03*
X447472D03*
X443771D03*
X453023Y893427D03*
X449322D03*
X445622D03*
X454874Y896616D03*
X451173D03*
X447472D03*
X443771D03*
X453023Y899805D03*
X449322D03*
X445622D03*
X454874Y902994D03*
X451173D03*
X447472D03*
X443771D03*
X453023Y906182D03*
X449322D03*
X445622D03*
X454874Y909371D03*
X451173D03*
X447472D03*
X443771D03*
X453023Y912560D03*
X449322D03*
X445622D03*
X454874Y915749D03*
X451173D03*
X447472D03*
X443771D03*
X453023Y918938D03*
X449322D03*
X445622D03*
X454874Y922127D03*
X451173D03*
X447472D03*
X443771D03*
X453023Y925316D03*
X449322D03*
X445622D03*
X454874Y928505D03*
X451173D03*
X447472D03*
X443771D03*
X453023Y931694D03*
X449322D03*
X445622D03*
X454874Y934883D03*
X451173D03*
X447472D03*
X443771D03*
X453023Y938072D03*
X449322D03*
X445622D03*
X454874Y941261D03*
X451173D03*
X447472D03*
X443771D03*
X453023Y944450D03*
X449322D03*
X445622D03*
X454874Y947639D03*
X451173D03*
X447472D03*
X443771D03*
X453023Y950828D03*
X449322D03*
X445622D03*
X454874Y954017D03*
X451173D03*
X447472D03*
X443771D03*
X453023Y957206D03*
X449322D03*
X445622D03*
X454874Y960395D03*
X451173D03*
X447472D03*
X443771D03*
X453023Y963584D03*
X449322D03*
X445622D03*
X454874Y966773D03*
X451173D03*
X447472D03*
X443771D03*
X453023Y969962D03*
X449322D03*
X445622D03*
X454874Y973151D03*
X451173D03*
X447472D03*
X443771D03*
X453023Y976340D03*
X449322D03*
X445622D03*
X454874Y979529D03*
X451173D03*
X447472D03*
X443771D03*
X453023Y982718D03*
X449322D03*
X445622D03*
X454874Y985907D03*
X451173D03*
X447472D03*
X443771D03*
X453023Y989096D03*
X449322D03*
X445622D03*
X454874Y992285D03*
X451173D03*
X447472D03*
X443771D03*
X452354Y1046143D03*
X448653D03*
X444952D03*
X454204Y1049332D03*
X450504D03*
X446803D03*
X452354Y1052521D03*
X448653D03*
X444952D03*
X454204Y1055710D03*
X450504D03*
X446803D03*
X452354Y1058899D03*
X448653D03*
X444952D03*
X454204Y1062088D03*
X450504D03*
X446803D03*
X452354Y1065277D03*
X448653D03*
X444952D03*
X454204Y1068466D03*
X450504D03*
X446803D03*
X452354Y1071655D03*
X448653D03*
X444952D03*
X454204Y1074844D03*
X450504D03*
X446803D03*
X452354Y1078033D03*
X448653D03*
X444952D03*
X454204Y1081222D03*
X450504D03*
X446803D03*
X452354Y1084411D03*
X448653D03*
X444952D03*
X454204Y1087600D03*
X450504D03*
X446803D03*
X452354Y1090789D03*
X448653D03*
X444952D03*
X454204Y1093978D03*
X450504D03*
X446803D03*
X452354Y1097167D03*
X448653D03*
X444952D03*
X454204Y1100356D03*
X450504D03*
X446803D03*
X452354Y1103545D03*
X448653D03*
X444952D03*
X454204Y1106734D03*
X450504D03*
X446803D03*
X452354Y1109923D03*
X448653D03*
X444952D03*
X454204Y1113112D03*
X450504D03*
X446803D03*
X452354Y1116301D03*
X448653D03*
X444952D03*
X454204Y1119490D03*
X450504D03*
X446803D03*
X452354Y1122679D03*
X448653D03*
X444952D03*
X454204Y1125868D03*
X450504D03*
X446803D03*
X452354Y1129057D03*
X448653D03*
X444952D03*
X454204Y1132246D03*
X450504D03*
X446803D03*
X452354Y1135434D03*
X448653D03*
X444952D03*
X454204Y1138623D03*
X450504D03*
X446803D03*
X452354Y1141812D03*
X448653D03*
X444952D03*
X454204Y1145001D03*
X450504D03*
X446803D03*
X452354Y1148190D03*
X448653D03*
X444952D03*
X454204Y1151379D03*
X450504D03*
X446803D03*
X452354Y1154568D03*
X448653D03*
X444952D03*
X454204Y1157757D03*
X450504D03*
X446803D03*
X452354Y1160946D03*
X448653D03*
X444952D03*
X454204Y1164135D03*
X450504D03*
X464126Y874293D03*
X460425D03*
X456724D03*
X469677Y877482D03*
X465976D03*
X462275D03*
X458574D03*
X467826Y880671D03*
X464126D03*
X460425D03*
X456724D03*
X469677Y883860D03*
X465976D03*
X462275D03*
X458574D03*
X467826Y887049D03*
X464126D03*
X460425D03*
X456724D03*
X469677Y890238D03*
X465976D03*
X462275D03*
X458574D03*
X467826Y893427D03*
X464126D03*
X460425D03*
X456724D03*
X469677Y896616D03*
X465976D03*
X462275D03*
X458574D03*
X467826Y899805D03*
X464126D03*
X460425D03*
X456724D03*
X469677Y902994D03*
X465976D03*
X462275D03*
X458574D03*
X467826Y906182D03*
X464126D03*
X460425D03*
X456724D03*
X469677Y909371D03*
X465976D03*
X462275D03*
X458574D03*
X467826Y912560D03*
X464126D03*
X460425D03*
X456724D03*
X469677Y915749D03*
X465976D03*
X462275D03*
X458574D03*
X467826Y918938D03*
X464126D03*
X460425D03*
X456724D03*
X469677Y922127D03*
X465976D03*
X462275D03*
X458574D03*
X467826Y925316D03*
X464126D03*
X460425D03*
X456724D03*
X469677Y928505D03*
X465976D03*
X462275D03*
X458574D03*
X467826Y931694D03*
X464126D03*
X460425D03*
X456724D03*
X469677Y934883D03*
X465976D03*
X462275D03*
X458574D03*
X467826Y938072D03*
X464126D03*
X460425D03*
X456724D03*
X469677Y941261D03*
X465976D03*
X462275D03*
X458574D03*
X467826Y944450D03*
X464126D03*
X460425D03*
X456724D03*
X469677Y947639D03*
X465976D03*
X462275D03*
X458574D03*
X467826Y950828D03*
X464126D03*
X460425D03*
X456724D03*
X469677Y954017D03*
X465976D03*
X462275D03*
X458574D03*
X467826Y957206D03*
X464126D03*
X460425D03*
X456724D03*
X469677Y960395D03*
X465976D03*
X462275D03*
X458574D03*
X467826Y963584D03*
X464126D03*
X460425D03*
X456724D03*
X469677Y966773D03*
X465976D03*
X462275D03*
X458574D03*
X467826Y969962D03*
X464126D03*
X460425D03*
X456724D03*
X469677Y973151D03*
X465976D03*
X462275D03*
X458574D03*
X467826Y976340D03*
X464126D03*
X460425D03*
X456724D03*
X469677Y979529D03*
X465976D03*
X462275D03*
X458574D03*
X467826Y982718D03*
X464126D03*
X460425D03*
X456724D03*
X469677Y985907D03*
X465976D03*
X462275D03*
X458574D03*
X467826Y989096D03*
X464126D03*
X460425D03*
X456724D03*
X469677Y992285D03*
X465976D03*
X462275D03*
X458574D03*
X467157Y1046143D03*
X463456D03*
X459755D03*
X456055D03*
X469007Y1049332D03*
X465307D03*
X461606D03*
X457905D03*
X467157Y1052521D03*
X463456D03*
X459755D03*
X456055D03*
X469007Y1055710D03*
X465307D03*
X461606D03*
X457905D03*
X467157Y1058899D03*
X463456D03*
X459755D03*
X456055D03*
X469007Y1062088D03*
X465307D03*
X461606D03*
X457905D03*
X467157Y1065277D03*
X463456D03*
X459755D03*
X456055D03*
X469007Y1068466D03*
X465307D03*
X461606D03*
X457905D03*
X467157Y1071655D03*
X463456D03*
X459755D03*
X456055D03*
X469007Y1074844D03*
X465307D03*
X461606D03*
X457905D03*
X467157Y1078033D03*
X463456D03*
X459755D03*
X456055D03*
X469007Y1081222D03*
X465307D03*
X461606D03*
X457905D03*
X467157Y1084411D03*
X463456D03*
X459755D03*
X456055D03*
X469007Y1087600D03*
X465307D03*
X461606D03*
X457905D03*
X467157Y1090789D03*
X463456D03*
X459755D03*
X456055D03*
X469007Y1093978D03*
X465307D03*
X461606D03*
X457905D03*
X467157Y1097167D03*
X463456D03*
X459755D03*
X456055D03*
X469007Y1100356D03*
X465307D03*
X461606D03*
X457905D03*
X467157Y1103545D03*
X463456D03*
X459755D03*
X456055D03*
X469007Y1106734D03*
X465307D03*
X461606D03*
X457905D03*
X467157Y1109923D03*
X463456D03*
X459755D03*
X456055D03*
X469007Y1113112D03*
X465307D03*
X461606D03*
X457905D03*
X467157Y1116301D03*
X463456D03*
X459755D03*
X456055D03*
X469007Y1119490D03*
X465307D03*
X461606D03*
X457905D03*
X467157Y1122679D03*
X463456D03*
X459755D03*
X456055D03*
X469007Y1125868D03*
X465307D03*
X461606D03*
X457905D03*
X467157Y1129057D03*
X463456D03*
X459755D03*
X456055D03*
X469007Y1132246D03*
X465307D03*
X461606D03*
X457905D03*
X467157Y1135434D03*
X463456D03*
X459755D03*
X456055D03*
X469007Y1138623D03*
X465307D03*
X461606D03*
X457905D03*
X467157Y1141812D03*
X463456D03*
X459755D03*
X456055D03*
X469007Y1145001D03*
X465307D03*
X461606D03*
X457905D03*
X467157Y1148190D03*
X463456D03*
X459755D03*
X456055D03*
X469007Y1151379D03*
X465307D03*
X461606D03*
X457905D03*
X467157Y1154568D03*
X463456D03*
X459755D03*
X456055D03*
X469007Y1157757D03*
X465307D03*
X461606D03*
X457905D03*
X467157Y1160946D03*
X463456D03*
X459755D03*
X456055D03*
X465307Y1164135D03*
X461606D03*
X457905D03*
X482629Y874293D03*
X478929D03*
X475228D03*
X471527D03*
X484480Y877482D03*
X480779D03*
X477078D03*
X473378D03*
X482629Y880671D03*
X478929D03*
X475228D03*
X471527D03*
X484480Y883860D03*
X480779D03*
X477078D03*
X473378D03*
X482629Y887049D03*
X478929D03*
X475228D03*
X471527D03*
X484480Y890238D03*
X480779D03*
X477078D03*
X473378D03*
X482629Y893427D03*
X478929D03*
X475228D03*
X471527D03*
X484480Y896616D03*
X480779D03*
X477078D03*
X473378D03*
X482629Y899805D03*
X478929D03*
X475228D03*
X471527D03*
X484480Y902994D03*
X480779D03*
X477078D03*
X473378D03*
X482629Y906182D03*
X478929D03*
X475228D03*
X471527D03*
X484480Y909371D03*
X480779D03*
X477078D03*
X473378D03*
X482629Y912560D03*
X478929D03*
X475228D03*
X471527D03*
X484480Y915749D03*
X480779D03*
X477078D03*
X473378D03*
X482629Y918938D03*
X478929D03*
X475228D03*
X471527D03*
X484480Y922127D03*
X480779D03*
X477078D03*
X473378D03*
X482629Y925316D03*
X478929D03*
X475228D03*
X471527D03*
X484480Y928505D03*
X480779D03*
X477078D03*
X473378D03*
X482629Y931694D03*
X478929D03*
X475228D03*
X471527D03*
X484480Y934883D03*
X480779D03*
X477078D03*
X473378D03*
X482629Y938072D03*
X478929D03*
X475228D03*
X471527D03*
X484480Y941261D03*
X480779D03*
X477078D03*
X473378D03*
X482629Y944450D03*
X478929D03*
X475228D03*
X471527D03*
X484480Y947639D03*
X480779D03*
X477078D03*
X473378D03*
X482629Y950828D03*
X478929D03*
X475228D03*
X471527D03*
X484480Y954017D03*
X480779D03*
X477078D03*
X473378D03*
X482629Y957206D03*
X478929D03*
X475228D03*
X471527D03*
X484480Y960395D03*
X480779D03*
X477078D03*
X473378D03*
X482629Y963584D03*
X478929D03*
X475228D03*
X471527D03*
X484480Y966773D03*
X480779D03*
X477078D03*
X473378D03*
X482629Y969962D03*
X478929D03*
X475228D03*
X471527D03*
X484480Y973151D03*
X480779D03*
X477078D03*
X473378D03*
X482629Y976340D03*
X478929D03*
X475228D03*
X471527D03*
X484480Y979529D03*
X480779D03*
X477078D03*
X473378D03*
X482629Y982718D03*
X478929D03*
X475228D03*
X471527D03*
X484480Y985907D03*
X480779D03*
X477078D03*
X473378D03*
X482629Y989096D03*
X478929D03*
X475228D03*
X471527D03*
X484480Y992285D03*
X480779D03*
X477078D03*
X473378D03*
X482629Y995474D03*
X478929D03*
X475228D03*
X484480Y998663D03*
X480779D03*
X477078D03*
X482629Y1001852D03*
X478929D03*
X475228D03*
X484480Y1005041D03*
X480779D03*
X477078D03*
X482629Y1008230D03*
X478929D03*
X475228D03*
X484480Y1011419D03*
X480779D03*
X477078D03*
X481960Y1027009D03*
X478259D03*
X483811Y1030198D03*
X480110D03*
X476409D03*
X481960Y1033387D03*
X478259D03*
X483811Y1036576D03*
X480110D03*
X476409D03*
X481960Y1039765D03*
X478259D03*
X483811Y1042954D03*
X480110D03*
X476409D03*
X481960Y1046143D03*
X478259D03*
X474559D03*
X470858D03*
X483811Y1049332D03*
X480110D03*
X476409D03*
X472708D03*
X481960Y1052521D03*
X478259D03*
X474559D03*
X470858D03*
X483811Y1055710D03*
X480110D03*
X476409D03*
X472708D03*
X481960Y1058899D03*
X478259D03*
X474559D03*
X470858D03*
X483811Y1062088D03*
X480110D03*
X476409D03*
X472708D03*
X481960Y1065277D03*
X478259D03*
X474559D03*
X470858D03*
X483811Y1068466D03*
X480110D03*
X476409D03*
X472708D03*
X481960Y1071655D03*
X478259D03*
X474559D03*
X470858D03*
X483811Y1074844D03*
X480110D03*
X476409D03*
X472708D03*
X481960Y1078033D03*
X478259D03*
X474559D03*
X470858D03*
X483811Y1081222D03*
X480110D03*
X476409D03*
X472708D03*
X481960Y1084411D03*
X478259D03*
X474559D03*
X470858D03*
X483811Y1087600D03*
X480110D03*
X476409D03*
X472708D03*
X481960Y1090789D03*
X478259D03*
X474559D03*
X470858D03*
X483811Y1093978D03*
X480110D03*
X476409D03*
X472708D03*
X481960Y1097167D03*
X478259D03*
X474559D03*
X470858D03*
X483811Y1100356D03*
X480110D03*
X476409D03*
X472708D03*
X481960Y1103545D03*
X478259D03*
X474559D03*
X470858D03*
X483811Y1106734D03*
X480110D03*
X476409D03*
X472708D03*
X481960Y1109923D03*
X478259D03*
X474559D03*
X470858D03*
X483811Y1113112D03*
X480110D03*
X476409D03*
X472708D03*
X481960Y1116301D03*
X478259D03*
X474559D03*
X470858D03*
X483811Y1119490D03*
X480110D03*
X476409D03*
X472708D03*
X481960Y1122679D03*
X478259D03*
X474559D03*
X470858D03*
X483811Y1125868D03*
X480110D03*
X476409D03*
X472708D03*
X481960Y1129057D03*
X478259D03*
X474559D03*
X470858D03*
X483811Y1132246D03*
X480110D03*
X476409D03*
X472708D03*
X481960Y1135434D03*
X478259D03*
X474559D03*
X470858D03*
X483811Y1138623D03*
X480110D03*
X476409D03*
X472708D03*
X481960Y1141812D03*
X478259D03*
X474559D03*
X470858D03*
X483811Y1145001D03*
X480110D03*
X476409D03*
X472708D03*
X481960Y1148190D03*
X478259D03*
X474559D03*
X470858D03*
X483811Y1151379D03*
X480110D03*
X476409D03*
X472708D03*
X481960Y1154568D03*
X478259D03*
X474559D03*
X470858D03*
X483811Y1157757D03*
X480110D03*
X476409D03*
X472708D03*
X481960Y1160946D03*
X478259D03*
X474559D03*
X470858D03*
X483811Y1164135D03*
X480110D03*
X476409D03*
X472708D03*
X497433Y874293D03*
X493732D03*
X486330D03*
X499283Y877482D03*
X495582D03*
X491881D03*
X488181D03*
X497433Y880671D03*
X493732D03*
X490031D03*
X486330D03*
X499283Y883860D03*
X495582D03*
X491881D03*
X488181D03*
X497433Y887049D03*
X493732D03*
X490031D03*
X486330D03*
X499283Y890238D03*
X495582D03*
X491881D03*
X488181D03*
X497433Y893427D03*
X493732D03*
X490031D03*
X486330D03*
X499283Y896616D03*
X495582D03*
X491881D03*
X488181D03*
X497433Y899805D03*
X493732D03*
X490031D03*
X486330D03*
X499283Y902994D03*
X495582D03*
X491881D03*
X488181D03*
X497433Y906182D03*
X493732D03*
X490031D03*
X486330D03*
X499283Y909371D03*
X495582D03*
X491881D03*
X488181D03*
X497433Y912560D03*
X493732D03*
X490031D03*
X486330D03*
X499283Y915749D03*
X495582D03*
X491881D03*
X488181D03*
X497433Y918938D03*
X493732D03*
X490031D03*
X486330D03*
X499283Y922127D03*
X495582D03*
X491881D03*
X488181D03*
X497433Y925316D03*
X493732D03*
X490031D03*
X486330D03*
X499283Y928505D03*
X495582D03*
X491881D03*
X488181D03*
X497433Y931694D03*
X493732D03*
X490031D03*
X486330D03*
X499283Y934883D03*
X495582D03*
X491881D03*
X488181D03*
X497433Y938072D03*
X493732D03*
X490031D03*
X486330D03*
X499283Y941261D03*
X495582D03*
X491881D03*
X488181D03*
X497433Y944450D03*
X493732D03*
X490031D03*
X486330D03*
X499283Y947639D03*
X495582D03*
X491881D03*
X488181D03*
X497433Y950828D03*
X493732D03*
X490031D03*
X486330D03*
X499283Y954017D03*
X495582D03*
X491881D03*
X488181D03*
X497433Y957206D03*
X493732D03*
X490031D03*
X486330D03*
X499283Y960395D03*
X495582D03*
X491881D03*
X488181D03*
X497433Y963584D03*
X493732D03*
X490031D03*
X486330D03*
X499283Y966773D03*
X495582D03*
X491881D03*
X488181D03*
X497433Y969962D03*
X493732D03*
X490031D03*
X486330D03*
X499283Y973151D03*
X495582D03*
X491881D03*
X488181D03*
X497433Y976340D03*
X493732D03*
X490031D03*
X486330D03*
X499283Y979529D03*
X495582D03*
X491881D03*
X488181D03*
X497433Y982718D03*
X493732D03*
X490031D03*
X486330D03*
X499283Y985907D03*
X495582D03*
X491881D03*
X488181D03*
X497433Y989096D03*
X493732D03*
X490031D03*
X486330D03*
X499283Y992285D03*
X495582D03*
X491881D03*
X488181D03*
X497433Y995474D03*
X493732D03*
X490031D03*
X486330D03*
X499283Y998663D03*
X495582D03*
X491881D03*
X488181D03*
X497433Y1001852D03*
X493732D03*
X490031D03*
X486330D03*
X499283Y1005041D03*
X495582D03*
X491881D03*
X488181D03*
X497433Y1008230D03*
X493732D03*
X490031D03*
X486330D03*
X499283Y1011419D03*
X495582D03*
X491881D03*
X488181D03*
X496763Y1027009D03*
X493063D03*
X489362D03*
X485661D03*
X498614Y1030198D03*
X494913D03*
X491212D03*
X487511D03*
X496763Y1033387D03*
X493063D03*
X489362D03*
X485661D03*
X498614Y1036576D03*
X494913D03*
X491212D03*
X487511D03*
X496763Y1039765D03*
X493063D03*
X489362D03*
X485661D03*
X498614Y1042954D03*
X494913D03*
X491212D03*
X487511D03*
X496763Y1046143D03*
X493063D03*
X489362D03*
X485661D03*
X498614Y1049332D03*
X494913D03*
X491212D03*
X487511D03*
X496763Y1052521D03*
X493063D03*
X489362D03*
X485661D03*
X498614Y1055710D03*
X494913D03*
X491212D03*
X487511D03*
X496763Y1058899D03*
X493063D03*
X489362D03*
X485661D03*
X498614Y1062088D03*
X494913D03*
X491212D03*
X487511D03*
X496763Y1065277D03*
X493063D03*
X489362D03*
X485661D03*
X498614Y1068466D03*
X494913D03*
X491212D03*
X487511D03*
X496763Y1071655D03*
X493063D03*
X489362D03*
X485661D03*
X498614Y1074844D03*
X494913D03*
X491212D03*
X487511D03*
X496763Y1078033D03*
X493063D03*
X489362D03*
X485661D03*
X498614Y1081222D03*
X494913D03*
X491212D03*
X487511D03*
X496763Y1084411D03*
X493063D03*
X489362D03*
X485661D03*
X498614Y1087600D03*
X494913D03*
X491212D03*
X487511D03*
X496763Y1090789D03*
X493063D03*
X489362D03*
X485661D03*
X498614Y1093978D03*
X494913D03*
X491212D03*
X487511D03*
X496763Y1097167D03*
X493063D03*
X489362D03*
X485661D03*
X498614Y1100356D03*
X494913D03*
X491212D03*
X487511D03*
X496763Y1103545D03*
X493063D03*
X489362D03*
X485661D03*
X498614Y1106734D03*
X494913D03*
X491212D03*
X487511D03*
X496763Y1109923D03*
X493063D03*
X489362D03*
X485661D03*
X498614Y1113112D03*
X494913D03*
X491212D03*
X487511D03*
X496763Y1116301D03*
X493063D03*
X489362D03*
X485661D03*
X498614Y1119490D03*
X494913D03*
X491212D03*
X487511D03*
X496763Y1122679D03*
X493063D03*
X489362D03*
X485661D03*
X498614Y1125868D03*
X494913D03*
X491212D03*
X487511D03*
X496763Y1129057D03*
X493063D03*
X489362D03*
X485661D03*
X498614Y1132246D03*
X494913D03*
X491212D03*
X487511D03*
X496763Y1135434D03*
X493063D03*
X489362D03*
X485661D03*
X498614Y1138623D03*
X494913D03*
X491212D03*
X487511D03*
X496763Y1141812D03*
X493063D03*
X489362D03*
X485661D03*
X498614Y1145001D03*
X494913D03*
X491212D03*
X487511D03*
X496763Y1148190D03*
X493063D03*
X489362D03*
X485661D03*
X498614Y1151379D03*
X494913D03*
X491212D03*
X487511D03*
X496763Y1154568D03*
X493063D03*
X489362D03*
X485661D03*
X498614Y1157757D03*
X494913D03*
X491212D03*
X487511D03*
X496763Y1160946D03*
X493063D03*
X489362D03*
X485661D03*
X498614Y1164135D03*
X494913D03*
X487511D03*
X508535Y874293D03*
X504834D03*
X501133D03*
X514086Y877482D03*
X510385D03*
X506685D03*
X502984D03*
X512236Y880671D03*
X508535D03*
X504834D03*
X501133D03*
X514086Y883860D03*
X510385D03*
X506685D03*
X502984D03*
X512236Y887049D03*
X508535D03*
X504834D03*
X501133D03*
X514086Y890238D03*
X510385D03*
X506685D03*
X502984D03*
X512236Y893427D03*
X508535D03*
X504834D03*
X501133D03*
X514086Y896616D03*
X510385D03*
X506685D03*
X502984D03*
X512236Y899805D03*
X508535D03*
X504834D03*
X501133D03*
X514086Y902994D03*
X510385D03*
X506685D03*
X502984D03*
X512236Y906182D03*
X508535D03*
X504834D03*
X501133D03*
X514086Y909371D03*
X510385D03*
X506685D03*
X502984D03*
X512236Y912560D03*
X508535D03*
X504834D03*
X501133D03*
X514086Y915749D03*
X510385D03*
X506685D03*
X502984D03*
X512236Y918938D03*
X508535D03*
X504834D03*
X501133D03*
X514086Y922127D03*
X510385D03*
X506685D03*
X502984D03*
X512236Y925316D03*
X508535D03*
X504834D03*
X501133D03*
X514086Y928505D03*
X510385D03*
X506685D03*
X502984D03*
X512236Y931694D03*
X508535D03*
X504834D03*
X501133D03*
X514086Y934883D03*
X510385D03*
X506685D03*
X502984D03*
X512236Y938072D03*
X508535D03*
X504834D03*
X501133D03*
X514086Y941261D03*
X510385D03*
X506685D03*
X502984D03*
X512236Y944450D03*
X508535D03*
X504834D03*
X501133D03*
X514086Y947639D03*
X510385D03*
X506685D03*
X502984D03*
X512236Y950828D03*
X508535D03*
X504834D03*
X501133D03*
X514086Y954017D03*
X510385D03*
X506685D03*
X502984D03*
X512236Y957206D03*
X508535D03*
X504834D03*
X501133D03*
X514086Y960395D03*
X510385D03*
X506685D03*
X502984D03*
X512236Y963584D03*
X508535D03*
X504834D03*
X501133D03*
X514086Y966773D03*
X510385D03*
X506685D03*
X502984D03*
X512236Y969962D03*
X508535D03*
X504834D03*
X501133D03*
X514086Y973151D03*
X510385D03*
X506685D03*
X502984D03*
X512236Y976340D03*
X508535D03*
X504834D03*
X501133D03*
X514086Y979529D03*
X510385D03*
X506685D03*
X502984D03*
X512236Y982718D03*
X508535D03*
X504834D03*
X501133D03*
X514086Y985907D03*
X510385D03*
X506685D03*
X502984D03*
X512236Y989096D03*
X508535D03*
X504834D03*
X501133D03*
X514086Y992285D03*
X510385D03*
X506685D03*
X502984D03*
X512236Y995474D03*
X508535D03*
X504834D03*
X501133D03*
X514086Y998663D03*
X510385D03*
X506685D03*
X502984D03*
X512236Y1001852D03*
X508535D03*
X504834D03*
X501133D03*
X514086Y1005041D03*
X510385D03*
X506685D03*
X502984D03*
X512236Y1008230D03*
X508535D03*
X504834D03*
X501133D03*
X514086Y1011419D03*
X510385D03*
X506685D03*
X502984D03*
X511567Y1027009D03*
X507866D03*
X504165D03*
X500464D03*
X513417Y1030198D03*
X509716D03*
X506015D03*
X502315D03*
X511567Y1033387D03*
X507866D03*
X504165D03*
X500464D03*
X513417Y1036576D03*
X509716D03*
X506015D03*
X502315D03*
X511567Y1039765D03*
X507866D03*
X504165D03*
X500464D03*
X513417Y1042954D03*
X509716D03*
X506015D03*
X502315D03*
X511567Y1046143D03*
X507866D03*
X504165D03*
X500464D03*
X513417Y1049332D03*
X509716D03*
X506015D03*
X502315D03*
X511567Y1052521D03*
X507866D03*
X504165D03*
X500464D03*
X513417Y1055710D03*
X509716D03*
X506015D03*
X502315D03*
X511567Y1058899D03*
X507866D03*
X504165D03*
X500464D03*
X513417Y1062088D03*
X509716D03*
X506015D03*
X502315D03*
X511567Y1065277D03*
X507866D03*
X504165D03*
X500464D03*
X513417Y1068466D03*
X509716D03*
X506015D03*
X502315D03*
X511567Y1071655D03*
X507866D03*
X504165D03*
X500464D03*
X513417Y1074844D03*
X509716D03*
X506015D03*
X502315D03*
X511567Y1078033D03*
X507866D03*
X504165D03*
X500464D03*
X513417Y1081222D03*
X509716D03*
X506015D03*
X502315D03*
X511567Y1084411D03*
X507866D03*
X504165D03*
X500464D03*
X513417Y1087600D03*
X509716D03*
X506015D03*
X502315D03*
X511567Y1090789D03*
X507866D03*
X504165D03*
X500464D03*
X513417Y1093978D03*
X509716D03*
X506015D03*
X502315D03*
X511567Y1097167D03*
X507866D03*
X504165D03*
X500464D03*
X513417Y1100356D03*
X509716D03*
X506015D03*
X502315D03*
X511567Y1103545D03*
X507866D03*
X504165D03*
X500464D03*
X513417Y1106734D03*
X509716D03*
X506015D03*
X502315D03*
X511567Y1109923D03*
X507866D03*
X504165D03*
X500464D03*
X513417Y1113112D03*
X509716D03*
X506015D03*
X502315D03*
X511567Y1116301D03*
X507866D03*
X504165D03*
X500464D03*
X513417Y1119490D03*
X509716D03*
X506015D03*
X502315D03*
X511567Y1122679D03*
X507866D03*
X504165D03*
X500464D03*
X513417Y1125868D03*
X509716D03*
X506015D03*
X502315D03*
X511567Y1129057D03*
X507866D03*
X504165D03*
X500464D03*
X513417Y1132246D03*
X509716D03*
X506015D03*
X502315D03*
X511567Y1135434D03*
X507866D03*
X504165D03*
X500464D03*
X513417Y1138623D03*
X509716D03*
X506015D03*
X502315D03*
X511567Y1141812D03*
X507866D03*
X504165D03*
X500464D03*
X513417Y1145001D03*
X509716D03*
X506015D03*
X502315D03*
X511567Y1148190D03*
X507866D03*
X504165D03*
X500464D03*
X513417Y1151379D03*
X509716D03*
X506015D03*
X502315D03*
X511567Y1154568D03*
X507866D03*
X504165D03*
X500464D03*
X513417Y1157757D03*
X509716D03*
X506015D03*
X502315D03*
X511567Y1160946D03*
X507866D03*
X504165D03*
X500464D03*
X509716Y1164135D03*
X506015D03*
X502315D03*
X527039Y874293D03*
X523338D03*
X519637D03*
X515937D03*
X528889Y877482D03*
X525189D03*
X521488D03*
X517787D03*
X527039Y880671D03*
X523338D03*
X519637D03*
X515937D03*
X528889Y883860D03*
X525189D03*
X521488D03*
X517787D03*
X527039Y887049D03*
X523338D03*
X519637D03*
X515937D03*
X528889Y890238D03*
X525189D03*
X521488D03*
X517787D03*
X527039Y893427D03*
X523338D03*
X519637D03*
X515937D03*
X528889Y896616D03*
X525189D03*
X521488D03*
X517787D03*
X527039Y899805D03*
X523338D03*
X519637D03*
X515937D03*
X528889Y902994D03*
X525189D03*
X521488D03*
X517787D03*
X527039Y906182D03*
X523338D03*
X519637D03*
X515937D03*
X528889Y909371D03*
X525189D03*
X521488D03*
X517787D03*
X527039Y912560D03*
X523338D03*
X519637D03*
X515937D03*
X528889Y915749D03*
X525189D03*
X521488D03*
X517787D03*
X527039Y918938D03*
X523338D03*
X519637D03*
X515937D03*
X528889Y922127D03*
X525189D03*
X521488D03*
X517787D03*
X527039Y925316D03*
X523338D03*
X519637D03*
X515937D03*
X528889Y928505D03*
X525189D03*
X521488D03*
X517787D03*
X527039Y931694D03*
X523338D03*
X519637D03*
X515937D03*
X528889Y934883D03*
X525189D03*
X521488D03*
X517787D03*
X527039Y938072D03*
X523338D03*
X519637D03*
X515937D03*
X528889Y941261D03*
X525189D03*
X521488D03*
X517787D03*
X527039Y944450D03*
X523338D03*
X519637D03*
X515937D03*
X528889Y947639D03*
X525189D03*
X521488D03*
X517787D03*
X527039Y950828D03*
X523338D03*
X519637D03*
X515937D03*
X528889Y954017D03*
X525189D03*
X521488D03*
X517787D03*
X527039Y957206D03*
X523338D03*
X519637D03*
X515937D03*
X528889Y960395D03*
X525189D03*
X521488D03*
X517787D03*
X527039Y963584D03*
X523338D03*
X519637D03*
X515937D03*
X528889Y966773D03*
X525189D03*
X521488D03*
X517787D03*
X527039Y969962D03*
X523338D03*
X519637D03*
X515937D03*
X528889Y973151D03*
X525189D03*
X521488D03*
X517787D03*
X527039Y976340D03*
X523338D03*
X519637D03*
X515937D03*
X528889Y979529D03*
X525189D03*
X521488D03*
X517787D03*
X527039Y982718D03*
X523338D03*
X519637D03*
X515937D03*
X528889Y985907D03*
X525189D03*
X521488D03*
X517787D03*
X527039Y989096D03*
X523338D03*
X519637D03*
X515937D03*
X528889Y992285D03*
X525189D03*
X521488D03*
X517787D03*
X527039Y995474D03*
X523338D03*
X519637D03*
X515937D03*
X528889Y998663D03*
X525189D03*
X521488D03*
X517787D03*
X527039Y1001852D03*
X523338D03*
X519637D03*
X515937D03*
X528889Y1005041D03*
X525189D03*
X521488D03*
X517787D03*
X527039Y1008230D03*
X523338D03*
X519637D03*
X515937D03*
X528889Y1011419D03*
X525189D03*
X521488D03*
X517787D03*
X526370Y1027009D03*
X522669D03*
X518968D03*
X515267D03*
X528220Y1030198D03*
X524519D03*
X520818D03*
X517118D03*
X526370Y1033387D03*
X522669D03*
X518968D03*
X515267D03*
X528220Y1036576D03*
X524519D03*
X520818D03*
X517118D03*
X526370Y1039765D03*
X522669D03*
X518968D03*
X515267D03*
X528220Y1042954D03*
X524519D03*
X520818D03*
X517118D03*
X526370Y1046143D03*
X522669D03*
X518968D03*
X515267D03*
X528220Y1049332D03*
X524519D03*
X520818D03*
X517118D03*
X526370Y1052521D03*
X522669D03*
X518968D03*
X515267D03*
X528220Y1055710D03*
X524519D03*
X520818D03*
X517118D03*
X526370Y1058899D03*
X522669D03*
X518968D03*
X515267D03*
X528220Y1062088D03*
X524519D03*
X520818D03*
X517118D03*
X526370Y1065277D03*
X522669D03*
X518968D03*
X515267D03*
X528220Y1068466D03*
X524519D03*
X520818D03*
X517118D03*
X526370Y1071655D03*
X522669D03*
X518968D03*
X515267D03*
X528220Y1074844D03*
X524519D03*
X520818D03*
X517118D03*
X526370Y1078033D03*
X522669D03*
X518968D03*
X515267D03*
X528220Y1081222D03*
X524519D03*
X520818D03*
X517118D03*
X526370Y1084411D03*
X522669D03*
X518968D03*
X515267D03*
X528220Y1087600D03*
X524519D03*
X520818D03*
X517118D03*
X526370Y1090789D03*
X522669D03*
X518968D03*
X515267D03*
X528220Y1093978D03*
X524519D03*
X520818D03*
X517118D03*
X526370Y1097167D03*
X522669D03*
X518968D03*
X515267D03*
X528220Y1100356D03*
X524519D03*
X520818D03*
X517118D03*
X526370Y1103545D03*
X522669D03*
X518968D03*
X515267D03*
X528220Y1106734D03*
X524519D03*
X520818D03*
X517118D03*
X526370Y1109923D03*
X522669D03*
X518968D03*
X515267D03*
X528220Y1113112D03*
X524519D03*
X520818D03*
X517118D03*
X526370Y1116301D03*
X522669D03*
X518968D03*
X515267D03*
X528220Y1119490D03*
X524519D03*
X520818D03*
X517118D03*
X526370Y1122679D03*
X522669D03*
X518968D03*
X515267D03*
X528220Y1125868D03*
X524519D03*
X520818D03*
X517118D03*
X526370Y1129057D03*
X522669D03*
X518968D03*
X515267D03*
X528220Y1132246D03*
X524519D03*
X520818D03*
X517118D03*
X526370Y1135434D03*
X522669D03*
X518968D03*
X515267D03*
X528220Y1138623D03*
X524519D03*
X520818D03*
X517118D03*
X526370Y1141812D03*
X522669D03*
X518968D03*
X515267D03*
X528220Y1145001D03*
X524519D03*
X520818D03*
X517118D03*
X526370Y1148190D03*
X522669D03*
X518968D03*
X515267D03*
X528220Y1151379D03*
X524519D03*
X520818D03*
X517118D03*
X526370Y1154568D03*
X522669D03*
X518968D03*
X515267D03*
X528220Y1157757D03*
X524519D03*
X520818D03*
X517118D03*
X526370Y1160946D03*
X522669D03*
X518968D03*
X515267D03*
X528220Y1164135D03*
X524519D03*
X520818D03*
X517118D03*
X541842Y874293D03*
X538141D03*
X530740D03*
X543693Y877482D03*
X539992D03*
X536291D03*
X532590D03*
X541842Y880671D03*
X538141D03*
X534441D03*
X530740D03*
X543693Y883860D03*
X539992D03*
X536291D03*
X532590D03*
X541842Y887049D03*
X538141D03*
X534441D03*
X530740D03*
X543693Y890238D03*
X539992D03*
X536291D03*
X532590D03*
X541842Y893427D03*
X538141D03*
X534441D03*
X530740D03*
X543693Y896616D03*
X539992D03*
X536291D03*
X532590D03*
X541842Y899805D03*
X538141D03*
X534441D03*
X530740D03*
X543693Y902994D03*
X539992D03*
X536291D03*
X532590D03*
X541842Y906182D03*
X538141D03*
X534441D03*
X530740D03*
X543693Y909371D03*
X539992D03*
X536291D03*
X532590D03*
X541842Y912560D03*
X538141D03*
X534441D03*
X530740D03*
X543693Y915749D03*
X539992D03*
X536291D03*
X532590D03*
X541842Y918938D03*
X538141D03*
X534441D03*
X530740D03*
X543693Y922127D03*
X539992D03*
X536291D03*
X532590D03*
X541842Y925316D03*
X538141D03*
X534441D03*
X530740D03*
X543693Y928505D03*
X539992D03*
X536291D03*
X532590D03*
X541842Y931694D03*
X538141D03*
X534441D03*
X530740D03*
X543693Y934883D03*
X539992D03*
X536291D03*
X532590D03*
X541842Y938072D03*
X538141D03*
X534441D03*
X530740D03*
X543693Y941261D03*
X539992D03*
X536291D03*
X532590D03*
X541842Y944450D03*
X538141D03*
X534441D03*
X530740D03*
X543693Y947639D03*
X539992D03*
X536291D03*
X532590D03*
X541842Y950828D03*
X538141D03*
X534441D03*
X530740D03*
X543693Y954017D03*
X539992D03*
X536291D03*
X532590D03*
X541842Y957206D03*
X538141D03*
X534441D03*
X530740D03*
X543693Y960395D03*
X539992D03*
X536291D03*
X532590D03*
X541842Y963584D03*
X538141D03*
X534441D03*
X530740D03*
X543693Y966773D03*
X539992D03*
X536291D03*
X532590D03*
X541842Y969962D03*
X538141D03*
X534441D03*
X530740D03*
X543693Y973151D03*
X539992D03*
X536291D03*
X532590D03*
X541842Y976340D03*
X538141D03*
X534441D03*
X530740D03*
X543693Y979529D03*
X539992D03*
X536291D03*
X532590D03*
X541842Y982718D03*
X538141D03*
X534441D03*
X530740D03*
X543693Y985907D03*
X539992D03*
X536291D03*
X532590D03*
X541842Y989096D03*
X538141D03*
X534441D03*
X530740D03*
X543693Y992285D03*
X539992D03*
X536291D03*
X532590D03*
X541842Y995474D03*
X538141D03*
X534441D03*
X530740D03*
X543693Y998663D03*
X539992D03*
X536291D03*
X532590D03*
X541842Y1001852D03*
X538141D03*
X534441D03*
X530740D03*
X543693Y1005041D03*
X539992D03*
X536291D03*
X532590D03*
X541842Y1008230D03*
X538141D03*
X534441D03*
X530740D03*
X543693Y1011419D03*
X539992D03*
X536291D03*
X532590D03*
X541173Y1027009D03*
X537472D03*
X533771D03*
X530070D03*
X543023Y1030198D03*
X539322D03*
X535622D03*
X531921D03*
X541173Y1033387D03*
X537472D03*
X533771D03*
X530070D03*
X543023Y1036576D03*
X539322D03*
X535622D03*
X531921D03*
X541173Y1039765D03*
X537472D03*
X533771D03*
X530070D03*
X543023Y1042954D03*
X539322D03*
X535622D03*
X531921D03*
X541173Y1046143D03*
X537472D03*
X533771D03*
X530070D03*
X543023Y1049332D03*
X539322D03*
X535622D03*
X531921D03*
X541173Y1052521D03*
X537472D03*
X533771D03*
X530070D03*
X543023Y1055710D03*
X539322D03*
X535622D03*
X531921D03*
X541173Y1058899D03*
X537472D03*
X533771D03*
X530070D03*
X543023Y1062088D03*
X539322D03*
X535622D03*
X531921D03*
X541173Y1065277D03*
X537472D03*
X533771D03*
X530070D03*
X543023Y1068466D03*
X539322D03*
X535622D03*
X531921D03*
X541173Y1071655D03*
X537472D03*
X533771D03*
X530070D03*
X543023Y1074844D03*
X539322D03*
X535622D03*
X531921D03*
X541173Y1078033D03*
X537472D03*
X533771D03*
X530070D03*
X543023Y1081222D03*
X539322D03*
X535622D03*
X531921D03*
X541173Y1084411D03*
X537472D03*
X533771D03*
X530070D03*
X543023Y1087600D03*
X539322D03*
X535622D03*
X531921D03*
X541173Y1090789D03*
X537472D03*
X533771D03*
X530070D03*
X543023Y1093978D03*
X539322D03*
X535622D03*
X531921D03*
X541173Y1097167D03*
X537472D03*
X533771D03*
X530070D03*
X543023Y1100356D03*
X539322D03*
X535622D03*
X531921D03*
X541173Y1103545D03*
X537472D03*
X533771D03*
X530070D03*
X543023Y1106734D03*
X539322D03*
X535622D03*
X531921D03*
X541173Y1109923D03*
X537472D03*
X533771D03*
X530070D03*
X543023Y1113112D03*
X539322D03*
X535622D03*
X531921D03*
X541173Y1116301D03*
X537472D03*
X533771D03*
X530070D03*
X543023Y1119490D03*
X539322D03*
X535622D03*
X531921D03*
X541173Y1122679D03*
X537472D03*
X533771D03*
X530070D03*
X543023Y1125868D03*
X539322D03*
X535622D03*
X531921D03*
X541173Y1129057D03*
X537472D03*
X533771D03*
X530070D03*
X543023Y1132246D03*
X539322D03*
X535622D03*
X531921D03*
X541173Y1135434D03*
X537472D03*
X533771D03*
X530070D03*
X543023Y1138623D03*
X539322D03*
X535622D03*
X531921D03*
X541173Y1141812D03*
X537472D03*
X533771D03*
X530070D03*
X543023Y1145001D03*
X539322D03*
X535622D03*
X531921D03*
X541173Y1148190D03*
X537472D03*
X533771D03*
X530070D03*
X543023Y1151379D03*
X539322D03*
X535622D03*
X531921D03*
X541173Y1154568D03*
X537472D03*
X533771D03*
X530070D03*
X543023Y1157757D03*
X539322D03*
X535622D03*
X531921D03*
X541173Y1160946D03*
X537472D03*
X533771D03*
X530070D03*
X543023Y1164135D03*
X539322D03*
X531921D03*
X552944Y874293D03*
X549244D03*
X545543D03*
X558496Y877482D03*
X554795D03*
X551094D03*
X547393D03*
X556645Y880671D03*
X552944D03*
X549244D03*
X545543D03*
X558496Y883860D03*
X554795D03*
X551094D03*
X547393D03*
X556645Y887049D03*
X552944D03*
X549244D03*
X545543D03*
X558496Y890238D03*
X554795D03*
X551094D03*
X547393D03*
X556645Y893427D03*
X552944D03*
X549244D03*
X545543D03*
X558496Y896616D03*
X554795D03*
X551094D03*
X547393D03*
X556645Y899805D03*
X552944D03*
X549244D03*
X545543D03*
X558496Y902994D03*
X554795D03*
X551094D03*
X547393D03*
X556645Y906182D03*
X552944D03*
X549244D03*
X545543D03*
X558496Y909371D03*
X554795D03*
X551094D03*
X547393D03*
X556645Y912560D03*
X552944D03*
X549244D03*
X545543D03*
X558496Y915749D03*
X554795D03*
X551094D03*
X547393D03*
X556645Y918938D03*
X552944D03*
X549244D03*
X545543D03*
X558496Y922127D03*
X554795D03*
X551094D03*
X547393D03*
X556645Y925316D03*
X552944D03*
X549244D03*
X545543D03*
X558496Y928505D03*
X554795D03*
X551094D03*
X547393D03*
X556645Y931694D03*
X552944D03*
X549244D03*
X545543D03*
X558496Y934883D03*
X554795D03*
X551094D03*
X547393D03*
X556645Y938072D03*
X552944D03*
X549244D03*
X545543D03*
X558496Y941261D03*
X554795D03*
X551094D03*
X547393D03*
X556645Y944450D03*
X552944D03*
X549244D03*
X545543D03*
X558496Y947639D03*
X554795D03*
X551094D03*
X547393D03*
X556645Y950828D03*
X552944D03*
X549244D03*
X545543D03*
X558496Y954017D03*
X554795D03*
X551094D03*
X547393D03*
X556645Y957206D03*
X552944D03*
X549244D03*
X545543D03*
X558496Y960395D03*
X554795D03*
X551094D03*
X547393D03*
X556645Y963584D03*
X552944D03*
X549244D03*
X545543D03*
X558496Y966773D03*
X554795D03*
X551094D03*
X547393D03*
X556645Y969962D03*
X552944D03*
X549244D03*
X545543D03*
X558496Y973151D03*
X554795D03*
X551094D03*
X547393D03*
X556645Y976340D03*
X552944D03*
X549244D03*
X545543D03*
X558496Y979529D03*
X554795D03*
X551094D03*
X547393D03*
X556645Y982718D03*
X552944D03*
X549244D03*
X545543D03*
X558496Y985907D03*
X554795D03*
X551094D03*
X547393D03*
X556645Y989096D03*
X552944D03*
X549244D03*
X545543D03*
X558496Y992285D03*
X554795D03*
X551094D03*
X547393D03*
X556645Y995474D03*
X552944D03*
X549244D03*
X545543D03*
X558496Y998663D03*
X554795D03*
X551094D03*
X547393D03*
X556645Y1001852D03*
X552944D03*
X549244D03*
X545543D03*
X558496Y1005041D03*
X554795D03*
X551094D03*
X547393D03*
X556645Y1008230D03*
X552944D03*
X549244D03*
X545543D03*
X558496Y1011419D03*
X554795D03*
X551094D03*
X547393D03*
X555976Y1027009D03*
X552275D03*
X548574D03*
X544874D03*
X557826Y1030198D03*
X554126D03*
X550425D03*
X546724D03*
X555976Y1033387D03*
X552275D03*
X548574D03*
X544874D03*
X557826Y1036576D03*
X554126D03*
X550425D03*
X546724D03*
X555976Y1039765D03*
X552275D03*
X548574D03*
X544874D03*
X557826Y1042954D03*
X554126D03*
X550425D03*
X546724D03*
X555976Y1046143D03*
X552275D03*
X548574D03*
X544874D03*
X557826Y1049332D03*
X554126D03*
X550425D03*
X546724D03*
X555976Y1052521D03*
X552275D03*
X548574D03*
X544874D03*
X557826Y1055710D03*
X554126D03*
X550425D03*
X546724D03*
X555976Y1058899D03*
X552275D03*
X548574D03*
X544874D03*
X557826Y1062088D03*
X554126D03*
X550425D03*
X546724D03*
X555976Y1065277D03*
X552275D03*
X548574D03*
X544874D03*
X557826Y1068466D03*
X554126D03*
X550425D03*
X546724D03*
X555976Y1071655D03*
X552275D03*
X548574D03*
X544874D03*
X557826Y1074844D03*
X554126D03*
X550425D03*
X546724D03*
X555976Y1078033D03*
X552275D03*
X548574D03*
X544874D03*
X557826Y1081222D03*
X554126D03*
X550425D03*
X546724D03*
X555976Y1084411D03*
X552275D03*
X548574D03*
X544874D03*
X557826Y1087600D03*
X554126D03*
X550425D03*
X546724D03*
X555976Y1090789D03*
X552275D03*
X548574D03*
X544874D03*
X557826Y1093978D03*
X554126D03*
X550425D03*
X546724D03*
X555976Y1097167D03*
X552275D03*
X548574D03*
X544874D03*
X557826Y1100356D03*
X554126D03*
X550425D03*
X546724D03*
X555976Y1103545D03*
X552275D03*
X548574D03*
X544874D03*
X557826Y1106734D03*
X554126D03*
X550425D03*
X546724D03*
X555976Y1109923D03*
X552275D03*
X548574D03*
X544874D03*
X557826Y1113112D03*
X554126D03*
X550425D03*
X546724D03*
X555976Y1116301D03*
X552275D03*
X548574D03*
X544874D03*
X557826Y1119490D03*
X554126D03*
X550425D03*
X546724D03*
X555976Y1122679D03*
X552275D03*
X548574D03*
X544874D03*
X557826Y1125868D03*
X554126D03*
X550425D03*
X546724D03*
X555976Y1129057D03*
X552275D03*
X548574D03*
X544874D03*
X557826Y1132246D03*
X554126D03*
X550425D03*
X546724D03*
X555976Y1135434D03*
X552275D03*
X548574D03*
X544874D03*
X557826Y1138623D03*
X554126D03*
X550425D03*
X546724D03*
X555976Y1141812D03*
X552275D03*
X548574D03*
X544874D03*
X557826Y1145001D03*
X554126D03*
X550425D03*
X546724D03*
X555976Y1148190D03*
X552275D03*
X548574D03*
X544874D03*
X557826Y1151379D03*
X554126D03*
X550425D03*
X546724D03*
X555976Y1154568D03*
X552275D03*
X548574D03*
X544874D03*
X557826Y1157757D03*
X554126D03*
X550425D03*
X546724D03*
X555976Y1160946D03*
X552275D03*
X548574D03*
X544874D03*
X554126Y1164135D03*
X550425D03*
X546724D03*
X567748Y874293D03*
X564047D03*
X560346D03*
X569598Y877482D03*
X565897D03*
X562196D03*
X571448Y880671D03*
X567748D03*
X564047D03*
X560346D03*
X573299Y883860D03*
X569598D03*
X565897D03*
X562196D03*
X571448Y887049D03*
X567748D03*
X564047D03*
X560346D03*
X573299Y890238D03*
X569598D03*
X565897D03*
X562196D03*
X571448Y893427D03*
X567748D03*
X564047D03*
X560346D03*
X573299Y896616D03*
X569598D03*
X565897D03*
X562196D03*
X571448Y899805D03*
X567748D03*
X564047D03*
X560346D03*
X573299Y902994D03*
X569598D03*
X565897D03*
X562196D03*
X571448Y906182D03*
X567748D03*
X564047D03*
X560346D03*
X573299Y909371D03*
X569598D03*
X565897D03*
X562196D03*
X571448Y912560D03*
X567748D03*
X564047D03*
X560346D03*
X573299Y915749D03*
X569598D03*
X565897D03*
X562196D03*
X571448Y918938D03*
X567748D03*
X564047D03*
X560346D03*
X573299Y922127D03*
X569598D03*
X565897D03*
X562196D03*
X571448Y925316D03*
X567748D03*
X564047D03*
X560346D03*
X573299Y928505D03*
X569598D03*
X565897D03*
X562196D03*
X571448Y931694D03*
X567748D03*
X564047D03*
X560346D03*
X573299Y934883D03*
X569598D03*
X565897D03*
X562196D03*
X571448Y938072D03*
X567748D03*
X564047D03*
X560346D03*
X573299Y941261D03*
X569598D03*
X565897D03*
X562196D03*
X571448Y944450D03*
X567748D03*
X564047D03*
X560346D03*
X573299Y947639D03*
X569598D03*
X565897D03*
X562196D03*
X571448Y950828D03*
X567748D03*
X564047D03*
X560346D03*
X573299Y954017D03*
X569598D03*
X565897D03*
X562196D03*
X571448Y957206D03*
X567748D03*
X564047D03*
X560346D03*
X573299Y960395D03*
X569598D03*
X565897D03*
X562196D03*
X571448Y963584D03*
X567748D03*
X564047D03*
X560346D03*
X573299Y966773D03*
X569598D03*
X565897D03*
X562196D03*
X571448Y969962D03*
X567748D03*
X564047D03*
X560346D03*
X573299Y973151D03*
X569598D03*
X565897D03*
X562196D03*
X571448Y976340D03*
X567748D03*
X564047D03*
X560346D03*
X573299Y979529D03*
X569598D03*
X565897D03*
X562196D03*
X571448Y982718D03*
X567748D03*
X564047D03*
X560346D03*
X573299Y985907D03*
X569598D03*
X565897D03*
X562196D03*
X571448Y989096D03*
X567748D03*
X564047D03*
X560346D03*
X573299Y992285D03*
X569598D03*
X565897D03*
X562196D03*
X571448Y995474D03*
X567748D03*
X564047D03*
X560346D03*
X573299Y998663D03*
X569598D03*
X565897D03*
X562196D03*
X571448Y1001852D03*
X567748D03*
X564047D03*
X560346D03*
X573299Y1005041D03*
X569598D03*
X565897D03*
X562196D03*
X571448Y1008230D03*
X567748D03*
X564047D03*
X560346D03*
X573299Y1011419D03*
X569598D03*
X565897D03*
X562196D03*
X570779Y1027009D03*
X567078D03*
X563378D03*
X559677D03*
X572629Y1030198D03*
X568929D03*
X565228D03*
X561527D03*
X570779Y1033387D03*
X567078D03*
X563378D03*
X559677D03*
X572629Y1036576D03*
X568929D03*
X565228D03*
X561527D03*
X570779Y1039765D03*
X567078D03*
X563378D03*
X559677D03*
X572629Y1042954D03*
X568929D03*
X565228D03*
X561527D03*
X570779Y1046143D03*
X567078D03*
X563378D03*
X559677D03*
X572629Y1049332D03*
X568929D03*
X565228D03*
X561527D03*
X570779Y1052521D03*
X567078D03*
X563378D03*
X559677D03*
X572629Y1055710D03*
X568929D03*
X565228D03*
X561527D03*
X570779Y1058899D03*
X567078D03*
X563378D03*
X559677D03*
X572629Y1062088D03*
X568929D03*
X565228D03*
X561527D03*
X570779Y1065277D03*
X567078D03*
X563378D03*
X559677D03*
X572629Y1068466D03*
X568929D03*
X565228D03*
X561527D03*
X570779Y1071655D03*
X567078D03*
X563378D03*
X559677D03*
X572629Y1074844D03*
X568929D03*
X565228D03*
X561527D03*
X570779Y1078033D03*
X567078D03*
X563378D03*
X559677D03*
X572629Y1081222D03*
X568929D03*
X565228D03*
X561527D03*
X570779Y1084411D03*
X567078D03*
X563378D03*
X559677D03*
X572629Y1087600D03*
X568929D03*
X565228D03*
X561527D03*
X570779Y1090789D03*
X567078D03*
X563378D03*
X559677D03*
X572629Y1093978D03*
X568929D03*
X565228D03*
X561527D03*
X570779Y1097167D03*
X567078D03*
X563378D03*
X559677D03*
X572629Y1100356D03*
X568929D03*
X565228D03*
X561527D03*
X570779Y1103545D03*
X567078D03*
X563378D03*
X559677D03*
X572629Y1106734D03*
X568929D03*
X565228D03*
X561527D03*
X570779Y1109923D03*
X567078D03*
X563378D03*
X559677D03*
X572629Y1113112D03*
X568929D03*
X565228D03*
X561527D03*
X570779Y1116301D03*
X567078D03*
X563378D03*
X559677D03*
X572629Y1119490D03*
X568929D03*
X565228D03*
X561527D03*
X570779Y1122679D03*
X567078D03*
X563378D03*
X559677D03*
X572629Y1125868D03*
X568929D03*
X565228D03*
X561527D03*
X570779Y1129057D03*
X567078D03*
X563378D03*
X559677D03*
X572629Y1132246D03*
X568929D03*
X565228D03*
X561527D03*
X570779Y1135434D03*
X567078D03*
X563378D03*
X559677D03*
X572629Y1138623D03*
X568929D03*
X565228D03*
X561527D03*
X570779Y1141812D03*
X567078D03*
X563378D03*
X559677D03*
X572629Y1145001D03*
X568929D03*
X565228D03*
X561527D03*
X570779Y1148190D03*
X567078D03*
X563378D03*
X559677D03*
X572629Y1151379D03*
X568929D03*
X565228D03*
X561527D03*
X570779Y1154568D03*
X567078D03*
X563378D03*
X559677D03*
X572629Y1157757D03*
X568929D03*
X565228D03*
X561527D03*
X570779Y1160946D03*
X567078D03*
X563378D03*
X559677D03*
X568929Y1164135D03*
X565228D03*
X561527D03*
X575149Y880671D03*
Y887049D03*
Y893427D03*
Y899805D03*
Y906182D03*
Y912560D03*
Y918938D03*
Y925316D03*
Y931694D03*
Y938072D03*
Y944450D03*
Y950828D03*
Y957206D03*
Y963584D03*
Y969962D03*
Y976340D03*
Y982718D03*
Y989096D03*
Y995474D03*
Y1001852D03*
Y1008230D03*
X574480Y1027009D03*
X576330Y1030198D03*
X574480Y1033387D03*
X576330Y1036576D03*
X574480Y1039765D03*
X576330Y1042954D03*
X574480Y1046143D03*
X576330Y1049332D03*
X574480Y1052521D03*
X576330Y1055710D03*
X574480Y1058899D03*
X576330Y1062088D03*
X574480Y1065277D03*
X576330Y1068466D03*
X574480Y1071655D03*
X576330Y1074844D03*
X574480Y1078033D03*
X576330Y1081222D03*
X574480Y1084411D03*
X576330Y1087600D03*
X574480Y1090789D03*
X576330Y1093978D03*
X574480Y1097167D03*
X576330Y1100356D03*
X574480Y1103545D03*
X576330Y1106734D03*
X574480Y1109923D03*
X576330Y1113112D03*
X574480Y1116301D03*
X576330Y1119490D03*
X574480Y1122679D03*
X576330Y1125868D03*
X574480Y1129057D03*
X576330Y1132246D03*
X574480Y1135434D03*
X576330Y1138623D03*
X574480Y1141812D03*
X576330Y1145001D03*
X574480Y1148190D03*
X576330Y1151379D03*
X574480Y1154568D03*
X576330Y1157757D03*
X1288535Y874292D03*
X1286685Y877481D03*
X1288535Y880670D03*
X1284835D03*
X1281134D03*
X1286685Y883859D03*
X1282984D03*
X1288535Y887048D03*
X1284835D03*
X1281134D03*
X1286685Y890237D03*
X1282984D03*
X1288535Y893426D03*
X1284835D03*
X1281134D03*
X1286685Y896615D03*
X1282984D03*
X1288535Y899804D03*
X1284835D03*
X1281134D03*
X1286685Y902993D03*
X1282984D03*
X1288535Y906181D03*
X1284835D03*
X1281134D03*
X1286685Y909370D03*
X1282984D03*
X1288535Y912559D03*
X1284835D03*
X1281134D03*
X1286685Y915748D03*
X1282984D03*
X1288535Y918937D03*
X1284835D03*
X1281134D03*
X1286685Y922126D03*
X1282984D03*
X1288535Y925315D03*
X1284835D03*
X1281134D03*
X1286685Y928504D03*
X1282984D03*
X1288535Y931693D03*
X1284835D03*
X1281134D03*
X1286685Y934882D03*
X1282984D03*
X1288535Y938071D03*
X1284835D03*
X1281134D03*
X1286685Y941260D03*
X1282984D03*
X1288535Y944449D03*
X1284835D03*
X1281134D03*
X1286685Y947638D03*
X1282984D03*
X1288535Y950827D03*
X1284835D03*
X1281134D03*
X1286685Y954016D03*
X1282984D03*
X1288535Y957205D03*
X1284835D03*
X1281134D03*
X1286685Y960394D03*
X1282984D03*
X1288535Y963583D03*
X1284835D03*
X1281134D03*
X1286685Y966772D03*
X1282984D03*
X1288535Y969961D03*
X1284835D03*
X1281134D03*
X1286685Y973150D03*
X1282984D03*
X1288535Y976339D03*
X1284835D03*
X1281134D03*
X1286685Y979528D03*
X1282984D03*
X1288535Y982717D03*
X1284835D03*
X1281134D03*
X1286685Y985906D03*
X1282984D03*
X1288535Y989095D03*
X1284835D03*
X1281134D03*
X1286685Y992284D03*
X1282984D03*
X1288535Y995473D03*
X1284835D03*
X1281134D03*
X1286685Y998662D03*
X1282984D03*
X1288535Y1001851D03*
X1284835D03*
X1281134D03*
X1286685Y1005040D03*
X1282984D03*
X1288535Y1008229D03*
X1284835D03*
X1281134D03*
X1286685Y1011418D03*
X1282984D03*
X1287866Y1027008D03*
X1284165D03*
X1289716Y1030197D03*
X1286016D03*
X1282315D03*
X1287866Y1033386D03*
X1284165D03*
X1289716Y1036575D03*
X1286016D03*
X1282315D03*
X1287866Y1039764D03*
X1284165D03*
X1289716Y1042953D03*
X1286016D03*
X1282315D03*
X1287866Y1046142D03*
X1284165D03*
X1289716Y1049331D03*
X1286016D03*
X1282315D03*
X1287866Y1052520D03*
X1284165D03*
X1289716Y1055709D03*
X1286016D03*
X1282315D03*
X1287866Y1058898D03*
X1284165D03*
X1289716Y1062087D03*
X1286016D03*
X1282315D03*
X1287866Y1065276D03*
X1284165D03*
X1289716Y1068465D03*
X1286016D03*
X1282315D03*
X1287866Y1071654D03*
X1284165D03*
X1289716Y1074843D03*
X1286016D03*
X1282315D03*
X1287866Y1078032D03*
X1284165D03*
X1289716Y1081221D03*
X1286016D03*
X1282315D03*
X1287866Y1084410D03*
X1284165D03*
X1289716Y1087599D03*
X1286016D03*
X1282315D03*
X1287866Y1090788D03*
X1284165D03*
X1289716Y1093977D03*
X1286016D03*
X1282315D03*
X1287866Y1097166D03*
X1284165D03*
X1289716Y1100355D03*
X1286016D03*
X1282315D03*
X1287866Y1103544D03*
X1284165D03*
X1289716Y1106733D03*
X1286016D03*
X1282315D03*
X1287866Y1109922D03*
X1284165D03*
X1289716Y1113111D03*
X1286016D03*
X1282315D03*
X1287866Y1116300D03*
X1284165D03*
X1289716Y1119489D03*
X1286016D03*
X1282315D03*
X1287866Y1122678D03*
X1284165D03*
X1289716Y1125867D03*
X1286016D03*
X1282315D03*
X1287866Y1129056D03*
X1284165D03*
X1289716Y1132245D03*
X1286016D03*
X1282315D03*
X1287866Y1135433D03*
X1284165D03*
X1289716Y1138622D03*
X1286016D03*
X1282315D03*
X1287866Y1141811D03*
X1284165D03*
X1289716Y1145000D03*
X1286016D03*
X1282315D03*
X1287866Y1148189D03*
X1284165D03*
X1289716Y1151378D03*
X1286016D03*
X1282315D03*
X1287866Y1154567D03*
X1284165D03*
X1289716Y1157756D03*
X1286016D03*
X1282315D03*
X1287866Y1160945D03*
X1289716Y1164134D03*
X1303338Y874292D03*
X1295937D03*
X1292236D03*
X1301488Y877481D03*
X1297787D03*
X1294086D03*
X1290386D03*
X1303338Y880670D03*
X1299638D03*
X1295937D03*
X1292236D03*
X1301488Y883859D03*
X1297787D03*
X1294086D03*
X1290386D03*
X1303338Y887048D03*
X1299638D03*
X1295937D03*
X1292236D03*
X1301488Y890237D03*
X1297787D03*
X1294086D03*
X1290386D03*
X1303338Y893426D03*
X1299638D03*
X1295937D03*
X1292236D03*
X1301488Y896615D03*
X1297787D03*
X1294086D03*
X1290386D03*
X1303338Y899804D03*
X1299638D03*
X1295937D03*
X1292236D03*
X1301488Y902993D03*
X1297787D03*
X1294086D03*
X1290386D03*
X1303338Y906181D03*
X1299638D03*
X1295937D03*
X1292236D03*
X1301488Y909370D03*
X1297787D03*
X1294086D03*
X1290386D03*
X1303338Y912559D03*
X1299638D03*
X1295937D03*
X1292236D03*
X1301488Y915748D03*
X1297787D03*
X1294086D03*
X1290386D03*
X1303338Y918937D03*
X1299638D03*
X1295937D03*
X1292236D03*
X1301488Y922126D03*
X1297787D03*
X1294086D03*
X1290386D03*
X1303338Y925315D03*
X1299638D03*
X1295937D03*
X1292236D03*
X1301488Y928504D03*
X1297787D03*
X1294086D03*
X1290386D03*
X1303338Y931693D03*
X1299638D03*
X1295937D03*
X1292236D03*
X1301488Y934882D03*
X1297787D03*
X1294086D03*
X1290386D03*
X1303338Y938071D03*
X1299638D03*
X1295937D03*
X1292236D03*
X1301488Y941260D03*
X1297787D03*
X1294086D03*
X1290386D03*
X1303338Y944449D03*
X1299638D03*
X1295937D03*
X1292236D03*
X1301488Y947638D03*
X1297787D03*
X1294086D03*
X1290386D03*
X1303338Y950827D03*
X1299638D03*
X1295937D03*
X1292236D03*
X1301488Y954016D03*
X1297787D03*
X1294086D03*
X1290386D03*
X1303338Y957205D03*
X1299638D03*
X1295937D03*
X1292236D03*
X1301488Y960394D03*
X1297787D03*
X1294086D03*
X1290386D03*
X1303338Y963583D03*
X1299638D03*
X1295937D03*
X1292236D03*
X1301488Y966772D03*
X1297787D03*
X1294086D03*
X1290386D03*
X1303338Y969961D03*
X1299638D03*
X1295937D03*
X1292236D03*
X1301488Y973150D03*
X1297787D03*
X1294086D03*
X1290386D03*
X1303338Y976339D03*
X1299638D03*
X1295937D03*
X1292236D03*
X1301488Y979528D03*
X1297787D03*
X1294086D03*
X1290386D03*
X1303338Y982717D03*
X1299638D03*
X1295937D03*
X1292236D03*
X1301488Y985906D03*
X1297787D03*
X1294086D03*
X1290386D03*
X1303338Y989095D03*
X1299638D03*
X1295937D03*
X1292236D03*
X1301488Y992284D03*
X1297787D03*
X1294086D03*
X1290386D03*
X1303338Y995473D03*
X1299638D03*
X1295937D03*
X1292236D03*
X1301488Y998662D03*
X1297787D03*
X1294086D03*
X1290386D03*
X1303338Y1001851D03*
X1299638D03*
X1295937D03*
X1292236D03*
X1301488Y1005040D03*
X1297787D03*
X1294086D03*
X1290386D03*
X1303338Y1008229D03*
X1299638D03*
X1295937D03*
X1292236D03*
X1301488Y1011418D03*
X1297787D03*
X1294086D03*
X1290386D03*
X1302669Y1027008D03*
X1298968D03*
X1295268D03*
X1291567D03*
X1304520Y1030197D03*
X1300819D03*
X1297118D03*
X1293417D03*
X1302669Y1033386D03*
X1298968D03*
X1295268D03*
X1291567D03*
X1304520Y1036575D03*
X1300819D03*
X1297118D03*
X1293417D03*
X1302669Y1039764D03*
X1298968D03*
X1295268D03*
X1291567D03*
X1304520Y1042953D03*
X1300819D03*
X1297118D03*
X1293417D03*
X1302669Y1046142D03*
X1298968D03*
X1295268D03*
X1291567D03*
X1304520Y1049331D03*
X1300819D03*
X1297118D03*
X1293417D03*
X1302669Y1052520D03*
X1298968D03*
X1295268D03*
X1291567D03*
X1304520Y1055709D03*
X1300819D03*
X1297118D03*
X1293417D03*
X1302669Y1058898D03*
X1298968D03*
X1295268D03*
X1291567D03*
X1304520Y1062087D03*
X1300819D03*
X1297118D03*
X1293417D03*
X1302669Y1065276D03*
X1298968D03*
X1295268D03*
X1291567D03*
X1304520Y1068465D03*
X1300819D03*
X1297118D03*
X1293417D03*
X1302669Y1071654D03*
X1298968D03*
X1295268D03*
X1291567D03*
X1304520Y1074843D03*
X1300819D03*
X1297118D03*
X1293417D03*
X1302669Y1078032D03*
X1298968D03*
X1295268D03*
X1291567D03*
X1304520Y1081221D03*
X1300819D03*
X1297118D03*
X1293417D03*
X1302669Y1084410D03*
X1298968D03*
X1295268D03*
X1291567D03*
X1304520Y1087599D03*
X1300819D03*
X1297118D03*
X1293417D03*
X1302669Y1090788D03*
X1298968D03*
X1295268D03*
X1291567D03*
X1304520Y1093977D03*
X1300819D03*
X1297118D03*
X1293417D03*
X1302669Y1097166D03*
X1298968D03*
X1295268D03*
X1291567D03*
X1304520Y1100355D03*
X1300819D03*
X1297118D03*
X1293417D03*
X1302669Y1103544D03*
X1298968D03*
X1295268D03*
X1291567D03*
X1304520Y1106733D03*
X1300819D03*
X1297118D03*
X1293417D03*
X1302669Y1109922D03*
X1298968D03*
X1295268D03*
X1291567D03*
X1304520Y1113111D03*
X1300819D03*
X1297118D03*
X1293417D03*
X1302669Y1116300D03*
X1298968D03*
X1295268D03*
X1291567D03*
X1304520Y1119489D03*
X1300819D03*
X1297118D03*
X1293417D03*
X1302669Y1122678D03*
X1298968D03*
X1295268D03*
X1291567D03*
X1304520Y1125867D03*
X1300819D03*
X1297118D03*
X1293417D03*
X1302669Y1129056D03*
X1298968D03*
X1295268D03*
X1291567D03*
X1304520Y1132245D03*
X1300819D03*
X1297118D03*
X1293417D03*
X1302669Y1135433D03*
X1298968D03*
X1295268D03*
X1291567D03*
X1304520Y1138622D03*
X1300819D03*
X1297118D03*
X1293417D03*
X1302669Y1141811D03*
X1298968D03*
X1295268D03*
X1291567D03*
X1304520Y1145000D03*
X1300819D03*
X1297118D03*
X1293417D03*
X1302669Y1148189D03*
X1298968D03*
X1295268D03*
X1291567D03*
X1304520Y1151378D03*
X1300819D03*
X1297118D03*
X1293417D03*
X1302669Y1154567D03*
X1298968D03*
X1295268D03*
X1291567D03*
X1304520Y1157756D03*
X1300819D03*
X1297118D03*
X1293417D03*
X1302669Y1160945D03*
X1298968D03*
X1295268D03*
X1291567D03*
X1304520Y1164134D03*
X1297118D03*
X1293417D03*
X1318142Y874292D03*
X1314441D03*
X1310740D03*
X1307039D03*
X1316291Y877481D03*
X1312590D03*
X1308890D03*
X1305189D03*
X1318142Y880670D03*
X1314441D03*
X1310740D03*
X1307039D03*
X1316291Y883859D03*
X1312590D03*
X1308890D03*
X1305189D03*
X1318142Y887048D03*
X1314441D03*
X1310740D03*
X1307039D03*
X1316291Y890237D03*
X1312590D03*
X1308890D03*
X1305189D03*
X1318142Y893426D03*
X1314441D03*
X1310740D03*
X1307039D03*
X1316291Y896615D03*
X1312590D03*
X1308890D03*
X1305189D03*
X1318142Y899804D03*
X1314441D03*
X1310740D03*
X1307039D03*
X1316291Y902993D03*
X1312590D03*
X1308890D03*
X1305189D03*
X1318142Y906181D03*
X1314441D03*
X1310740D03*
X1307039D03*
X1316291Y909370D03*
X1312590D03*
X1308890D03*
X1305189D03*
X1318142Y912559D03*
X1314441D03*
X1310740D03*
X1307039D03*
X1316291Y915748D03*
X1312590D03*
X1308890D03*
X1305189D03*
X1318142Y918937D03*
X1314441D03*
X1310740D03*
X1307039D03*
X1316291Y922126D03*
X1312590D03*
X1308890D03*
X1305189D03*
X1318142Y925315D03*
X1314441D03*
X1310740D03*
X1307039D03*
X1316291Y928504D03*
X1312590D03*
X1308890D03*
X1305189D03*
X1318142Y931693D03*
X1314441D03*
X1310740D03*
X1307039D03*
X1316291Y934882D03*
X1312590D03*
X1308890D03*
X1305189D03*
X1318142Y938071D03*
X1314441D03*
X1310740D03*
X1307039D03*
X1316291Y941260D03*
X1312590D03*
X1308890D03*
X1305189D03*
X1318142Y944449D03*
X1314441D03*
X1310740D03*
X1307039D03*
X1316291Y947638D03*
X1312590D03*
X1308890D03*
X1305189D03*
X1318142Y950827D03*
X1314441D03*
X1310740D03*
X1307039D03*
X1316291Y954016D03*
X1312590D03*
X1308890D03*
X1305189D03*
X1318142Y957205D03*
X1314441D03*
X1310740D03*
X1307039D03*
X1316291Y960394D03*
X1312590D03*
X1308890D03*
X1305189D03*
X1318142Y963583D03*
X1314441D03*
X1310740D03*
X1307039D03*
X1316291Y966772D03*
X1312590D03*
X1308890D03*
X1305189D03*
X1318142Y969961D03*
X1314441D03*
X1310740D03*
X1307039D03*
X1316291Y973150D03*
X1312590D03*
X1308890D03*
X1305189D03*
X1318142Y976339D03*
X1314441D03*
X1310740D03*
X1307039D03*
X1316291Y979528D03*
X1312590D03*
X1308890D03*
X1305189D03*
X1318142Y982717D03*
X1314441D03*
X1310740D03*
X1307039D03*
X1316291Y985906D03*
X1312590D03*
X1308890D03*
X1305189D03*
X1318142Y989095D03*
X1314441D03*
X1310740D03*
X1307039D03*
X1316291Y992284D03*
X1312590D03*
X1308890D03*
X1305189D03*
X1318142Y995473D03*
X1314441D03*
X1310740D03*
X1307039D03*
X1316291Y998662D03*
X1312590D03*
X1308890D03*
X1305189D03*
X1318142Y1001851D03*
X1314441D03*
X1310740D03*
X1307039D03*
X1316291Y1005040D03*
X1312590D03*
X1308890D03*
X1305189D03*
X1318142Y1008229D03*
X1314441D03*
X1310740D03*
X1307039D03*
X1316291Y1011418D03*
X1312590D03*
X1308890D03*
X1305189D03*
X1317472Y1027008D03*
X1313771D03*
X1310071D03*
X1306370D03*
X1319323Y1030197D03*
X1315622D03*
X1311921D03*
X1308220D03*
X1317472Y1033386D03*
X1313771D03*
X1310071D03*
X1306370D03*
X1319323Y1036575D03*
X1315622D03*
X1311921D03*
X1308220D03*
X1317472Y1039764D03*
X1313771D03*
X1310071D03*
X1306370D03*
X1319323Y1042953D03*
X1315622D03*
X1311921D03*
X1308220D03*
X1317472Y1046142D03*
X1313771D03*
X1310071D03*
X1306370D03*
X1319323Y1049331D03*
X1315622D03*
X1311921D03*
X1308220D03*
X1317472Y1052520D03*
X1313771D03*
X1310071D03*
X1306370D03*
X1319323Y1055709D03*
X1315622D03*
X1311921D03*
X1308220D03*
X1317472Y1058898D03*
X1313771D03*
X1310071D03*
X1306370D03*
X1319323Y1062087D03*
X1315622D03*
X1311921D03*
X1308220D03*
X1317472Y1065276D03*
X1313771D03*
X1310071D03*
X1306370D03*
X1319323Y1068465D03*
X1315622D03*
X1311921D03*
X1308220D03*
X1317472Y1071654D03*
X1313771D03*
X1310071D03*
X1306370D03*
X1319323Y1074843D03*
X1315622D03*
X1311921D03*
X1308220D03*
X1317472Y1078032D03*
X1313771D03*
X1310071D03*
X1306370D03*
X1319323Y1081221D03*
X1315622D03*
X1311921D03*
X1308220D03*
X1317472Y1084410D03*
X1313771D03*
X1310071D03*
X1306370D03*
X1319323Y1087599D03*
X1315622D03*
X1311921D03*
X1308220D03*
X1317472Y1090788D03*
X1313771D03*
X1310071D03*
X1306370D03*
X1319323Y1093977D03*
X1315622D03*
X1311921D03*
X1308220D03*
X1317472Y1097166D03*
X1313771D03*
X1310071D03*
X1306370D03*
X1319323Y1100355D03*
X1315622D03*
X1311921D03*
X1308220D03*
X1317472Y1103544D03*
X1313771D03*
X1310071D03*
X1306370D03*
X1319323Y1106733D03*
X1315622D03*
X1311921D03*
X1308220D03*
X1317472Y1109922D03*
X1313771D03*
X1310071D03*
X1306370D03*
X1319323Y1113111D03*
X1315622D03*
X1311921D03*
X1308220D03*
X1317472Y1116300D03*
X1313771D03*
X1310071D03*
X1306370D03*
X1319323Y1119489D03*
X1315622D03*
X1311921D03*
X1308220D03*
X1317472Y1122678D03*
X1313771D03*
X1310071D03*
X1306370D03*
X1319323Y1125867D03*
X1315622D03*
X1311921D03*
X1308220D03*
X1317472Y1129056D03*
X1313771D03*
X1310071D03*
X1306370D03*
X1319323Y1132245D03*
X1315622D03*
X1311921D03*
X1308220D03*
X1317472Y1135433D03*
X1313771D03*
X1310071D03*
X1306370D03*
X1319323Y1138622D03*
X1315622D03*
X1311921D03*
X1308220D03*
X1317472Y1141811D03*
X1313771D03*
X1310071D03*
X1306370D03*
X1319323Y1145000D03*
X1315622D03*
X1311921D03*
X1308220D03*
X1317472Y1148189D03*
X1313771D03*
X1310071D03*
X1306370D03*
X1319323Y1151378D03*
X1315622D03*
X1311921D03*
X1308220D03*
X1317472Y1154567D03*
X1313771D03*
X1310071D03*
X1306370D03*
X1319323Y1157756D03*
X1315622D03*
X1311921D03*
X1308220D03*
X1317472Y1160945D03*
X1313771D03*
X1310071D03*
X1306370D03*
X1319323Y1164134D03*
X1315622D03*
X1311921D03*
X1308220D03*
X1332945Y874292D03*
X1329244D03*
X1325543D03*
X1331094Y877481D03*
X1327394D03*
X1323693D03*
X1319992D03*
X1332945Y880670D03*
X1329244D03*
X1325543D03*
X1321842D03*
X1331094Y883859D03*
X1327394D03*
X1323693D03*
X1319992D03*
X1332945Y887048D03*
X1329244D03*
X1325543D03*
X1321842D03*
X1331094Y890237D03*
X1327394D03*
X1323693D03*
X1319992D03*
X1332945Y893426D03*
X1329244D03*
X1325543D03*
X1321842D03*
X1331094Y896615D03*
X1327394D03*
X1323693D03*
X1319992D03*
X1332945Y899804D03*
X1329244D03*
X1325543D03*
X1321842D03*
X1331094Y902993D03*
X1327394D03*
X1323693D03*
X1319992D03*
X1332945Y906181D03*
X1329244D03*
X1325543D03*
X1321842D03*
X1331094Y909370D03*
X1327394D03*
X1323693D03*
X1319992D03*
X1332945Y912559D03*
X1329244D03*
X1325543D03*
X1321842D03*
X1331094Y915748D03*
X1327394D03*
X1323693D03*
X1319992D03*
X1332945Y918937D03*
X1329244D03*
X1325543D03*
X1321842D03*
X1331094Y922126D03*
X1327394D03*
X1323693D03*
X1319992D03*
X1332945Y925315D03*
X1329244D03*
X1325543D03*
X1321842D03*
X1331094Y928504D03*
X1327394D03*
X1323693D03*
X1319992D03*
X1332945Y931693D03*
X1329244D03*
X1325543D03*
X1321842D03*
X1331094Y934882D03*
X1327394D03*
X1323693D03*
X1319992D03*
X1332945Y938071D03*
X1329244D03*
X1325543D03*
X1321842D03*
X1331094Y941260D03*
X1327394D03*
X1323693D03*
X1319992D03*
X1332945Y944449D03*
X1329244D03*
X1325543D03*
X1321842D03*
X1331094Y947638D03*
X1327394D03*
X1323693D03*
X1319992D03*
X1332945Y950827D03*
X1329244D03*
X1325543D03*
X1321842D03*
X1331094Y954016D03*
X1327394D03*
X1323693D03*
X1319992D03*
X1332945Y957205D03*
X1329244D03*
X1325543D03*
X1321842D03*
X1331094Y960394D03*
X1327394D03*
X1323693D03*
X1319992D03*
X1332945Y963583D03*
X1329244D03*
X1325543D03*
X1321842D03*
X1331094Y966772D03*
X1327394D03*
X1323693D03*
X1319992D03*
X1332945Y969961D03*
X1329244D03*
X1325543D03*
X1321842D03*
X1331094Y973150D03*
X1327394D03*
X1323693D03*
X1319992D03*
X1332945Y976339D03*
X1329244D03*
X1325543D03*
X1321842D03*
X1331094Y979528D03*
X1327394D03*
X1323693D03*
X1319992D03*
X1332945Y982717D03*
X1329244D03*
X1325543D03*
X1321842D03*
X1331094Y985906D03*
X1327394D03*
X1323693D03*
X1319992D03*
X1332945Y989095D03*
X1329244D03*
X1325543D03*
X1321842D03*
X1331094Y992284D03*
X1327394D03*
X1323693D03*
X1319992D03*
X1332945Y995473D03*
X1329244D03*
X1325543D03*
X1321842D03*
X1331094Y998662D03*
X1327394D03*
X1323693D03*
X1319992D03*
X1332945Y1001851D03*
X1329244D03*
X1325543D03*
X1321842D03*
X1331094Y1005040D03*
X1327394D03*
X1323693D03*
X1319992D03*
X1332945Y1008229D03*
X1329244D03*
X1325543D03*
X1321842D03*
X1331094Y1011418D03*
X1327394D03*
X1323693D03*
X1319992D03*
X1332275Y1027008D03*
X1328575D03*
X1324874D03*
X1321173D03*
X1334126Y1030197D03*
X1330425D03*
X1326724D03*
X1323023D03*
X1332275Y1033386D03*
X1328575D03*
X1324874D03*
X1321173D03*
X1334126Y1036575D03*
X1330425D03*
X1326724D03*
X1323023D03*
X1332275Y1039764D03*
X1328575D03*
X1324874D03*
X1321173D03*
X1334126Y1042953D03*
X1330425D03*
X1326724D03*
X1323023D03*
X1332275Y1046142D03*
X1328575D03*
X1324874D03*
X1321173D03*
X1334126Y1049331D03*
X1330425D03*
X1326724D03*
X1323023D03*
X1332275Y1052520D03*
X1328575D03*
X1324874D03*
X1321173D03*
X1334126Y1055709D03*
X1330425D03*
X1326724D03*
X1323023D03*
X1332275Y1058898D03*
X1328575D03*
X1324874D03*
X1321173D03*
X1334126Y1062087D03*
X1330425D03*
X1326724D03*
X1323023D03*
X1332275Y1065276D03*
X1328575D03*
X1324874D03*
X1321173D03*
X1334126Y1068465D03*
X1330425D03*
X1326724D03*
X1323023D03*
X1332275Y1071654D03*
X1328575D03*
X1324874D03*
X1321173D03*
X1334126Y1074843D03*
X1330425D03*
X1326724D03*
X1323023D03*
X1332275Y1078032D03*
X1328575D03*
X1324874D03*
X1321173D03*
X1334126Y1081221D03*
X1330425D03*
X1326724D03*
X1323023D03*
X1332275Y1084410D03*
X1328575D03*
X1324874D03*
X1321173D03*
X1334126Y1087599D03*
X1330425D03*
X1326724D03*
X1323023D03*
X1332275Y1090788D03*
X1328575D03*
X1324874D03*
X1321173D03*
X1334126Y1093977D03*
X1330425D03*
X1326724D03*
X1323023D03*
X1332275Y1097166D03*
X1328575D03*
X1324874D03*
X1321173D03*
X1334126Y1100355D03*
X1330425D03*
X1326724D03*
X1323023D03*
X1332275Y1103544D03*
X1328575D03*
X1324874D03*
X1321173D03*
X1334126Y1106733D03*
X1330425D03*
X1326724D03*
X1323023D03*
X1332275Y1109922D03*
X1328575D03*
X1324874D03*
X1321173D03*
X1334126Y1113111D03*
X1330425D03*
X1326724D03*
X1323023D03*
X1332275Y1116300D03*
X1328575D03*
X1324874D03*
X1321173D03*
X1334126Y1119489D03*
X1330425D03*
X1326724D03*
X1323023D03*
X1332275Y1122678D03*
X1328575D03*
X1324874D03*
X1321173D03*
X1334126Y1125867D03*
X1330425D03*
X1326724D03*
X1323023D03*
X1332275Y1129056D03*
X1328575D03*
X1324874D03*
X1321173D03*
X1334126Y1132245D03*
X1330425D03*
X1326724D03*
X1323023D03*
X1332275Y1135433D03*
X1328575D03*
X1324874D03*
X1321173D03*
X1334126Y1138622D03*
X1330425D03*
X1326724D03*
X1323023D03*
X1332275Y1141811D03*
X1328575D03*
X1324874D03*
X1321173D03*
X1334126Y1145000D03*
X1330425D03*
X1326724D03*
X1323023D03*
X1332275Y1148189D03*
X1328575D03*
X1324874D03*
X1321173D03*
X1334126Y1151378D03*
X1330425D03*
X1326724D03*
X1323023D03*
X1332275Y1154567D03*
X1328575D03*
X1324874D03*
X1321173D03*
X1334126Y1157756D03*
X1330425D03*
X1326724D03*
X1323023D03*
X1332275Y1160945D03*
X1328575D03*
X1324874D03*
X1321173D03*
X1334126Y1164134D03*
X1330425D03*
X1326724D03*
X1347748Y874292D03*
X1340346D03*
X1336646D03*
X1349598Y877481D03*
X1345897D03*
X1342197D03*
X1338496D03*
X1334795D03*
X1347748Y880670D03*
X1344047D03*
X1340346D03*
X1336646D03*
X1349598Y883859D03*
X1345897D03*
X1342197D03*
X1338496D03*
X1334795D03*
X1347748Y887048D03*
X1344047D03*
X1340346D03*
X1336646D03*
X1349598Y890237D03*
X1345897D03*
X1342197D03*
X1338496D03*
X1334795D03*
X1347748Y893426D03*
X1344047D03*
X1340346D03*
X1336646D03*
X1349598Y896615D03*
X1345897D03*
X1342197D03*
X1338496D03*
X1334795D03*
X1347748Y899804D03*
X1344047D03*
X1340346D03*
X1336646D03*
X1349598Y902993D03*
X1345897D03*
X1342197D03*
X1338496D03*
X1334795D03*
X1347748Y906181D03*
X1344047D03*
X1340346D03*
X1336646D03*
X1349598Y909370D03*
X1345897D03*
X1342197D03*
X1338496D03*
X1334795D03*
X1347748Y912559D03*
X1344047D03*
X1340346D03*
X1336646D03*
X1349598Y915748D03*
X1345897D03*
X1342197D03*
X1338496D03*
X1334795D03*
X1347748Y918937D03*
X1344047D03*
X1340346D03*
X1336646D03*
X1349598Y922126D03*
X1345897D03*
X1342197D03*
X1338496D03*
X1334795D03*
X1347748Y925315D03*
X1344047D03*
X1340346D03*
X1336646D03*
X1349598Y928504D03*
X1345897D03*
X1342197D03*
X1338496D03*
X1334795D03*
X1347748Y931693D03*
X1344047D03*
X1340346D03*
X1336646D03*
X1349598Y934882D03*
X1345897D03*
X1342197D03*
X1338496D03*
X1334795D03*
X1347748Y938071D03*
X1344047D03*
X1340346D03*
X1336646D03*
X1349598Y941260D03*
X1345897D03*
X1342197D03*
X1338496D03*
X1334795D03*
X1347748Y944449D03*
X1344047D03*
X1340346D03*
X1336646D03*
X1349598Y947638D03*
X1345897D03*
X1342197D03*
X1338496D03*
X1334795D03*
X1347748Y950827D03*
X1344047D03*
X1340346D03*
X1336646D03*
X1349598Y954016D03*
X1345897D03*
X1342197D03*
X1338496D03*
X1334795D03*
X1347748Y957205D03*
X1344047D03*
X1340346D03*
X1336646D03*
X1349598Y960394D03*
X1345897D03*
X1342197D03*
X1338496D03*
X1334795D03*
X1347748Y963583D03*
X1344047D03*
X1340346D03*
X1336646D03*
X1349598Y966772D03*
X1345897D03*
X1342197D03*
X1338496D03*
X1334795D03*
X1347748Y969961D03*
X1344047D03*
X1340346D03*
X1336646D03*
X1349598Y973150D03*
X1345897D03*
X1342197D03*
X1338496D03*
X1334795D03*
X1347748Y976339D03*
X1344047D03*
X1340346D03*
X1336646D03*
X1349598Y979528D03*
X1345897D03*
X1342197D03*
X1338496D03*
X1334795D03*
X1347748Y982717D03*
X1344047D03*
X1340346D03*
X1336646D03*
X1349598Y985906D03*
X1345897D03*
X1342197D03*
X1338496D03*
X1334795D03*
X1347748Y989095D03*
X1344047D03*
X1340346D03*
X1336646D03*
X1349598Y992284D03*
X1345897D03*
X1342197D03*
X1338496D03*
X1334795D03*
X1347748Y995473D03*
X1344047D03*
X1340346D03*
X1336646D03*
X1349598Y998662D03*
X1345897D03*
X1342197D03*
X1338496D03*
X1334795D03*
X1347748Y1001851D03*
X1344047D03*
X1340346D03*
X1336646D03*
X1349598Y1005040D03*
X1345897D03*
X1342197D03*
X1338496D03*
X1334795D03*
X1347748Y1008229D03*
X1344047D03*
X1340346D03*
X1336646D03*
X1349598Y1011418D03*
X1345897D03*
X1342197D03*
X1338496D03*
X1334795D03*
X1347079Y1027008D03*
X1343378D03*
X1339677D03*
X1335976D03*
X1348929Y1030197D03*
X1345228D03*
X1341527D03*
X1337827D03*
X1347079Y1033386D03*
X1343378D03*
X1339677D03*
X1335976D03*
X1348929Y1036575D03*
X1345228D03*
X1341527D03*
X1337827D03*
X1347079Y1039764D03*
X1343378D03*
X1339677D03*
X1335976D03*
X1348929Y1042953D03*
X1345228D03*
X1341527D03*
X1337827D03*
X1347079Y1046142D03*
X1343378D03*
X1339677D03*
X1335976D03*
X1348929Y1049331D03*
X1345228D03*
X1341527D03*
X1337827D03*
X1347079Y1052520D03*
X1343378D03*
X1339677D03*
X1335976D03*
X1348929Y1055709D03*
X1345228D03*
X1341527D03*
X1337827D03*
X1347079Y1058898D03*
X1343378D03*
X1339677D03*
X1335976D03*
X1348929Y1062087D03*
X1345228D03*
X1341527D03*
X1337827D03*
X1347079Y1065276D03*
X1343378D03*
X1339677D03*
X1335976D03*
X1348929Y1068465D03*
X1345228D03*
X1341527D03*
X1337827D03*
X1347079Y1071654D03*
X1343378D03*
X1339677D03*
X1335976D03*
X1348929Y1074843D03*
X1345228D03*
X1341527D03*
X1337827D03*
X1347079Y1078032D03*
X1343378D03*
X1339677D03*
X1335976D03*
X1348929Y1081221D03*
X1345228D03*
X1341527D03*
X1337827D03*
X1347079Y1084410D03*
X1343378D03*
X1339677D03*
X1335976D03*
X1348929Y1087599D03*
X1345228D03*
X1341527D03*
X1337827D03*
X1347079Y1090788D03*
X1343378D03*
X1339677D03*
X1335976D03*
X1348929Y1093977D03*
X1345228D03*
X1341527D03*
X1337827D03*
X1347079Y1097166D03*
X1343378D03*
X1339677D03*
X1335976D03*
X1348929Y1100355D03*
X1345228D03*
X1341527D03*
X1337827D03*
X1347079Y1103544D03*
X1343378D03*
X1339677D03*
X1335976D03*
X1348929Y1106733D03*
X1345228D03*
X1341527D03*
X1337827D03*
X1347079Y1109922D03*
X1343378D03*
X1339677D03*
X1335976D03*
X1348929Y1113111D03*
X1345228D03*
X1341527D03*
X1337827D03*
X1347079Y1116300D03*
X1343378D03*
X1339677D03*
X1335976D03*
X1348929Y1119489D03*
X1345228D03*
X1341527D03*
X1337827D03*
X1347079Y1122678D03*
X1343378D03*
X1339677D03*
X1335976D03*
X1348929Y1125867D03*
X1345228D03*
X1341527D03*
X1337827D03*
X1347079Y1129056D03*
X1343378D03*
X1339677D03*
X1335976D03*
X1348929Y1132245D03*
X1345228D03*
X1341527D03*
X1337827D03*
X1347079Y1135433D03*
X1343378D03*
X1339677D03*
X1335976D03*
X1348929Y1138622D03*
X1345228D03*
X1341527D03*
X1337827D03*
X1347079Y1141811D03*
X1343378D03*
X1339677D03*
X1335976D03*
X1348929Y1145000D03*
X1345228D03*
X1341527D03*
X1337827D03*
X1347079Y1148189D03*
X1343378D03*
X1339677D03*
X1335976D03*
X1348929Y1151378D03*
X1345228D03*
X1341527D03*
X1337827D03*
X1347079Y1154567D03*
X1343378D03*
X1339677D03*
X1335976D03*
X1348929Y1157756D03*
X1345228D03*
X1341527D03*
X1337827D03*
X1347079Y1160945D03*
X1343378D03*
X1339677D03*
X1335976D03*
X1348929Y1164134D03*
X1341527D03*
X1337827D03*
X1362551Y874292D03*
X1358850D03*
X1355149D03*
X1351449D03*
X1364401Y877481D03*
X1360701D03*
X1357000D03*
X1353299D03*
X1362551Y880670D03*
X1358850D03*
X1355149D03*
X1351449D03*
X1364401Y883859D03*
X1360701D03*
X1357000D03*
X1353299D03*
X1362551Y887048D03*
X1358850D03*
X1355149D03*
X1351449D03*
X1364401Y890237D03*
X1360701D03*
X1357000D03*
X1353299D03*
X1362551Y893426D03*
X1358850D03*
X1355149D03*
X1351449D03*
X1364401Y896615D03*
X1360701D03*
X1357000D03*
X1353299D03*
X1362551Y899804D03*
X1358850D03*
X1355149D03*
X1351449D03*
X1364401Y902993D03*
X1360701D03*
X1357000D03*
X1353299D03*
X1362551Y906181D03*
X1358850D03*
X1355149D03*
X1351449D03*
X1364401Y909370D03*
X1360701D03*
X1357000D03*
X1353299D03*
X1362551Y912559D03*
X1358850D03*
X1355149D03*
X1351449D03*
X1364401Y915748D03*
X1360701D03*
X1357000D03*
X1353299D03*
X1362551Y918937D03*
X1358850D03*
X1355149D03*
X1351449D03*
X1364401Y922126D03*
X1360701D03*
X1357000D03*
X1353299D03*
X1362551Y925315D03*
X1358850D03*
X1355149D03*
X1351449D03*
X1364401Y928504D03*
X1360701D03*
X1357000D03*
X1353299D03*
X1362551Y931693D03*
X1358850D03*
X1355149D03*
X1351449D03*
X1364401Y934882D03*
X1360701D03*
X1357000D03*
X1353299D03*
X1362551Y938071D03*
X1358850D03*
X1355149D03*
X1351449D03*
X1364401Y941260D03*
X1360701D03*
X1357000D03*
X1353299D03*
X1362551Y944449D03*
X1358850D03*
X1355149D03*
X1351449D03*
X1364401Y947638D03*
X1360701D03*
X1357000D03*
X1353299D03*
X1362551Y950827D03*
X1358850D03*
X1355149D03*
X1351449D03*
X1364401Y954016D03*
X1360701D03*
X1357000D03*
X1353299D03*
X1362551Y957205D03*
X1358850D03*
X1355149D03*
X1351449D03*
X1364401Y960394D03*
X1360701D03*
X1357000D03*
X1353299D03*
X1362551Y963583D03*
X1358850D03*
X1355149D03*
X1351449D03*
X1364401Y966772D03*
X1360701D03*
X1357000D03*
X1353299D03*
X1362551Y969961D03*
X1358850D03*
X1355149D03*
X1351449D03*
X1364401Y973150D03*
X1360701D03*
X1357000D03*
X1353299D03*
X1362551Y976339D03*
X1358850D03*
X1355149D03*
X1351449D03*
X1364401Y979528D03*
X1360701D03*
X1357000D03*
X1353299D03*
X1362551Y982717D03*
X1358850D03*
X1355149D03*
X1351449D03*
X1364401Y985906D03*
X1360701D03*
X1357000D03*
X1353299D03*
X1362551Y989095D03*
X1358850D03*
X1355149D03*
X1351449D03*
X1364401Y992284D03*
X1360701D03*
X1357000D03*
X1353299D03*
X1362551Y995473D03*
X1358850D03*
X1355149D03*
X1351449D03*
X1364401Y998662D03*
X1360701D03*
X1357000D03*
X1353299D03*
X1362551Y1001851D03*
X1358850D03*
X1355149D03*
X1351449D03*
X1364401Y1005040D03*
X1360701D03*
X1357000D03*
X1353299D03*
X1362551Y1008229D03*
X1358850D03*
X1355149D03*
X1351449D03*
X1364401Y1011418D03*
X1360701D03*
X1357000D03*
X1353299D03*
X1361882Y1027008D03*
X1358181D03*
X1354480D03*
X1350779D03*
X1363732Y1030197D03*
X1360031D03*
X1356331D03*
X1352630D03*
X1361882Y1033386D03*
X1358181D03*
X1354480D03*
X1350779D03*
X1363732Y1036575D03*
X1360031D03*
X1356331D03*
X1352630D03*
X1361882Y1039764D03*
X1358181D03*
X1354480D03*
X1350779D03*
X1363732Y1042953D03*
X1360031D03*
X1356331D03*
X1352630D03*
X1361882Y1046142D03*
X1358181D03*
X1354480D03*
X1350779D03*
X1363732Y1049331D03*
X1360031D03*
X1356331D03*
X1352630D03*
X1361882Y1052520D03*
X1358181D03*
X1354480D03*
X1350779D03*
X1363732Y1055709D03*
X1360031D03*
X1356331D03*
X1352630D03*
X1361882Y1058898D03*
X1358181D03*
X1354480D03*
X1350779D03*
X1363732Y1062087D03*
X1360031D03*
X1356331D03*
X1352630D03*
X1361882Y1065276D03*
X1358181D03*
X1354480D03*
X1350779D03*
X1363732Y1068465D03*
X1360031D03*
X1356331D03*
X1352630D03*
X1361882Y1071654D03*
X1358181D03*
X1354480D03*
X1350779D03*
X1363732Y1074843D03*
X1360031D03*
X1356331D03*
X1352630D03*
X1361882Y1078032D03*
X1358181D03*
X1354480D03*
X1350779D03*
X1363732Y1081221D03*
X1360031D03*
X1356331D03*
X1352630D03*
X1361882Y1084410D03*
X1358181D03*
X1354480D03*
X1350779D03*
X1363732Y1087599D03*
X1360031D03*
X1356331D03*
X1352630D03*
X1361882Y1090788D03*
X1358181D03*
X1354480D03*
X1350779D03*
X1363732Y1093977D03*
X1360031D03*
X1356331D03*
X1352630D03*
X1361882Y1097166D03*
X1358181D03*
X1354480D03*
X1350779D03*
X1363732Y1100355D03*
X1360031D03*
X1356331D03*
X1352630D03*
X1361882Y1103544D03*
X1358181D03*
X1354480D03*
X1350779D03*
X1363732Y1106733D03*
X1360031D03*
X1356331D03*
X1352630D03*
X1361882Y1109922D03*
X1358181D03*
X1354480D03*
X1350779D03*
X1363732Y1113111D03*
X1360031D03*
X1356331D03*
X1352630D03*
X1361882Y1116300D03*
X1358181D03*
X1354480D03*
X1350779D03*
X1363732Y1119489D03*
X1360031D03*
X1356331D03*
X1352630D03*
X1361882Y1122678D03*
X1358181D03*
X1354480D03*
X1350779D03*
X1363732Y1125867D03*
X1360031D03*
X1356331D03*
X1352630D03*
X1361882Y1129056D03*
X1358181D03*
X1354480D03*
X1350779D03*
X1363732Y1132245D03*
X1360031D03*
X1356331D03*
X1352630D03*
X1361882Y1135433D03*
X1358181D03*
X1354480D03*
X1350779D03*
X1363732Y1138622D03*
X1360031D03*
X1356331D03*
X1352630D03*
X1361882Y1141811D03*
X1358181D03*
X1354480D03*
X1350779D03*
X1363732Y1145000D03*
X1360031D03*
X1356331D03*
X1352630D03*
X1361882Y1148189D03*
X1358181D03*
X1354480D03*
X1350779D03*
X1363732Y1151378D03*
X1360031D03*
X1356331D03*
X1352630D03*
X1361882Y1154567D03*
X1358181D03*
X1354480D03*
X1350779D03*
X1363732Y1157756D03*
X1360031D03*
X1356331D03*
X1352630D03*
X1361882Y1160945D03*
X1358181D03*
X1354480D03*
X1350779D03*
X1363732Y1164134D03*
X1360031D03*
X1356331D03*
X1352630D03*
X1377354Y874292D03*
X1373653D03*
X1369953D03*
X1379205Y877481D03*
X1375504D03*
X1371803D03*
X1368102D03*
X1377354Y880670D03*
X1373653D03*
X1369953D03*
X1366252D03*
X1379205Y883859D03*
X1375504D03*
X1371803D03*
X1368102D03*
X1377354Y887048D03*
X1373653D03*
X1369953D03*
X1366252D03*
X1379205Y890237D03*
X1375504D03*
X1371803D03*
X1368102D03*
X1377354Y893426D03*
X1373653D03*
X1369953D03*
X1366252D03*
X1379205Y896615D03*
X1375504D03*
X1371803D03*
X1368102D03*
X1377354Y899804D03*
X1373653D03*
X1369953D03*
X1366252D03*
X1379205Y902993D03*
X1375504D03*
X1371803D03*
X1368102D03*
X1377354Y906181D03*
X1373653D03*
X1369953D03*
X1366252D03*
X1379205Y909370D03*
X1375504D03*
X1371803D03*
X1368102D03*
X1377354Y912559D03*
X1373653D03*
X1369953D03*
X1366252D03*
X1379205Y915748D03*
X1375504D03*
X1371803D03*
X1368102D03*
X1377354Y918937D03*
X1373653D03*
X1369953D03*
X1366252D03*
X1379205Y922126D03*
X1375504D03*
X1371803D03*
X1368102D03*
X1377354Y925315D03*
X1373653D03*
X1369953D03*
X1366252D03*
X1379205Y928504D03*
X1375504D03*
X1371803D03*
X1368102D03*
X1377354Y931693D03*
X1373653D03*
X1369953D03*
X1366252D03*
X1379205Y934882D03*
X1375504D03*
X1371803D03*
X1368102D03*
X1377354Y938071D03*
X1373653D03*
X1369953D03*
X1366252D03*
X1379205Y941260D03*
X1375504D03*
X1371803D03*
X1368102D03*
X1377354Y944449D03*
X1373653D03*
X1369953D03*
X1366252D03*
X1379205Y947638D03*
X1375504D03*
X1371803D03*
X1368102D03*
X1377354Y950827D03*
X1373653D03*
X1369953D03*
X1366252D03*
X1379205Y954016D03*
X1375504D03*
X1371803D03*
X1368102D03*
X1377354Y957205D03*
X1373653D03*
X1369953D03*
X1366252D03*
X1379205Y960394D03*
X1375504D03*
X1371803D03*
X1368102D03*
X1377354Y963583D03*
X1373653D03*
X1369953D03*
X1366252D03*
X1379205Y966772D03*
X1375504D03*
X1371803D03*
X1368102D03*
X1377354Y969961D03*
X1373653D03*
X1369953D03*
X1366252D03*
X1379205Y973150D03*
X1375504D03*
X1371803D03*
X1368102D03*
X1377354Y976339D03*
X1373653D03*
X1369953D03*
X1366252D03*
X1379205Y979528D03*
X1375504D03*
X1371803D03*
X1368102D03*
X1377354Y982717D03*
X1373653D03*
X1369953D03*
X1366252D03*
X1379205Y985906D03*
X1375504D03*
X1371803D03*
X1368102D03*
X1377354Y989095D03*
X1373653D03*
X1369953D03*
X1366252D03*
X1379205Y992284D03*
X1375504D03*
X1371803D03*
X1368102D03*
X1377354Y995473D03*
X1373653D03*
X1369953D03*
X1366252D03*
X1379205Y998662D03*
X1375504D03*
X1371803D03*
X1368102D03*
X1377354Y1001851D03*
X1373653D03*
X1369953D03*
X1366252D03*
X1379205Y1005040D03*
X1375504D03*
X1371803D03*
X1368102D03*
X1377354Y1008229D03*
X1373653D03*
X1369953D03*
X1366252D03*
X1379205Y1011418D03*
X1375504D03*
X1371803D03*
X1368102D03*
X1376685Y1027008D03*
X1372984D03*
X1369283D03*
X1365583D03*
X1378535Y1030197D03*
X1374835D03*
X1371134D03*
X1367433D03*
X1376685Y1033386D03*
X1372984D03*
X1369283D03*
X1365583D03*
X1378535Y1036575D03*
X1374835D03*
X1371134D03*
X1367433D03*
X1376685Y1039764D03*
X1372984D03*
X1369283D03*
X1365583D03*
X1378535Y1042953D03*
X1374835D03*
X1371134D03*
X1367433D03*
X1376685Y1046142D03*
X1372984D03*
X1369283D03*
X1365583D03*
X1378535Y1049331D03*
X1374835D03*
X1371134D03*
X1367433D03*
X1376685Y1052520D03*
X1372984D03*
X1369283D03*
X1365583D03*
X1378535Y1055709D03*
X1374835D03*
X1371134D03*
X1367433D03*
X1376685Y1058898D03*
X1372984D03*
X1369283D03*
X1365583D03*
X1378535Y1062087D03*
X1374835D03*
X1371134D03*
X1367433D03*
X1376685Y1065276D03*
X1372984D03*
X1369283D03*
X1365583D03*
X1378535Y1068465D03*
X1374835D03*
X1371134D03*
X1367433D03*
X1376685Y1071654D03*
X1372984D03*
X1369283D03*
X1365583D03*
X1378535Y1074843D03*
X1374835D03*
X1371134D03*
X1367433D03*
X1376685Y1078032D03*
X1372984D03*
X1369283D03*
X1365583D03*
X1378535Y1081221D03*
X1374835D03*
X1371134D03*
X1367433D03*
X1376685Y1084410D03*
X1372984D03*
X1369283D03*
X1365583D03*
X1378535Y1087599D03*
X1374835D03*
X1371134D03*
X1367433D03*
X1376685Y1090788D03*
X1372984D03*
X1369283D03*
X1365583D03*
X1378535Y1093977D03*
X1374835D03*
X1371134D03*
X1367433D03*
X1376685Y1097166D03*
X1372984D03*
X1369283D03*
X1365583D03*
X1378535Y1100355D03*
X1374835D03*
X1371134D03*
X1367433D03*
X1376685Y1103544D03*
X1372984D03*
X1369283D03*
X1365583D03*
X1378535Y1106733D03*
X1374835D03*
X1371134D03*
X1367433D03*
X1376685Y1109922D03*
X1372984D03*
X1369283D03*
X1365583D03*
X1378535Y1113111D03*
X1374835D03*
X1371134D03*
X1367433D03*
X1376685Y1116300D03*
X1372984D03*
X1369283D03*
X1365583D03*
X1378535Y1119489D03*
X1374835D03*
X1371134D03*
X1367433D03*
X1376685Y1122678D03*
X1372984D03*
X1369283D03*
X1365583D03*
X1378535Y1125867D03*
X1374835D03*
X1371134D03*
X1367433D03*
X1376685Y1129056D03*
X1372984D03*
X1369283D03*
X1365583D03*
X1378535Y1132245D03*
X1374835D03*
X1371134D03*
X1367433D03*
X1376685Y1135433D03*
X1372984D03*
X1369283D03*
X1365583D03*
X1378535Y1138622D03*
X1374835D03*
X1371134D03*
X1367433D03*
X1376685Y1141811D03*
X1372984D03*
X1369283D03*
X1365583D03*
X1378535Y1145000D03*
X1374835D03*
X1371134D03*
X1367433D03*
X1376685Y1148189D03*
X1372984D03*
X1369283D03*
X1365583D03*
X1378535Y1151378D03*
X1374835D03*
X1371134D03*
X1367433D03*
X1376685Y1154567D03*
X1372984D03*
X1369283D03*
X1365583D03*
X1378535Y1157756D03*
X1374835D03*
X1371134D03*
X1367433D03*
X1376685Y1160945D03*
X1372984D03*
X1369283D03*
X1365583D03*
X1378535Y1164134D03*
X1374835D03*
X1371134D03*
X1392157Y874292D03*
X1384756D03*
X1381055D03*
X1394008Y877481D03*
X1390307D03*
X1386606D03*
X1382905D03*
X1392157Y880670D03*
X1388457D03*
X1384756D03*
X1381055D03*
X1394008Y883859D03*
X1390307D03*
X1386606D03*
X1382905D03*
X1392157Y887048D03*
X1388457D03*
X1384756D03*
X1381055D03*
X1394008Y890237D03*
X1390307D03*
X1386606D03*
X1382905D03*
X1392157Y893426D03*
X1388457D03*
X1384756D03*
X1381055D03*
X1394008Y896615D03*
X1390307D03*
X1386606D03*
X1382905D03*
X1392157Y899804D03*
X1388457D03*
X1384756D03*
X1381055D03*
X1394008Y902993D03*
X1390307D03*
X1386606D03*
X1382905D03*
X1392157Y906181D03*
X1388457D03*
X1384756D03*
X1381055D03*
X1394008Y909370D03*
X1390307D03*
X1386606D03*
X1382905D03*
X1392157Y912559D03*
X1388457D03*
X1384756D03*
X1381055D03*
X1394008Y915748D03*
X1390307D03*
X1386606D03*
X1382905D03*
X1392157Y918937D03*
X1388457D03*
X1384756D03*
X1381055D03*
X1394008Y922126D03*
X1390307D03*
X1386606D03*
X1382905D03*
X1392157Y925315D03*
X1388457D03*
X1384756D03*
X1381055D03*
X1394008Y928504D03*
X1390307D03*
X1386606D03*
X1382905D03*
X1392157Y931693D03*
X1388457D03*
X1384756D03*
X1381055D03*
X1394008Y934882D03*
X1390307D03*
X1386606D03*
X1382905D03*
X1392157Y938071D03*
X1388457D03*
X1384756D03*
X1381055D03*
X1394008Y941260D03*
X1390307D03*
X1386606D03*
X1382905D03*
X1392157Y944449D03*
X1388457D03*
X1384756D03*
X1381055D03*
X1394008Y947638D03*
X1390307D03*
X1386606D03*
X1382905D03*
X1392157Y950827D03*
X1388457D03*
X1384756D03*
X1381055D03*
X1394008Y954016D03*
X1390307D03*
X1386606D03*
X1382905D03*
X1392157Y957205D03*
X1388457D03*
X1384756D03*
X1381055D03*
X1394008Y960394D03*
X1390307D03*
X1386606D03*
X1382905D03*
X1392157Y963583D03*
X1388457D03*
X1384756D03*
X1381055D03*
X1394008Y966772D03*
X1390307D03*
X1386606D03*
X1382905D03*
X1392157Y969961D03*
X1388457D03*
X1384756D03*
X1381055D03*
X1394008Y973150D03*
X1390307D03*
X1386606D03*
X1382905D03*
X1392157Y976339D03*
X1388457D03*
X1384756D03*
X1381055D03*
X1394008Y979528D03*
X1390307D03*
X1386606D03*
X1382905D03*
X1392157Y982717D03*
X1388457D03*
X1384756D03*
X1381055D03*
X1394008Y985906D03*
X1390307D03*
X1386606D03*
X1382905D03*
X1392157Y989095D03*
X1388457D03*
X1384756D03*
X1381055D03*
X1394008Y992284D03*
X1390307D03*
X1386606D03*
X1382905D03*
X1381055Y995473D03*
Y1001851D03*
Y1008229D03*
X1380386Y1027008D03*
X1382236Y1030197D03*
X1380386Y1033386D03*
X1382236Y1036575D03*
X1380386Y1039764D03*
X1382236Y1042953D03*
X1391488Y1046142D03*
X1387787D03*
X1384086D03*
X1380386D03*
X1393338Y1049331D03*
X1389638D03*
X1385937D03*
X1382236D03*
X1391488Y1052520D03*
X1387787D03*
X1384086D03*
X1380386D03*
X1393338Y1055709D03*
X1389638D03*
X1385937D03*
X1382236D03*
X1391488Y1058898D03*
X1387787D03*
X1384086D03*
X1380386D03*
X1393338Y1062087D03*
X1389638D03*
X1385937D03*
X1382236D03*
X1391488Y1065276D03*
X1387787D03*
X1384086D03*
X1380386D03*
X1393338Y1068465D03*
X1389638D03*
X1385937D03*
X1382236D03*
X1391488Y1071654D03*
X1387787D03*
X1384086D03*
X1380386D03*
X1393338Y1074843D03*
X1389638D03*
X1385937D03*
X1382236D03*
X1391488Y1078032D03*
X1387787D03*
X1384086D03*
X1380386D03*
X1393338Y1081221D03*
X1389638D03*
X1385937D03*
X1382236D03*
X1391488Y1084410D03*
X1387787D03*
X1384086D03*
X1380386D03*
X1393338Y1087599D03*
X1389638D03*
X1385937D03*
X1382236D03*
X1391488Y1090788D03*
X1387787D03*
X1384086D03*
X1380386D03*
X1393338Y1093977D03*
X1389638D03*
X1385937D03*
X1382236D03*
X1391488Y1097166D03*
X1387787D03*
X1384086D03*
X1380386D03*
X1393338Y1100355D03*
X1389638D03*
X1385937D03*
X1382236D03*
X1391488Y1103544D03*
X1387787D03*
X1384086D03*
X1380386D03*
X1393338Y1106733D03*
X1389638D03*
X1385937D03*
X1382236D03*
X1391488Y1109922D03*
X1387787D03*
X1384086D03*
X1380386D03*
X1393338Y1113111D03*
X1389638D03*
X1385937D03*
X1382236D03*
X1391488Y1116300D03*
X1387787D03*
X1384086D03*
X1380386D03*
X1393338Y1119489D03*
X1389638D03*
X1385937D03*
X1382236D03*
X1391488Y1122678D03*
X1387787D03*
X1384086D03*
X1380386D03*
X1393338Y1125867D03*
X1389638D03*
X1385937D03*
X1382236D03*
X1391488Y1129056D03*
X1387787D03*
X1384086D03*
X1380386D03*
X1393338Y1132245D03*
X1389638D03*
X1385937D03*
X1382236D03*
X1391488Y1135433D03*
X1387787D03*
X1384086D03*
X1380386D03*
X1393338Y1138622D03*
X1389638D03*
X1385937D03*
X1382236D03*
X1391488Y1141811D03*
X1387787D03*
X1384086D03*
X1380386D03*
X1393338Y1145000D03*
X1389638D03*
X1385937D03*
X1382236D03*
X1391488Y1148189D03*
X1387787D03*
X1384086D03*
X1380386D03*
X1393338Y1151378D03*
X1389638D03*
X1385937D03*
X1382236D03*
X1391488Y1154567D03*
X1387787D03*
X1384086D03*
X1380386D03*
X1393338Y1157756D03*
X1389638D03*
X1385937D03*
X1382236D03*
X1391488Y1160945D03*
X1387787D03*
X1384086D03*
X1380386D03*
X1393338Y1164134D03*
X1385937D03*
X1382236D03*
X1406960Y874292D03*
X1403260D03*
X1399559D03*
X1395858D03*
X1408811Y877481D03*
X1405110D03*
X1401409D03*
X1397709D03*
X1406960Y880670D03*
X1403260D03*
X1399559D03*
X1395858D03*
X1408811Y883859D03*
X1405110D03*
X1401409D03*
X1397709D03*
X1406960Y887048D03*
X1403260D03*
X1399559D03*
X1395858D03*
X1408811Y890237D03*
X1405110D03*
X1401409D03*
X1397709D03*
X1406960Y893426D03*
X1403260D03*
X1399559D03*
X1395858D03*
X1408811Y896615D03*
X1405110D03*
X1401409D03*
X1397709D03*
X1406960Y899804D03*
X1403260D03*
X1399559D03*
X1395858D03*
X1408811Y902993D03*
X1405110D03*
X1401409D03*
X1397709D03*
X1406960Y906181D03*
X1403260D03*
X1399559D03*
X1395858D03*
X1408811Y909370D03*
X1405110D03*
X1401409D03*
X1397709D03*
X1406960Y912559D03*
X1403260D03*
X1399559D03*
X1395858D03*
X1408811Y915748D03*
X1405110D03*
X1401409D03*
X1397709D03*
X1406960Y918937D03*
X1403260D03*
X1399559D03*
X1395858D03*
X1408811Y922126D03*
X1405110D03*
X1401409D03*
X1397709D03*
X1406960Y925315D03*
X1403260D03*
X1399559D03*
X1395858D03*
X1408811Y928504D03*
X1405110D03*
X1401409D03*
X1397709D03*
X1406960Y931693D03*
X1403260D03*
X1399559D03*
X1395858D03*
X1408811Y934882D03*
X1405110D03*
X1401409D03*
X1397709D03*
X1406960Y938071D03*
X1403260D03*
X1399559D03*
X1395858D03*
X1408811Y941260D03*
X1405110D03*
X1401409D03*
X1397709D03*
X1406960Y944449D03*
X1403260D03*
X1399559D03*
X1395858D03*
X1408811Y947638D03*
X1405110D03*
X1401409D03*
X1397709D03*
X1406960Y950827D03*
X1403260D03*
X1399559D03*
X1395858D03*
X1408811Y954016D03*
X1405110D03*
X1401409D03*
X1397709D03*
X1406960Y957205D03*
X1403260D03*
X1399559D03*
X1395858D03*
X1408811Y960394D03*
X1405110D03*
X1401409D03*
X1397709D03*
X1406960Y963583D03*
X1403260D03*
X1399559D03*
X1395858D03*
X1408811Y966772D03*
X1405110D03*
X1401409D03*
X1397709D03*
X1406960Y969961D03*
X1403260D03*
X1399559D03*
X1395858D03*
X1408811Y973150D03*
X1405110D03*
X1401409D03*
X1397709D03*
X1406960Y976339D03*
X1403260D03*
X1399559D03*
X1395858D03*
X1408811Y979528D03*
X1405110D03*
X1401409D03*
X1397709D03*
X1406960Y982717D03*
X1403260D03*
X1399559D03*
X1395858D03*
X1408811Y985906D03*
X1405110D03*
X1401409D03*
X1397709D03*
X1406960Y989095D03*
X1403260D03*
X1399559D03*
X1395858D03*
X1408811Y992284D03*
X1405110D03*
X1401409D03*
X1397709D03*
X1406291Y1046142D03*
X1402590D03*
X1398890D03*
X1395189D03*
X1408142Y1049331D03*
X1404441D03*
X1400740D03*
X1397039D03*
X1406291Y1052520D03*
X1402590D03*
X1398890D03*
X1395189D03*
X1408142Y1055709D03*
X1404441D03*
X1400740D03*
X1397039D03*
X1406291Y1058898D03*
X1402590D03*
X1398890D03*
X1395189D03*
X1408142Y1062087D03*
X1404441D03*
X1400740D03*
X1397039D03*
X1406291Y1065276D03*
X1402590D03*
X1398890D03*
X1395189D03*
X1408142Y1068465D03*
X1404441D03*
X1400740D03*
X1397039D03*
X1406291Y1071654D03*
X1402590D03*
X1398890D03*
X1395189D03*
X1408142Y1074843D03*
X1404441D03*
X1400740D03*
X1397039D03*
X1406291Y1078032D03*
X1402590D03*
X1398890D03*
X1395189D03*
X1408142Y1081221D03*
X1404441D03*
X1400740D03*
X1397039D03*
X1406291Y1084410D03*
X1402590D03*
X1398890D03*
X1395189D03*
X1408142Y1087599D03*
X1404441D03*
X1400740D03*
X1397039D03*
X1406291Y1090788D03*
X1402590D03*
X1398890D03*
X1395189D03*
X1408142Y1093977D03*
X1404441D03*
X1400740D03*
X1397039D03*
X1406291Y1097166D03*
X1402590D03*
X1398890D03*
X1395189D03*
X1408142Y1100355D03*
X1404441D03*
X1400740D03*
X1397039D03*
X1406291Y1103544D03*
X1402590D03*
X1398890D03*
X1395189D03*
X1408142Y1106733D03*
X1404441D03*
X1400740D03*
X1397039D03*
X1406291Y1109922D03*
X1402590D03*
X1398890D03*
X1395189D03*
X1408142Y1113111D03*
X1404441D03*
X1400740D03*
X1397039D03*
X1406291Y1116300D03*
X1402590D03*
X1398890D03*
X1395189D03*
X1408142Y1119489D03*
X1404441D03*
X1400740D03*
X1397039D03*
X1406291Y1122678D03*
X1402590D03*
X1398890D03*
X1395189D03*
X1408142Y1125867D03*
X1404441D03*
X1400740D03*
X1397039D03*
X1406291Y1129056D03*
X1402590D03*
X1398890D03*
X1395189D03*
X1408142Y1132245D03*
X1404441D03*
X1400740D03*
X1397039D03*
X1406291Y1135433D03*
X1402590D03*
X1398890D03*
X1395189D03*
X1408142Y1138622D03*
X1404441D03*
X1400740D03*
X1397039D03*
X1406291Y1141811D03*
X1402590D03*
X1398890D03*
X1395189D03*
X1408142Y1145000D03*
X1404441D03*
X1400740D03*
X1397039D03*
X1406291Y1148189D03*
X1402590D03*
X1398890D03*
X1395189D03*
X1408142Y1151378D03*
X1404441D03*
X1400740D03*
X1397039D03*
X1406291Y1154567D03*
X1402590D03*
X1398890D03*
X1395189D03*
X1408142Y1157756D03*
X1404441D03*
X1400740D03*
X1397039D03*
X1406291Y1160945D03*
X1402590D03*
X1398890D03*
X1395189D03*
X1408142Y1164134D03*
X1404441D03*
X1400740D03*
X1397039D03*
X1423614Y877481D03*
X1419913D03*
X1412512D03*
X1421764Y880670D03*
X1410661D03*
X1423614Y883859D03*
X1419913D03*
X1412512D03*
X1421764Y887048D03*
X1410661D03*
X1423614Y890237D03*
X1419913D03*
X1412512D03*
X1421764Y893426D03*
X1410661D03*
X1423614Y896615D03*
X1419913D03*
X1412512D03*
X1421764Y899804D03*
X1410661D03*
X1423614Y902993D03*
X1419913D03*
X1412512D03*
X1421764Y906181D03*
X1410661D03*
X1423614Y909370D03*
X1419913D03*
X1412512D03*
X1421764Y912559D03*
X1410661D03*
X1423614Y915748D03*
X1419913D03*
X1412512D03*
X1421764Y918937D03*
X1410661D03*
X1423614Y922126D03*
X1419913D03*
X1412512D03*
X1421764Y925315D03*
X1410661D03*
X1423614Y928504D03*
X1419913D03*
X1412512D03*
X1421764Y931693D03*
X1410661D03*
X1423614Y934882D03*
X1419913D03*
X1412512D03*
X1421764Y938071D03*
X1410661D03*
X1423614Y941260D03*
X1419913D03*
X1412512D03*
X1421764Y944449D03*
X1410661D03*
X1423614Y947638D03*
X1419913D03*
X1412512D03*
X1421764Y950827D03*
X1410661D03*
X1423614Y954016D03*
X1419913D03*
X1412512D03*
X1421764Y957205D03*
X1410661D03*
X1423614Y960394D03*
X1419913D03*
X1412512D03*
X1421764Y963583D03*
X1410661D03*
X1423614Y966772D03*
X1419913D03*
X1412512D03*
X1421764Y969961D03*
X1410661D03*
X1423614Y973150D03*
X1419913D03*
X1412512D03*
X1421764Y976339D03*
X1410661D03*
X1423614Y979528D03*
X1419913D03*
X1412512D03*
X1421764Y982717D03*
X1410661D03*
X1423614Y985906D03*
X1419913D03*
X1412512D03*
X1421764Y989095D03*
X1410661D03*
X1423614Y992284D03*
X1419913D03*
X1412512D03*
X1421094Y1046142D03*
X1413693D03*
X1409992D03*
X1422945Y1049331D03*
X1411842D03*
X1421094Y1052520D03*
X1413693D03*
X1409992D03*
X1422945Y1055709D03*
X1411842D03*
X1421094Y1058898D03*
X1413693D03*
X1409992D03*
X1422945Y1062087D03*
X1411842D03*
X1421094Y1065276D03*
X1413693D03*
X1409992D03*
X1422945Y1068465D03*
X1411842D03*
X1421094Y1071654D03*
X1413693D03*
X1409992D03*
X1422945Y1074843D03*
X1411842D03*
X1421094Y1078032D03*
X1413693D03*
X1409992D03*
X1422945Y1081221D03*
X1411842D03*
X1421094Y1084410D03*
X1413693D03*
X1409992D03*
X1422945Y1087599D03*
X1411842D03*
X1421094Y1090788D03*
X1413693D03*
X1409992D03*
X1422945Y1093977D03*
X1411842D03*
X1421094Y1097166D03*
X1413693D03*
X1409992D03*
X1422945Y1100355D03*
X1411842D03*
X1421094Y1103544D03*
X1413693D03*
X1409992D03*
X1422945Y1106733D03*
X1411842D03*
X1421094Y1109922D03*
X1413693D03*
X1409992D03*
X1422945Y1113111D03*
X1411842D03*
X1421094Y1116300D03*
X1413693D03*
X1409992D03*
X1422945Y1119489D03*
X1411842D03*
X1421094Y1122678D03*
X1413693D03*
X1409992D03*
X1422945Y1125867D03*
X1411842D03*
X1421094Y1129056D03*
X1413693D03*
X1409992D03*
X1422945Y1132245D03*
X1411842D03*
X1421094Y1135433D03*
X1413693D03*
X1409992D03*
X1422945Y1138622D03*
X1411842D03*
X1421094Y1141811D03*
X1413693D03*
X1409992D03*
X1422945Y1145000D03*
X1411842D03*
X1421094Y1148189D03*
X1413693D03*
X1409992D03*
X1422945Y1151378D03*
X1411842D03*
X1421094Y1154567D03*
X1413693D03*
X1409992D03*
X1422945Y1157756D03*
X1411842D03*
X1421094Y1160945D03*
X1413693D03*
X1409992D03*
X1436567Y874292D03*
X1432866D03*
X1429165D03*
X1425464D03*
X1438417Y877481D03*
X1434716D03*
X1431016D03*
X1427315D03*
X1436567Y880670D03*
X1432866D03*
X1429165D03*
X1425464D03*
X1438417Y883859D03*
X1434716D03*
X1431016D03*
X1427315D03*
X1436567Y887048D03*
X1432866D03*
X1429165D03*
X1425464D03*
X1438417Y890237D03*
X1434716D03*
X1431016D03*
X1427315D03*
X1436567Y893426D03*
X1432866D03*
X1429165D03*
X1425464D03*
X1438417Y896615D03*
X1434716D03*
X1431016D03*
X1427315D03*
X1436567Y899804D03*
X1432866D03*
X1429165D03*
X1425464D03*
X1438417Y902993D03*
X1434716D03*
X1431016D03*
X1427315D03*
X1436567Y906181D03*
X1432866D03*
X1429165D03*
X1425464D03*
X1438417Y909370D03*
X1434716D03*
X1431016D03*
X1427315D03*
X1436567Y912559D03*
X1432866D03*
X1429165D03*
X1425464D03*
X1438417Y915748D03*
X1434716D03*
X1431016D03*
X1427315D03*
X1436567Y918937D03*
X1432866D03*
X1429165D03*
X1425464D03*
X1438417Y922126D03*
X1434716D03*
X1431016D03*
X1427315D03*
X1436567Y925315D03*
X1432866D03*
X1429165D03*
X1425464D03*
X1438417Y928504D03*
X1434716D03*
X1431016D03*
X1427315D03*
X1436567Y931693D03*
X1432866D03*
X1429165D03*
X1425464D03*
X1438417Y934882D03*
X1434716D03*
X1431016D03*
X1427315D03*
X1436567Y938071D03*
X1432866D03*
X1429165D03*
X1425464D03*
X1438417Y941260D03*
X1434716D03*
X1431016D03*
X1427315D03*
X1436567Y944449D03*
X1432866D03*
X1429165D03*
X1425464D03*
X1438417Y947638D03*
X1434716D03*
X1431016D03*
X1427315D03*
X1436567Y950827D03*
X1432866D03*
X1429165D03*
X1425464D03*
X1438417Y954016D03*
X1434716D03*
X1431016D03*
X1427315D03*
X1436567Y957205D03*
X1432866D03*
X1429165D03*
X1425464D03*
X1438417Y960394D03*
X1434716D03*
X1431016D03*
X1427315D03*
X1436567Y963583D03*
X1432866D03*
X1429165D03*
X1425464D03*
X1438417Y966772D03*
X1434716D03*
X1431016D03*
X1427315D03*
X1436567Y969961D03*
X1432866D03*
X1429165D03*
X1425464D03*
X1438417Y973150D03*
X1434716D03*
X1431016D03*
X1427315D03*
X1436567Y976339D03*
X1432866D03*
X1429165D03*
X1425464D03*
X1438417Y979528D03*
X1434716D03*
X1431016D03*
X1427315D03*
X1436567Y982717D03*
X1432866D03*
X1429165D03*
X1425464D03*
X1438417Y985906D03*
X1434716D03*
X1431016D03*
X1427315D03*
X1436567Y989095D03*
X1432866D03*
X1429165D03*
X1425464D03*
X1438417Y992284D03*
X1434716D03*
X1431016D03*
X1427315D03*
X1435897Y1046142D03*
X1432197D03*
X1428496D03*
X1424795D03*
X1437748Y1049331D03*
X1434047D03*
X1430346D03*
X1426646D03*
X1435897Y1052520D03*
X1432197D03*
X1428496D03*
X1424795D03*
X1437748Y1055709D03*
X1434047D03*
X1430346D03*
X1426646D03*
X1435897Y1058898D03*
X1432197D03*
X1428496D03*
X1424795D03*
X1437748Y1062087D03*
X1434047D03*
X1430346D03*
X1426646D03*
X1435897Y1065276D03*
X1432197D03*
X1428496D03*
X1424795D03*
X1437748Y1068465D03*
X1434047D03*
X1430346D03*
X1426646D03*
X1435897Y1071654D03*
X1432197D03*
X1428496D03*
X1424795D03*
X1437748Y1074843D03*
X1434047D03*
X1430346D03*
X1426646D03*
X1435897Y1078032D03*
X1432197D03*
X1428496D03*
X1424795D03*
X1437748Y1081221D03*
X1434047D03*
X1430346D03*
X1426646D03*
X1435897Y1084410D03*
X1432197D03*
X1428496D03*
X1424795D03*
X1437748Y1087599D03*
X1434047D03*
X1430346D03*
X1426646D03*
X1435897Y1090788D03*
X1432197D03*
X1428496D03*
X1424795D03*
X1437748Y1093977D03*
X1434047D03*
X1430346D03*
X1426646D03*
X1435897Y1097166D03*
X1432197D03*
X1428496D03*
X1424795D03*
X1437748Y1100355D03*
X1434047D03*
X1430346D03*
X1426646D03*
X1435897Y1103544D03*
X1432197D03*
X1428496D03*
X1424795D03*
X1437748Y1106733D03*
X1434047D03*
X1430346D03*
X1426646D03*
X1435897Y1109922D03*
X1432197D03*
X1428496D03*
X1424795D03*
X1437748Y1113111D03*
X1434047D03*
X1430346D03*
X1426646D03*
X1435897Y1116300D03*
X1432197D03*
X1428496D03*
X1424795D03*
X1437748Y1119489D03*
X1434047D03*
X1430346D03*
X1426646D03*
X1435897Y1122678D03*
X1432197D03*
X1428496D03*
X1424795D03*
X1437748Y1125867D03*
X1434047D03*
X1430346D03*
X1426646D03*
X1435897Y1129056D03*
X1432197D03*
X1428496D03*
X1424795D03*
X1437748Y1132245D03*
X1434047D03*
X1430346D03*
X1426646D03*
X1435897Y1135433D03*
X1432197D03*
X1428496D03*
X1424795D03*
X1437748Y1138622D03*
X1434047D03*
X1430346D03*
X1426646D03*
X1435897Y1141811D03*
X1432197D03*
X1428496D03*
X1424795D03*
X1437748Y1145000D03*
X1434047D03*
X1430346D03*
X1426646D03*
X1435897Y1148189D03*
X1432197D03*
X1428496D03*
X1424795D03*
X1437748Y1151378D03*
X1434047D03*
X1430346D03*
X1426646D03*
X1435897Y1154567D03*
X1432197D03*
X1428496D03*
X1424795D03*
X1437748Y1157756D03*
X1434047D03*
X1430346D03*
X1426646D03*
X1435897Y1160945D03*
X1432197D03*
X1428496D03*
X1424795D03*
X1437748Y1164134D03*
X1434047D03*
X1430346D03*
X1426646D03*
X1451370Y874292D03*
X1447669D03*
X1440268D03*
X1453220Y877481D03*
X1449520D03*
X1445819D03*
X1442118D03*
X1451370Y880670D03*
X1447669D03*
X1443968D03*
X1440268D03*
X1453220Y883859D03*
X1449520D03*
X1445819D03*
X1442118D03*
X1451370Y887048D03*
X1447669D03*
X1443968D03*
X1440268D03*
X1453220Y890237D03*
X1449520D03*
X1445819D03*
X1442118D03*
X1451370Y893426D03*
X1447669D03*
X1443968D03*
X1440268D03*
X1453220Y896615D03*
X1449520D03*
X1445819D03*
X1442118D03*
X1451370Y899804D03*
X1447669D03*
X1443968D03*
X1440268D03*
X1453220Y902993D03*
X1449520D03*
X1445819D03*
X1442118D03*
X1451370Y906181D03*
X1447669D03*
X1443968D03*
X1440268D03*
X1453220Y909370D03*
X1449520D03*
X1445819D03*
X1442118D03*
X1451370Y912559D03*
X1447669D03*
X1443968D03*
X1440268D03*
X1453220Y915748D03*
X1449520D03*
X1445819D03*
X1442118D03*
X1451370Y918937D03*
X1447669D03*
X1443968D03*
X1440268D03*
X1453220Y922126D03*
X1449520D03*
X1445819D03*
X1442118D03*
X1451370Y925315D03*
X1447669D03*
X1443968D03*
X1440268D03*
X1453220Y928504D03*
X1449520D03*
X1445819D03*
X1442118D03*
X1451370Y931693D03*
X1447669D03*
X1443968D03*
X1440268D03*
X1453220Y934882D03*
X1449520D03*
X1445819D03*
X1442118D03*
X1451370Y938071D03*
X1447669D03*
X1443968D03*
X1440268D03*
X1453220Y941260D03*
X1449520D03*
X1445819D03*
X1442118D03*
X1451370Y944449D03*
X1447669D03*
X1443968D03*
X1440268D03*
X1453220Y947638D03*
X1449520D03*
X1445819D03*
X1442118D03*
X1451370Y950827D03*
X1447669D03*
X1443968D03*
X1440268D03*
X1453220Y954016D03*
X1449520D03*
X1445819D03*
X1442118D03*
X1451370Y957205D03*
X1447669D03*
X1443968D03*
X1440268D03*
X1453220Y960394D03*
X1449520D03*
X1445819D03*
X1442118D03*
X1451370Y963583D03*
X1447669D03*
X1443968D03*
X1440268D03*
X1453220Y966772D03*
X1449520D03*
X1445819D03*
X1442118D03*
X1451370Y969961D03*
X1447669D03*
X1443968D03*
X1440268D03*
X1453220Y973150D03*
X1449520D03*
X1445819D03*
X1442118D03*
X1451370Y976339D03*
X1447669D03*
X1443968D03*
X1440268D03*
X1453220Y979528D03*
X1449520D03*
X1445819D03*
X1442118D03*
X1451370Y982717D03*
X1447669D03*
X1443968D03*
X1440268D03*
X1453220Y985906D03*
X1449520D03*
X1445819D03*
X1442118D03*
X1451370Y989095D03*
X1447669D03*
X1443968D03*
X1440268D03*
X1453220Y992284D03*
X1449520D03*
X1445819D03*
X1442118D03*
X1451370Y995473D03*
X1453220Y998662D03*
X1451370Y1001851D03*
X1453220Y1005040D03*
X1451370Y1008229D03*
X1453220Y1011418D03*
X1452551Y1030197D03*
Y1036575D03*
Y1042953D03*
X1450701Y1046142D03*
X1447000D03*
X1443299D03*
X1439598D03*
X1452551Y1049331D03*
X1448850D03*
X1445149D03*
X1441449D03*
X1450701Y1052520D03*
X1447000D03*
X1443299D03*
X1439598D03*
X1452551Y1055709D03*
X1448850D03*
X1445149D03*
X1441449D03*
X1450701Y1058898D03*
X1447000D03*
X1443299D03*
X1439598D03*
X1452551Y1062087D03*
X1448850D03*
X1445149D03*
X1441449D03*
X1450701Y1065276D03*
X1447000D03*
X1443299D03*
X1439598D03*
X1452551Y1068465D03*
X1448850D03*
X1445149D03*
X1441449D03*
X1450701Y1071654D03*
X1447000D03*
X1443299D03*
X1439598D03*
X1452551Y1074843D03*
X1448850D03*
X1445149D03*
X1441449D03*
X1450701Y1078032D03*
X1447000D03*
X1443299D03*
X1439598D03*
X1452551Y1081221D03*
X1448850D03*
X1445149D03*
X1441449D03*
X1450701Y1084410D03*
X1447000D03*
X1443299D03*
X1439598D03*
X1452551Y1087599D03*
X1448850D03*
X1445149D03*
X1441449D03*
X1450701Y1090788D03*
X1447000D03*
X1443299D03*
X1439598D03*
X1452551Y1093977D03*
X1448850D03*
X1445149D03*
X1441449D03*
X1450701Y1097166D03*
X1447000D03*
X1443299D03*
X1439598D03*
X1452551Y1100355D03*
X1448850D03*
X1445149D03*
X1441449D03*
X1450701Y1103544D03*
X1447000D03*
X1443299D03*
X1439598D03*
X1452551Y1106733D03*
X1448850D03*
X1445149D03*
X1441449D03*
X1450701Y1109922D03*
X1447000D03*
X1443299D03*
X1439598D03*
X1452551Y1113111D03*
X1448850D03*
X1445149D03*
X1441449D03*
X1450701Y1116300D03*
X1447000D03*
X1443299D03*
X1439598D03*
X1452551Y1119489D03*
X1448850D03*
X1445149D03*
X1441449D03*
X1450701Y1122678D03*
X1447000D03*
X1443299D03*
X1439598D03*
X1452551Y1125867D03*
X1448850D03*
X1445149D03*
X1441449D03*
X1450701Y1129056D03*
X1447000D03*
X1443299D03*
X1439598D03*
X1452551Y1132245D03*
X1448850D03*
X1445149D03*
X1441449D03*
X1450701Y1135433D03*
X1447000D03*
X1443299D03*
X1439598D03*
X1452551Y1138622D03*
X1448850D03*
X1445149D03*
X1441449D03*
X1450701Y1141811D03*
X1447000D03*
X1443299D03*
X1439598D03*
X1452551Y1145000D03*
X1448850D03*
X1445149D03*
X1441449D03*
X1450701Y1148189D03*
X1447000D03*
X1443299D03*
X1439598D03*
X1452551Y1151378D03*
X1448850D03*
X1445149D03*
X1441449D03*
X1450701Y1154567D03*
X1447000D03*
X1443299D03*
X1439598D03*
X1452551Y1157756D03*
X1448850D03*
X1445149D03*
X1441449D03*
X1450701Y1160945D03*
X1447000D03*
X1443299D03*
X1439598D03*
X1452551Y1164134D03*
X1448850D03*
X1441449D03*
X1462472Y874292D03*
X1458771D03*
X1455071D03*
X1468023Y877481D03*
X1464323D03*
X1460622D03*
X1456921D03*
X1466173Y880670D03*
X1462472D03*
X1458771D03*
X1455071D03*
X1468023Y883859D03*
X1464323D03*
X1460622D03*
X1456921D03*
X1466173Y887048D03*
X1462472D03*
X1458771D03*
X1455071D03*
X1468023Y890237D03*
X1464323D03*
X1460622D03*
X1456921D03*
X1466173Y893426D03*
X1462472D03*
X1458771D03*
X1455071D03*
X1468023Y896615D03*
X1464323D03*
X1460622D03*
X1456921D03*
X1466173Y899804D03*
X1462472D03*
X1458771D03*
X1455071D03*
X1468023Y902993D03*
X1464323D03*
X1460622D03*
X1456921D03*
X1466173Y906181D03*
X1462472D03*
X1458771D03*
X1455071D03*
X1468023Y909370D03*
X1464323D03*
X1460622D03*
X1456921D03*
X1466173Y912559D03*
X1462472D03*
X1458771D03*
X1455071D03*
X1468023Y915748D03*
X1464323D03*
X1460622D03*
X1456921D03*
X1466173Y918937D03*
X1462472D03*
X1458771D03*
X1455071D03*
X1468023Y922126D03*
X1464323D03*
X1460622D03*
X1456921D03*
X1466173Y925315D03*
X1462472D03*
X1458771D03*
X1455071D03*
X1468023Y928504D03*
X1464323D03*
X1460622D03*
X1456921D03*
X1466173Y931693D03*
X1462472D03*
X1458771D03*
X1455071D03*
X1468023Y934882D03*
X1464323D03*
X1460622D03*
X1456921D03*
X1466173Y938071D03*
X1462472D03*
X1458771D03*
X1455071D03*
X1468023Y941260D03*
X1464323D03*
X1460622D03*
X1456921D03*
X1466173Y944449D03*
X1462472D03*
X1458771D03*
X1455071D03*
X1468023Y947638D03*
X1464323D03*
X1460622D03*
X1456921D03*
X1466173Y950827D03*
X1462472D03*
X1458771D03*
X1455071D03*
X1468023Y954016D03*
X1464323D03*
X1460622D03*
X1456921D03*
X1466173Y957205D03*
X1462472D03*
X1458771D03*
X1455071D03*
X1468023Y960394D03*
X1464323D03*
X1460622D03*
X1456921D03*
X1466173Y963583D03*
X1462472D03*
X1458771D03*
X1455071D03*
X1468023Y966772D03*
X1464323D03*
X1460622D03*
X1456921D03*
X1466173Y969961D03*
X1462472D03*
X1458771D03*
X1455071D03*
X1468023Y973150D03*
X1464323D03*
X1460622D03*
X1456921D03*
X1466173Y976339D03*
X1462472D03*
X1458771D03*
X1455071D03*
X1468023Y979528D03*
X1464323D03*
X1460622D03*
X1456921D03*
X1466173Y982717D03*
X1462472D03*
X1458771D03*
X1455071D03*
X1468023Y985906D03*
X1464323D03*
X1460622D03*
X1456921D03*
X1466173Y989095D03*
X1462472D03*
X1458771D03*
X1455071D03*
X1468023Y992284D03*
X1464323D03*
X1460622D03*
X1456921D03*
X1466173Y995473D03*
X1462472D03*
X1458771D03*
X1455071D03*
X1468023Y998662D03*
X1464323D03*
X1460622D03*
X1456921D03*
X1466173Y1001851D03*
X1462472D03*
X1458771D03*
X1455071D03*
X1468023Y1005040D03*
X1464323D03*
X1460622D03*
X1456921D03*
X1466173Y1008229D03*
X1462472D03*
X1458771D03*
X1455071D03*
X1468023Y1011418D03*
X1464323D03*
X1460622D03*
X1456921D03*
X1465504Y1027008D03*
X1461803D03*
X1458102D03*
X1454401D03*
X1467354Y1030197D03*
X1463653D03*
X1459953D03*
X1456252D03*
X1465504Y1033386D03*
X1461803D03*
X1458102D03*
X1454401D03*
X1467354Y1036575D03*
X1463653D03*
X1459953D03*
X1456252D03*
X1465504Y1039764D03*
X1461803D03*
X1458102D03*
X1454401D03*
X1467354Y1042953D03*
X1463653D03*
X1459953D03*
X1456252D03*
X1465504Y1046142D03*
X1461803D03*
X1458102D03*
X1454401D03*
X1467354Y1049331D03*
X1463653D03*
X1459953D03*
X1456252D03*
X1465504Y1052520D03*
X1461803D03*
X1458102D03*
X1454401D03*
X1467354Y1055709D03*
X1463653D03*
X1459953D03*
X1456252D03*
X1465504Y1058898D03*
X1461803D03*
X1458102D03*
X1454401D03*
X1467354Y1062087D03*
X1463653D03*
X1459953D03*
X1456252D03*
X1465504Y1065276D03*
X1461803D03*
X1458102D03*
X1454401D03*
X1467354Y1068465D03*
X1463653D03*
X1459953D03*
X1456252D03*
X1465504Y1071654D03*
X1461803D03*
X1458102D03*
X1454401D03*
X1467354Y1074843D03*
X1463653D03*
X1459953D03*
X1456252D03*
X1465504Y1078032D03*
X1461803D03*
X1458102D03*
X1454401D03*
X1467354Y1081221D03*
X1463653D03*
X1459953D03*
X1456252D03*
X1465504Y1084410D03*
X1461803D03*
X1458102D03*
X1454401D03*
X1467354Y1087599D03*
X1463653D03*
X1459953D03*
X1456252D03*
X1465504Y1090788D03*
X1461803D03*
X1458102D03*
X1454401D03*
X1467354Y1093977D03*
X1463653D03*
X1459953D03*
X1456252D03*
X1465504Y1097166D03*
X1461803D03*
X1458102D03*
X1454401D03*
X1467354Y1100355D03*
X1463653D03*
X1459953D03*
X1456252D03*
X1465504Y1103544D03*
X1461803D03*
X1458102D03*
X1454401D03*
X1467354Y1106733D03*
X1463653D03*
X1459953D03*
X1456252D03*
X1465504Y1109922D03*
X1461803D03*
X1458102D03*
X1454401D03*
X1467354Y1113111D03*
X1463653D03*
X1459953D03*
X1456252D03*
X1465504Y1116300D03*
X1461803D03*
X1458102D03*
X1454401D03*
X1467354Y1119489D03*
X1463653D03*
X1459953D03*
X1456252D03*
X1465504Y1122678D03*
X1461803D03*
X1458102D03*
X1454401D03*
X1467354Y1125867D03*
X1463653D03*
X1459953D03*
X1456252D03*
X1465504Y1129056D03*
X1461803D03*
X1458102D03*
X1454401D03*
X1467354Y1132245D03*
X1463653D03*
X1459953D03*
X1456252D03*
X1465504Y1135433D03*
X1461803D03*
X1458102D03*
X1454401D03*
X1467354Y1138622D03*
X1463653D03*
X1459953D03*
X1456252D03*
X1465504Y1141811D03*
X1461803D03*
X1458102D03*
X1454401D03*
X1467354Y1145000D03*
X1463653D03*
X1459953D03*
X1456252D03*
X1465504Y1148189D03*
X1461803D03*
X1458102D03*
X1454401D03*
X1467354Y1151378D03*
X1463653D03*
X1459953D03*
X1456252D03*
X1465504Y1154567D03*
X1461803D03*
X1458102D03*
X1454401D03*
X1467354Y1157756D03*
X1463653D03*
X1459953D03*
X1456252D03*
X1465504Y1160945D03*
X1461803D03*
X1458102D03*
X1454401D03*
X1463653Y1164134D03*
X1459953D03*
X1456252D03*
X1480976Y874292D03*
X1477275D03*
X1473575D03*
X1469874D03*
X1482827Y877481D03*
X1479126D03*
X1475425D03*
X1471724D03*
X1480976Y880670D03*
X1477275D03*
X1473575D03*
X1469874D03*
X1482827Y883859D03*
X1479126D03*
X1475425D03*
X1471724D03*
X1480976Y887048D03*
X1477275D03*
X1473575D03*
X1469874D03*
X1482827Y890237D03*
X1479126D03*
X1475425D03*
X1471724D03*
X1480976Y893426D03*
X1477275D03*
X1473575D03*
X1469874D03*
X1482827Y896615D03*
X1479126D03*
X1475425D03*
X1471724D03*
X1480976Y899804D03*
X1477275D03*
X1473575D03*
X1469874D03*
X1482827Y902993D03*
X1479126D03*
X1475425D03*
X1471724D03*
X1480976Y906181D03*
X1477275D03*
X1473575D03*
X1469874D03*
X1482827Y909370D03*
X1479126D03*
X1475425D03*
X1471724D03*
X1480976Y912559D03*
X1477275D03*
X1473575D03*
X1469874D03*
X1482827Y915748D03*
X1479126D03*
X1475425D03*
X1471724D03*
X1480976Y918937D03*
X1477275D03*
X1473575D03*
X1469874D03*
X1482827Y922126D03*
X1479126D03*
X1475425D03*
X1471724D03*
X1480976Y925315D03*
X1477275D03*
X1473575D03*
X1469874D03*
X1482827Y928504D03*
X1479126D03*
X1475425D03*
X1471724D03*
X1480976Y931693D03*
X1477275D03*
X1473575D03*
X1469874D03*
X1482827Y934882D03*
X1479126D03*
X1475425D03*
X1471724D03*
X1480976Y938071D03*
X1477275D03*
X1473575D03*
X1469874D03*
X1482827Y941260D03*
X1479126D03*
X1475425D03*
X1471724D03*
X1480976Y944449D03*
X1477275D03*
X1473575D03*
X1469874D03*
X1482827Y947638D03*
X1479126D03*
X1475425D03*
X1471724D03*
X1480976Y950827D03*
X1477275D03*
X1473575D03*
X1469874D03*
X1482827Y954016D03*
X1479126D03*
X1475425D03*
X1471724D03*
X1480976Y957205D03*
X1477275D03*
X1473575D03*
X1469874D03*
X1482827Y960394D03*
X1479126D03*
X1475425D03*
X1471724D03*
X1480976Y963583D03*
X1477275D03*
X1473575D03*
X1469874D03*
X1482827Y966772D03*
X1479126D03*
X1475425D03*
X1471724D03*
X1480976Y969961D03*
X1477275D03*
X1473575D03*
X1469874D03*
X1482827Y973150D03*
X1479126D03*
X1475425D03*
X1471724D03*
X1480976Y976339D03*
X1477275D03*
X1473575D03*
X1469874D03*
X1482827Y979528D03*
X1479126D03*
X1475425D03*
X1471724D03*
X1480976Y982717D03*
X1477275D03*
X1473575D03*
X1469874D03*
X1482827Y985906D03*
X1479126D03*
X1475425D03*
X1471724D03*
X1480976Y989095D03*
X1477275D03*
X1473575D03*
X1469874D03*
X1482827Y992284D03*
X1479126D03*
X1475425D03*
X1471724D03*
X1480976Y995473D03*
X1477275D03*
X1473575D03*
X1469874D03*
X1482827Y998662D03*
X1479126D03*
X1475425D03*
X1471724D03*
X1480976Y1001851D03*
X1477275D03*
X1473575D03*
X1469874D03*
X1482827Y1005040D03*
X1479126D03*
X1475425D03*
X1471724D03*
X1480976Y1008229D03*
X1477275D03*
X1473575D03*
X1469874D03*
X1482827Y1011418D03*
X1479126D03*
X1475425D03*
X1471724D03*
X1480307Y1027008D03*
X1476606D03*
X1472905D03*
X1469205D03*
X1482157Y1030197D03*
X1478457D03*
X1474756D03*
X1471055D03*
X1480307Y1033386D03*
X1476606D03*
X1472905D03*
X1469205D03*
X1482157Y1036575D03*
X1478457D03*
X1474756D03*
X1471055D03*
X1480307Y1039764D03*
X1476606D03*
X1472905D03*
X1469205D03*
X1482157Y1042953D03*
X1478457D03*
X1474756D03*
X1471055D03*
X1480307Y1046142D03*
X1476606D03*
X1472905D03*
X1469205D03*
X1482157Y1049331D03*
X1478457D03*
X1474756D03*
X1471055D03*
X1480307Y1052520D03*
X1476606D03*
X1472905D03*
X1469205D03*
X1482157Y1055709D03*
X1478457D03*
X1474756D03*
X1471055D03*
X1480307Y1058898D03*
X1476606D03*
X1472905D03*
X1469205D03*
X1482157Y1062087D03*
X1478457D03*
X1474756D03*
X1471055D03*
X1480307Y1065276D03*
X1476606D03*
X1472905D03*
X1469205D03*
X1482157Y1068465D03*
X1478457D03*
X1474756D03*
X1471055D03*
X1480307Y1071654D03*
X1476606D03*
X1472905D03*
X1469205D03*
X1482157Y1074843D03*
X1478457D03*
X1474756D03*
X1471055D03*
X1480307Y1078032D03*
X1476606D03*
X1472905D03*
X1469205D03*
X1482157Y1081221D03*
X1478457D03*
X1474756D03*
X1471055D03*
X1480307Y1084410D03*
X1476606D03*
X1472905D03*
X1469205D03*
X1482157Y1087599D03*
X1478457D03*
X1474756D03*
X1471055D03*
X1480307Y1090788D03*
X1476606D03*
X1472905D03*
X1469205D03*
X1482157Y1093977D03*
X1478457D03*
X1474756D03*
X1471055D03*
X1480307Y1097166D03*
X1476606D03*
X1472905D03*
X1469205D03*
X1482157Y1100355D03*
X1478457D03*
X1474756D03*
X1471055D03*
X1480307Y1103544D03*
X1476606D03*
X1472905D03*
X1469205D03*
X1482157Y1106733D03*
X1478457D03*
X1474756D03*
X1471055D03*
X1480307Y1109922D03*
X1476606D03*
X1472905D03*
X1469205D03*
X1482157Y1113111D03*
X1478457D03*
X1474756D03*
X1471055D03*
X1480307Y1116300D03*
X1476606D03*
X1472905D03*
X1469205D03*
X1482157Y1119489D03*
X1478457D03*
X1474756D03*
X1471055D03*
X1480307Y1122678D03*
X1476606D03*
X1472905D03*
X1469205D03*
X1482157Y1125867D03*
X1478457D03*
X1474756D03*
X1471055D03*
X1480307Y1129056D03*
X1476606D03*
X1472905D03*
X1469205D03*
X1482157Y1132245D03*
X1478457D03*
X1474756D03*
X1471055D03*
X1480307Y1135433D03*
X1476606D03*
X1472905D03*
X1469205D03*
X1482157Y1138622D03*
X1478457D03*
X1474756D03*
X1471055D03*
X1480307Y1141811D03*
X1476606D03*
X1472905D03*
X1469205D03*
X1482157Y1145000D03*
X1478457D03*
X1474756D03*
X1471055D03*
X1480307Y1148189D03*
X1476606D03*
X1472905D03*
X1469205D03*
X1482157Y1151378D03*
X1478457D03*
X1474756D03*
X1471055D03*
X1480307Y1154567D03*
X1476606D03*
X1472905D03*
X1469205D03*
X1482157Y1157756D03*
X1478457D03*
X1474756D03*
X1471055D03*
X1480307Y1160945D03*
X1476606D03*
X1472905D03*
X1469205D03*
X1482157Y1164134D03*
X1478457D03*
X1474756D03*
X1471055D03*
X1495779Y874292D03*
X1492079D03*
X1484677D03*
X1497630Y877481D03*
X1493929D03*
X1490228D03*
X1486527D03*
X1495779Y880670D03*
X1492079D03*
X1488378D03*
X1484677D03*
X1497630Y883859D03*
X1493929D03*
X1490228D03*
X1486527D03*
X1495779Y887048D03*
X1492079D03*
X1488378D03*
X1484677D03*
X1497630Y890237D03*
X1493929D03*
X1490228D03*
X1486527D03*
X1495779Y893426D03*
X1492079D03*
X1488378D03*
X1484677D03*
X1497630Y896615D03*
X1493929D03*
X1490228D03*
X1486527D03*
X1495779Y899804D03*
X1492079D03*
X1488378D03*
X1484677D03*
X1497630Y902993D03*
X1493929D03*
X1490228D03*
X1486527D03*
X1495779Y906181D03*
X1492079D03*
X1488378D03*
X1484677D03*
X1497630Y909370D03*
X1493929D03*
X1490228D03*
X1486527D03*
X1495779Y912559D03*
X1492079D03*
X1488378D03*
X1484677D03*
X1497630Y915748D03*
X1493929D03*
X1490228D03*
X1486527D03*
X1495779Y918937D03*
X1492079D03*
X1488378D03*
X1484677D03*
X1497630Y922126D03*
X1493929D03*
X1490228D03*
X1486527D03*
X1495779Y925315D03*
X1492079D03*
X1488378D03*
X1484677D03*
X1497630Y928504D03*
X1493929D03*
X1490228D03*
X1486527D03*
X1495779Y931693D03*
X1492079D03*
X1488378D03*
X1484677D03*
X1497630Y934882D03*
X1493929D03*
X1490228D03*
X1486527D03*
X1495779Y938071D03*
X1492079D03*
X1488378D03*
X1484677D03*
X1497630Y941260D03*
X1493929D03*
X1490228D03*
X1486527D03*
X1495779Y944449D03*
X1492079D03*
X1488378D03*
X1484677D03*
X1497630Y947638D03*
X1493929D03*
X1490228D03*
X1486527D03*
X1495779Y950827D03*
X1492079D03*
X1488378D03*
X1484677D03*
X1497630Y954016D03*
X1493929D03*
X1490228D03*
X1486527D03*
X1495779Y957205D03*
X1492079D03*
X1488378D03*
X1484677D03*
X1497630Y960394D03*
X1493929D03*
X1490228D03*
X1486527D03*
X1495779Y963583D03*
X1492079D03*
X1488378D03*
X1484677D03*
X1497630Y966772D03*
X1493929D03*
X1490228D03*
X1486527D03*
X1495779Y969961D03*
X1492079D03*
X1488378D03*
X1484677D03*
X1497630Y973150D03*
X1493929D03*
X1490228D03*
X1486527D03*
X1495779Y976339D03*
X1492079D03*
X1488378D03*
X1484677D03*
X1497630Y979528D03*
X1493929D03*
X1490228D03*
X1486527D03*
X1495779Y982717D03*
X1492079D03*
X1488378D03*
X1484677D03*
X1497630Y985906D03*
X1493929D03*
X1490228D03*
X1486527D03*
X1495779Y989095D03*
X1492079D03*
X1488378D03*
X1484677D03*
X1497630Y992284D03*
X1493929D03*
X1490228D03*
X1486527D03*
X1495779Y995473D03*
X1492079D03*
X1488378D03*
X1484677D03*
X1497630Y998662D03*
X1493929D03*
X1490228D03*
X1486527D03*
X1495779Y1001851D03*
X1492079D03*
X1488378D03*
X1484677D03*
X1497630Y1005040D03*
X1493929D03*
X1490228D03*
X1486527D03*
X1495779Y1008229D03*
X1492079D03*
X1488378D03*
X1484677D03*
X1497630Y1011418D03*
X1493929D03*
X1490228D03*
X1486527D03*
X1495110Y1027008D03*
X1491409D03*
X1487709D03*
X1484008D03*
X1496960Y1030197D03*
X1493260D03*
X1489559D03*
X1485858D03*
X1495110Y1033386D03*
X1491409D03*
X1487709D03*
X1484008D03*
X1496960Y1036575D03*
X1493260D03*
X1489559D03*
X1485858D03*
X1495110Y1039764D03*
X1491409D03*
X1487709D03*
X1484008D03*
X1496960Y1042953D03*
X1493260D03*
X1489559D03*
X1485858D03*
X1495110Y1046142D03*
X1491409D03*
X1487709D03*
X1484008D03*
X1496960Y1049331D03*
X1493260D03*
X1489559D03*
X1485858D03*
X1495110Y1052520D03*
X1491409D03*
X1487709D03*
X1484008D03*
X1496960Y1055709D03*
X1493260D03*
X1489559D03*
X1485858D03*
X1495110Y1058898D03*
X1491409D03*
X1487709D03*
X1484008D03*
X1496960Y1062087D03*
X1493260D03*
X1489559D03*
X1485858D03*
X1495110Y1065276D03*
X1491409D03*
X1487709D03*
X1484008D03*
X1496960Y1068465D03*
X1493260D03*
X1489559D03*
X1485858D03*
X1495110Y1071654D03*
X1491409D03*
X1487709D03*
X1484008D03*
X1496960Y1074843D03*
X1493260D03*
X1489559D03*
X1485858D03*
X1495110Y1078032D03*
X1491409D03*
X1487709D03*
X1484008D03*
X1496960Y1081221D03*
X1493260D03*
X1489559D03*
X1485858D03*
X1495110Y1084410D03*
X1491409D03*
X1487709D03*
X1484008D03*
X1496960Y1087599D03*
X1493260D03*
X1489559D03*
X1485858D03*
X1495110Y1090788D03*
X1491409D03*
X1487709D03*
X1484008D03*
X1496960Y1093977D03*
X1493260D03*
X1489559D03*
X1485858D03*
X1495110Y1097166D03*
X1491409D03*
X1487709D03*
X1484008D03*
X1496960Y1100355D03*
X1493260D03*
X1489559D03*
X1485858D03*
X1495110Y1103544D03*
X1491409D03*
X1487709D03*
X1484008D03*
X1496960Y1106733D03*
X1493260D03*
X1489559D03*
X1485858D03*
X1495110Y1109922D03*
X1491409D03*
X1487709D03*
X1484008D03*
X1496960Y1113111D03*
X1493260D03*
X1489559D03*
X1485858D03*
X1495110Y1116300D03*
X1491409D03*
X1487709D03*
X1484008D03*
X1496960Y1119489D03*
X1493260D03*
X1489559D03*
X1485858D03*
X1495110Y1122678D03*
X1491409D03*
X1487709D03*
X1484008D03*
X1496960Y1125867D03*
X1493260D03*
X1489559D03*
X1485858D03*
X1495110Y1129056D03*
X1491409D03*
X1487709D03*
X1484008D03*
X1496960Y1132245D03*
X1493260D03*
X1489559D03*
X1485858D03*
X1495110Y1135433D03*
X1491409D03*
X1487709D03*
X1484008D03*
X1496960Y1138622D03*
X1493260D03*
X1489559D03*
X1485858D03*
X1495110Y1141811D03*
X1491409D03*
X1487709D03*
X1484008D03*
X1496960Y1145000D03*
X1493260D03*
X1489559D03*
X1485858D03*
X1495110Y1148189D03*
X1491409D03*
X1487709D03*
X1484008D03*
X1496960Y1151378D03*
X1493260D03*
X1489559D03*
X1485858D03*
X1495110Y1154567D03*
X1491409D03*
X1487709D03*
X1484008D03*
X1496960Y1157756D03*
X1493260D03*
X1489559D03*
X1485858D03*
X1495110Y1160945D03*
X1491409D03*
X1487709D03*
X1484008D03*
X1496960Y1164134D03*
X1493260D03*
X1485858D03*
X1506882Y874292D03*
X1503181D03*
X1499480D03*
X1512433Y877481D03*
X1508732D03*
X1505031D03*
X1501331D03*
X1510583Y880670D03*
X1506882D03*
X1503181D03*
X1499480D03*
X1512433Y883859D03*
X1508732D03*
X1505031D03*
X1501331D03*
X1510583Y887048D03*
X1506882D03*
X1503181D03*
X1499480D03*
X1512433Y890237D03*
X1508732D03*
X1505031D03*
X1501331D03*
X1510583Y893426D03*
X1506882D03*
X1503181D03*
X1499480D03*
X1512433Y896615D03*
X1508732D03*
X1505031D03*
X1501331D03*
X1510583Y899804D03*
X1506882D03*
X1503181D03*
X1499480D03*
X1512433Y902993D03*
X1508732D03*
X1505031D03*
X1501331D03*
X1510583Y906181D03*
X1506882D03*
X1503181D03*
X1499480D03*
X1512433Y909370D03*
X1508732D03*
X1505031D03*
X1501331D03*
X1510583Y912559D03*
X1506882D03*
X1503181D03*
X1499480D03*
X1512433Y915748D03*
X1508732D03*
X1505031D03*
X1501331D03*
X1510583Y918937D03*
X1506882D03*
X1503181D03*
X1499480D03*
X1512433Y922126D03*
X1508732D03*
X1505031D03*
X1501331D03*
X1510583Y925315D03*
X1506882D03*
X1503181D03*
X1499480D03*
X1512433Y928504D03*
X1508732D03*
X1505031D03*
X1501331D03*
X1510583Y931693D03*
X1506882D03*
X1503181D03*
X1499480D03*
X1512433Y934882D03*
X1508732D03*
X1505031D03*
X1501331D03*
X1510583Y938071D03*
X1506882D03*
X1503181D03*
X1499480D03*
X1512433Y941260D03*
X1508732D03*
X1505031D03*
X1501331D03*
X1510583Y944449D03*
X1506882D03*
X1503181D03*
X1499480D03*
X1512433Y947638D03*
X1508732D03*
X1505031D03*
X1501331D03*
X1510583Y950827D03*
X1506882D03*
X1503181D03*
X1499480D03*
X1512433Y954016D03*
X1508732D03*
X1505031D03*
X1501331D03*
X1510583Y957205D03*
X1506882D03*
X1503181D03*
X1499480D03*
X1512433Y960394D03*
X1508732D03*
X1505031D03*
X1501331D03*
X1510583Y963583D03*
X1506882D03*
X1503181D03*
X1499480D03*
X1512433Y966772D03*
X1508732D03*
X1505031D03*
X1501331D03*
X1510583Y969961D03*
X1506882D03*
X1503181D03*
X1499480D03*
X1512433Y973150D03*
X1508732D03*
X1505031D03*
X1501331D03*
X1510583Y976339D03*
X1506882D03*
X1503181D03*
X1499480D03*
X1512433Y979528D03*
X1508732D03*
X1505031D03*
X1501331D03*
X1510583Y982717D03*
X1506882D03*
X1503181D03*
X1499480D03*
X1512433Y985906D03*
X1508732D03*
X1505031D03*
X1501331D03*
X1510583Y989095D03*
X1506882D03*
X1503181D03*
X1499480D03*
X1512433Y992284D03*
X1508732D03*
X1505031D03*
X1501331D03*
X1510583Y995473D03*
X1506882D03*
X1503181D03*
X1499480D03*
X1512433Y998662D03*
X1508732D03*
X1505031D03*
X1501331D03*
X1510583Y1001851D03*
X1506882D03*
X1503181D03*
X1499480D03*
X1512433Y1005040D03*
X1508732D03*
X1505031D03*
X1501331D03*
X1510583Y1008229D03*
X1506882D03*
X1503181D03*
X1499480D03*
X1512433Y1011418D03*
X1508732D03*
X1505031D03*
X1501331D03*
X1513614Y1027008D03*
X1509913D03*
X1506212D03*
X1502512D03*
X1498811D03*
X1511764Y1030197D03*
X1508063D03*
X1504362D03*
X1500661D03*
X1513614Y1033386D03*
X1509913D03*
X1506212D03*
X1502512D03*
X1498811D03*
X1511764Y1036575D03*
X1508063D03*
X1504362D03*
X1500661D03*
X1513614Y1039764D03*
X1509913D03*
X1506212D03*
X1502512D03*
X1498811D03*
X1511764Y1042953D03*
X1508063D03*
X1504362D03*
X1500661D03*
X1513614Y1046142D03*
X1509913D03*
X1506212D03*
X1502512D03*
X1498811D03*
X1511764Y1049331D03*
X1508063D03*
X1504362D03*
X1500661D03*
X1513614Y1052520D03*
X1509913D03*
X1506212D03*
X1502512D03*
X1498811D03*
X1511764Y1055709D03*
X1508063D03*
X1504362D03*
X1500661D03*
X1513614Y1058898D03*
X1509913D03*
X1506212D03*
X1502512D03*
X1498811D03*
X1511764Y1062087D03*
X1508063D03*
X1504362D03*
X1500661D03*
X1513614Y1065276D03*
X1509913D03*
X1506212D03*
X1502512D03*
X1498811D03*
X1511764Y1068465D03*
X1508063D03*
X1504362D03*
X1500661D03*
X1513614Y1071654D03*
X1509913D03*
X1506212D03*
X1502512D03*
X1498811D03*
X1511764Y1074843D03*
X1508063D03*
X1504362D03*
X1500661D03*
X1513614Y1078032D03*
X1509913D03*
X1506212D03*
X1502512D03*
X1498811D03*
X1511764Y1081221D03*
X1508063D03*
X1504362D03*
X1500661D03*
X1513614Y1084410D03*
X1509913D03*
X1506212D03*
X1502512D03*
X1498811D03*
X1511764Y1087599D03*
X1508063D03*
X1504362D03*
X1500661D03*
X1513614Y1090788D03*
X1509913D03*
X1506212D03*
X1502512D03*
X1498811D03*
X1511764Y1093977D03*
X1508063D03*
X1504362D03*
X1500661D03*
X1513614Y1097166D03*
X1509913D03*
X1506212D03*
X1502512D03*
X1498811D03*
X1511764Y1100355D03*
X1508063D03*
X1504362D03*
X1500661D03*
X1513614Y1103544D03*
X1509913D03*
X1506212D03*
X1502512D03*
X1498811D03*
X1511764Y1106733D03*
X1508063D03*
X1504362D03*
X1500661D03*
X1513614Y1109922D03*
X1509913D03*
X1506212D03*
X1502512D03*
X1498811D03*
X1511764Y1113111D03*
X1508063D03*
X1504362D03*
X1500661D03*
X1513614Y1116300D03*
X1509913D03*
X1506212D03*
X1502512D03*
X1498811D03*
X1511764Y1119489D03*
X1508063D03*
X1504362D03*
X1500661D03*
X1513614Y1122678D03*
X1509913D03*
X1506212D03*
X1502512D03*
X1498811D03*
X1511764Y1125867D03*
X1508063D03*
X1504362D03*
X1500661D03*
X1513614Y1129056D03*
X1509913D03*
X1506212D03*
X1502512D03*
X1498811D03*
X1511764Y1132245D03*
X1508063D03*
X1504362D03*
X1500661D03*
X1513614Y1135433D03*
X1509913D03*
X1506212D03*
X1502512D03*
X1498811D03*
X1511764Y1138622D03*
X1508063D03*
X1504362D03*
X1500661D03*
X1513614Y1141811D03*
X1509913D03*
X1506212D03*
X1502512D03*
X1498811D03*
X1511764Y1145000D03*
X1508063D03*
X1504362D03*
X1500661D03*
X1513614Y1148189D03*
X1509913D03*
X1506212D03*
X1502512D03*
X1498811D03*
X1511764Y1151378D03*
X1508063D03*
X1504362D03*
X1500661D03*
X1513614Y1154567D03*
X1509913D03*
X1506212D03*
X1502512D03*
X1498811D03*
X1511764Y1157756D03*
X1508063D03*
X1504362D03*
X1500661D03*
X1513614Y1160945D03*
X1509913D03*
X1506212D03*
X1502512D03*
X1498811D03*
X1508063Y1164134D03*
X1504362D03*
X1500661D03*
X1525386Y874292D03*
X1521685D03*
X1517984D03*
X1514283D03*
X1527236Y877481D03*
X1523535D03*
X1519835D03*
X1516134D03*
X1525386Y880670D03*
X1521685D03*
X1517984D03*
X1514283D03*
X1527236Y883859D03*
X1523535D03*
X1519835D03*
X1516134D03*
X1525386Y887048D03*
X1521685D03*
X1517984D03*
X1514283D03*
X1527236Y890237D03*
X1523535D03*
X1519835D03*
X1516134D03*
X1525386Y893426D03*
X1521685D03*
X1517984D03*
X1514283D03*
X1527236Y896615D03*
X1523535D03*
X1519835D03*
X1516134D03*
X1525386Y899804D03*
X1521685D03*
X1517984D03*
X1514283D03*
X1527236Y902993D03*
X1523535D03*
X1519835D03*
X1516134D03*
X1525386Y906181D03*
X1521685D03*
X1517984D03*
X1514283D03*
X1527236Y909370D03*
X1523535D03*
X1519835D03*
X1516134D03*
X1525386Y912559D03*
X1521685D03*
X1517984D03*
X1514283D03*
X1527236Y915748D03*
X1523535D03*
X1519835D03*
X1516134D03*
X1525386Y918937D03*
X1521685D03*
X1517984D03*
X1514283D03*
X1527236Y922126D03*
X1523535D03*
X1519835D03*
X1516134D03*
X1525386Y925315D03*
X1521685D03*
X1517984D03*
X1514283D03*
X1527236Y928504D03*
X1523535D03*
X1519835D03*
X1516134D03*
X1525386Y931693D03*
X1521685D03*
X1517984D03*
X1514283D03*
X1527236Y934882D03*
X1523535D03*
X1519835D03*
X1516134D03*
X1525386Y938071D03*
X1521685D03*
X1517984D03*
X1514283D03*
X1527236Y941260D03*
X1523535D03*
X1519835D03*
X1516134D03*
X1525386Y944449D03*
X1521685D03*
X1517984D03*
X1514283D03*
X1527236Y947638D03*
X1523535D03*
X1519835D03*
X1516134D03*
X1525386Y950827D03*
X1521685D03*
X1517984D03*
X1514283D03*
X1527236Y954016D03*
X1523535D03*
X1519835D03*
X1516134D03*
X1525386Y957205D03*
X1521685D03*
X1517984D03*
X1514283D03*
X1527236Y960394D03*
X1523535D03*
X1519835D03*
X1516134D03*
X1525386Y963583D03*
X1521685D03*
X1517984D03*
X1514283D03*
X1527236Y966772D03*
X1523535D03*
X1519835D03*
X1516134D03*
X1525386Y969961D03*
X1521685D03*
X1517984D03*
X1514283D03*
X1527236Y973150D03*
X1523535D03*
X1519835D03*
X1516134D03*
X1525386Y976339D03*
X1521685D03*
X1517984D03*
X1514283D03*
X1527236Y979528D03*
X1523535D03*
X1519835D03*
X1516134D03*
X1525386Y982717D03*
X1521685D03*
X1517984D03*
X1514283D03*
X1527236Y985906D03*
X1523535D03*
X1519835D03*
X1516134D03*
X1525386Y989095D03*
X1521685D03*
X1517984D03*
X1514283D03*
X1527236Y992284D03*
X1523535D03*
X1519835D03*
X1516134D03*
X1525386Y995473D03*
X1521685D03*
X1517984D03*
X1514283D03*
X1527236Y998662D03*
X1523535D03*
X1519835D03*
X1516134D03*
X1525386Y1001851D03*
X1521685D03*
X1517984D03*
X1514283D03*
X1527236Y1005040D03*
X1523535D03*
X1519835D03*
X1516134D03*
X1525386Y1008229D03*
X1521685D03*
X1517984D03*
X1514283D03*
X1527236Y1011418D03*
X1523535D03*
X1519835D03*
X1516134D03*
X1528417Y1027008D03*
X1524716D03*
X1521016D03*
X1517315D03*
X1526567Y1030197D03*
X1522866D03*
X1519165D03*
X1515464D03*
X1528417Y1033386D03*
X1524716D03*
X1521016D03*
X1517315D03*
X1526567Y1036575D03*
X1522866D03*
X1519165D03*
X1515464D03*
X1528417Y1039764D03*
X1524716D03*
X1521016D03*
X1517315D03*
X1526567Y1042953D03*
X1522866D03*
X1519165D03*
X1515464D03*
X1528417Y1046142D03*
X1524716D03*
X1521016D03*
X1517315D03*
X1526567Y1049331D03*
X1522866D03*
X1519165D03*
X1515464D03*
X1528417Y1052520D03*
X1524716D03*
X1521016D03*
X1517315D03*
X1526567Y1055709D03*
X1522866D03*
X1519165D03*
X1515464D03*
X1528417Y1058898D03*
X1524716D03*
X1521016D03*
X1517315D03*
X1526567Y1062087D03*
X1522866D03*
X1519165D03*
X1515464D03*
X1528417Y1065276D03*
X1524716D03*
X1521016D03*
X1517315D03*
X1526567Y1068465D03*
X1522866D03*
X1519165D03*
X1515464D03*
X1528417Y1071654D03*
X1524716D03*
X1521016D03*
X1517315D03*
X1526567Y1074843D03*
X1522866D03*
X1519165D03*
X1515464D03*
X1528417Y1078032D03*
X1524716D03*
X1521016D03*
X1517315D03*
X1526567Y1081221D03*
X1522866D03*
X1519165D03*
X1515464D03*
X1528417Y1084410D03*
X1524716D03*
X1521016D03*
X1517315D03*
X1526567Y1087599D03*
X1522866D03*
X1519165D03*
X1515464D03*
X1528417Y1090788D03*
X1524716D03*
X1521016D03*
X1517315D03*
X1526567Y1093977D03*
X1522866D03*
X1519165D03*
X1515464D03*
X1528417Y1097166D03*
X1524716D03*
X1521016D03*
X1517315D03*
X1526567Y1100355D03*
X1522866D03*
X1519165D03*
X1515464D03*
X1528417Y1103544D03*
X1524716D03*
X1521016D03*
X1517315D03*
X1526567Y1106733D03*
X1522866D03*
X1519165D03*
X1515464D03*
X1528417Y1109922D03*
X1524716D03*
X1521016D03*
X1517315D03*
X1526567Y1113111D03*
X1522866D03*
X1519165D03*
X1515464D03*
X1528417Y1116300D03*
X1524716D03*
X1521016D03*
X1517315D03*
X1526567Y1119489D03*
X1522866D03*
X1519165D03*
X1515464D03*
X1528417Y1122678D03*
X1524716D03*
X1521016D03*
X1517315D03*
X1526567Y1125867D03*
X1522866D03*
X1519165D03*
X1515464D03*
X1528417Y1129056D03*
X1524716D03*
X1521016D03*
X1517315D03*
X1526567Y1132245D03*
X1522866D03*
X1519165D03*
X1515464D03*
X1528417Y1135433D03*
X1524716D03*
X1521016D03*
X1517315D03*
X1526567Y1138622D03*
X1522866D03*
X1519165D03*
X1515464D03*
X1528417Y1141811D03*
X1524716D03*
X1521016D03*
X1517315D03*
X1526567Y1145000D03*
X1522866D03*
X1519165D03*
X1515464D03*
X1528417Y1148189D03*
X1524716D03*
X1521016D03*
X1517315D03*
X1526567Y1151378D03*
X1522866D03*
X1519165D03*
X1515464D03*
X1528417Y1154567D03*
X1524716D03*
X1521016D03*
X1517315D03*
X1526567Y1157756D03*
X1522866D03*
X1519165D03*
X1515464D03*
X1528417Y1160945D03*
X1524716D03*
X1521016D03*
X1517315D03*
X1526567Y1164134D03*
X1522866D03*
X1519165D03*
X1515464D03*
X1540189Y874292D03*
X1536488D03*
X1529086D03*
X1542039Y877481D03*
X1538338D03*
X1534638D03*
X1530937D03*
X1540189Y880670D03*
X1536488D03*
X1532787D03*
X1529086D03*
X1542039Y883859D03*
X1538338D03*
X1534638D03*
X1530937D03*
X1540189Y887048D03*
X1536488D03*
X1532787D03*
X1529086D03*
X1542039Y890237D03*
X1538338D03*
X1534638D03*
X1530937D03*
X1540189Y893426D03*
X1536488D03*
X1532787D03*
X1529086D03*
X1542039Y896615D03*
X1538338D03*
X1534638D03*
X1530937D03*
X1540189Y899804D03*
X1536488D03*
X1532787D03*
X1529086D03*
X1542039Y902993D03*
X1538338D03*
X1534638D03*
X1530937D03*
X1540189Y906181D03*
X1536488D03*
X1532787D03*
X1529086D03*
X1542039Y909370D03*
X1538338D03*
X1534638D03*
X1530937D03*
X1540189Y912559D03*
X1536488D03*
X1532787D03*
X1529086D03*
X1542039Y915748D03*
X1538338D03*
X1534638D03*
X1530937D03*
X1540189Y918937D03*
X1536488D03*
X1532787D03*
X1529086D03*
X1542039Y922126D03*
X1538338D03*
X1534638D03*
X1530937D03*
X1540189Y925315D03*
X1536488D03*
X1532787D03*
X1529086D03*
X1542039Y928504D03*
X1538338D03*
X1534638D03*
X1530937D03*
X1540189Y931693D03*
X1536488D03*
X1532787D03*
X1529086D03*
X1542039Y934882D03*
X1538338D03*
X1534638D03*
X1530937D03*
X1540189Y938071D03*
X1536488D03*
X1532787D03*
X1529086D03*
X1542039Y941260D03*
X1538338D03*
X1534638D03*
X1530937D03*
X1540189Y944449D03*
X1536488D03*
X1532787D03*
X1529086D03*
X1542039Y947638D03*
X1538338D03*
X1534638D03*
X1530937D03*
X1540189Y950827D03*
X1536488D03*
X1532787D03*
X1529086D03*
X1542039Y954016D03*
X1538338D03*
X1534638D03*
X1530937D03*
X1540189Y957205D03*
X1536488D03*
X1532787D03*
X1529086D03*
X1542039Y960394D03*
X1538338D03*
X1534638D03*
X1530937D03*
X1540189Y963583D03*
X1536488D03*
X1532787D03*
X1529086D03*
X1542039Y966772D03*
X1538338D03*
X1534638D03*
X1530937D03*
X1540189Y969961D03*
X1536488D03*
X1532787D03*
X1529086D03*
X1542039Y973150D03*
X1538338D03*
X1534638D03*
X1530937D03*
X1540189Y976339D03*
X1536488D03*
X1532787D03*
X1529086D03*
X1542039Y979528D03*
X1538338D03*
X1534638D03*
X1530937D03*
X1540189Y982717D03*
X1536488D03*
X1532787D03*
X1529086D03*
X1542039Y985906D03*
X1538338D03*
X1534638D03*
X1530937D03*
X1540189Y989095D03*
X1536488D03*
X1532787D03*
X1529086D03*
X1542039Y992284D03*
X1538338D03*
X1534638D03*
X1530937D03*
X1540189Y995473D03*
X1536488D03*
X1532787D03*
X1529086D03*
X1542039Y998662D03*
X1538338D03*
X1534638D03*
X1530937D03*
X1540189Y1001851D03*
X1536488D03*
X1532787D03*
X1529086D03*
X1542039Y1005040D03*
X1538338D03*
X1534638D03*
X1530937D03*
X1540189Y1008229D03*
X1536488D03*
X1532787D03*
X1529086D03*
X1542039Y1011418D03*
X1538338D03*
X1534638D03*
X1530937D03*
X1543220Y1027008D03*
X1539520D03*
X1535819D03*
X1532118D03*
X1541370Y1030197D03*
X1537669D03*
X1533968D03*
X1530268D03*
X1543220Y1033386D03*
X1539520D03*
X1535819D03*
X1532118D03*
X1541370Y1036575D03*
X1537669D03*
X1533968D03*
X1530268D03*
X1543220Y1039764D03*
X1539520D03*
X1535819D03*
X1532118D03*
X1541370Y1042953D03*
X1537669D03*
X1533968D03*
X1530268D03*
X1543220Y1046142D03*
X1539520D03*
X1535819D03*
X1532118D03*
X1541370Y1049331D03*
X1537669D03*
X1533968D03*
X1530268D03*
X1543220Y1052520D03*
X1539520D03*
X1535819D03*
X1532118D03*
X1541370Y1055709D03*
X1537669D03*
X1533968D03*
X1530268D03*
X1543220Y1058898D03*
X1539520D03*
X1535819D03*
X1532118D03*
X1541370Y1062087D03*
X1537669D03*
X1533968D03*
X1530268D03*
X1543220Y1065276D03*
X1539520D03*
X1535819D03*
X1532118D03*
X1541370Y1068465D03*
X1537669D03*
X1533968D03*
X1530268D03*
X1543220Y1071654D03*
X1539520D03*
X1535819D03*
X1532118D03*
X1541370Y1074843D03*
X1537669D03*
X1533968D03*
X1530268D03*
X1543220Y1078032D03*
X1539520D03*
X1535819D03*
X1532118D03*
X1541370Y1081221D03*
X1537669D03*
X1533968D03*
X1530268D03*
X1543220Y1084410D03*
X1539520D03*
X1535819D03*
X1532118D03*
X1541370Y1087599D03*
X1537669D03*
X1533968D03*
X1530268D03*
X1543220Y1090788D03*
X1539520D03*
X1535819D03*
X1532118D03*
X1541370Y1093977D03*
X1537669D03*
X1533968D03*
X1530268D03*
X1543220Y1097166D03*
X1539520D03*
X1535819D03*
X1532118D03*
X1541370Y1100355D03*
X1537669D03*
X1533968D03*
X1530268D03*
X1543220Y1103544D03*
X1539520D03*
X1535819D03*
X1532118D03*
X1541370Y1106733D03*
X1537669D03*
X1533968D03*
X1530268D03*
X1543220Y1109922D03*
X1539520D03*
X1535819D03*
X1532118D03*
X1541370Y1113111D03*
X1537669D03*
X1533968D03*
X1530268D03*
X1543220Y1116300D03*
X1539520D03*
X1535819D03*
X1532118D03*
X1541370Y1119489D03*
X1537669D03*
X1533968D03*
X1530268D03*
X1543220Y1122678D03*
X1539520D03*
X1535819D03*
X1532118D03*
X1541370Y1125867D03*
X1537669D03*
X1533968D03*
X1530268D03*
X1543220Y1129056D03*
X1539520D03*
X1535819D03*
X1532118D03*
X1541370Y1132245D03*
X1537669D03*
X1533968D03*
X1530268D03*
X1543220Y1135433D03*
X1539520D03*
X1535819D03*
X1532118D03*
X1541370Y1138622D03*
X1537669D03*
X1533968D03*
X1530268D03*
X1543220Y1141811D03*
X1539520D03*
X1535819D03*
X1532118D03*
X1541370Y1145000D03*
X1537669D03*
X1533968D03*
X1530268D03*
X1543220Y1148189D03*
X1539520D03*
X1535819D03*
X1532118D03*
X1541370Y1151378D03*
X1537669D03*
X1533968D03*
X1530268D03*
X1543220Y1154567D03*
X1539520D03*
X1535819D03*
X1532118D03*
X1541370Y1157756D03*
X1537669D03*
X1533968D03*
X1530268D03*
X1543220Y1160945D03*
X1539520D03*
X1535819D03*
X1532118D03*
X1541370Y1164134D03*
X1537669D03*
X1530268D03*
X1543890Y874292D03*
X1545740Y877481D03*
X1551291Y880670D03*
X1547590D03*
X1543890D03*
X1549441Y883859D03*
X1545740D03*
X1551291Y887048D03*
X1547590D03*
X1543890D03*
X1549441Y890237D03*
X1545740D03*
X1551291Y893426D03*
X1547590D03*
X1543890D03*
X1549441Y896615D03*
X1545740D03*
X1551291Y899804D03*
X1547590D03*
X1543890D03*
X1549441Y902993D03*
X1545740D03*
X1551291Y906181D03*
X1547590D03*
X1543890D03*
X1549441Y909370D03*
X1545740D03*
X1551291Y912559D03*
X1547590D03*
X1543890D03*
X1549441Y915748D03*
X1545740D03*
X1551291Y918937D03*
X1547590D03*
X1543890D03*
X1549441Y922126D03*
X1545740D03*
X1551291Y925315D03*
X1547590D03*
X1543890D03*
X1549441Y928504D03*
X1545740D03*
X1551291Y931693D03*
X1547590D03*
X1543890D03*
X1549441Y934882D03*
X1545740D03*
X1551291Y938071D03*
X1547590D03*
X1543890D03*
X1549441Y941260D03*
X1545740D03*
X1551291Y944449D03*
X1547590D03*
X1543890D03*
X1549441Y947638D03*
X1545740D03*
X1551291Y950827D03*
X1547590D03*
X1543890D03*
X1549441Y954016D03*
X1545740D03*
X1551291Y957205D03*
X1547590D03*
X1543890D03*
X1549441Y960394D03*
X1545740D03*
X1551291Y963583D03*
X1547590D03*
X1543890D03*
X1549441Y966772D03*
X1545740D03*
X1551291Y969961D03*
X1547590D03*
X1543890D03*
X1549441Y973150D03*
X1545740D03*
X1551291Y976339D03*
X1547590D03*
X1543890D03*
X1549441Y979528D03*
X1545740D03*
X1551291Y982717D03*
X1547590D03*
X1543890D03*
X1549441Y985906D03*
X1545740D03*
X1551291Y989095D03*
X1547590D03*
X1543890D03*
X1549441Y992284D03*
X1545740D03*
X1551291Y995473D03*
X1547590D03*
X1543890D03*
X1549441Y998662D03*
X1545740D03*
X1551291Y1001851D03*
X1547590D03*
X1543890D03*
X1549441Y1005040D03*
X1545740D03*
X1551291Y1008229D03*
X1547590D03*
X1543890D03*
X1549441Y1011418D03*
X1545740D03*
X1550622Y1027008D03*
X1546921D03*
X1552472Y1030197D03*
X1548771D03*
X1545071D03*
X1550622Y1033386D03*
X1546921D03*
X1552472Y1036575D03*
X1548771D03*
X1545071D03*
X1550622Y1039764D03*
X1546921D03*
X1552472Y1042953D03*
X1548771D03*
X1545071D03*
X1550622Y1046142D03*
X1546921D03*
X1552472Y1049331D03*
X1548771D03*
X1545071D03*
X1550622Y1052520D03*
X1546921D03*
X1552472Y1055709D03*
X1548771D03*
X1545071D03*
X1550622Y1058898D03*
X1546921D03*
X1552472Y1062087D03*
X1548771D03*
X1545071D03*
X1550622Y1065276D03*
X1546921D03*
X1552472Y1068465D03*
X1548771D03*
X1545071D03*
X1550622Y1071654D03*
X1546921D03*
X1552472Y1074843D03*
X1548771D03*
X1545071D03*
X1550622Y1078032D03*
X1546921D03*
X1552472Y1081221D03*
X1548771D03*
X1545071D03*
X1550622Y1084410D03*
X1546921D03*
X1552472Y1087599D03*
X1548771D03*
X1545071D03*
X1550622Y1090788D03*
X1546921D03*
X1552472Y1093977D03*
X1548771D03*
X1545071D03*
X1550622Y1097166D03*
X1546921D03*
X1552472Y1100355D03*
X1548771D03*
X1545071D03*
X1550622Y1103544D03*
X1546921D03*
X1552472Y1106733D03*
X1548771D03*
X1545071D03*
X1550622Y1109922D03*
X1546921D03*
X1552472Y1113111D03*
X1548771D03*
X1545071D03*
X1550622Y1116300D03*
X1546921D03*
X1552472Y1119489D03*
X1548771D03*
X1545071D03*
X1550622Y1122678D03*
X1546921D03*
X1552472Y1125867D03*
X1548771D03*
X1545071D03*
X1550622Y1129056D03*
X1546921D03*
X1552472Y1132245D03*
X1548771D03*
X1545071D03*
X1550622Y1135433D03*
X1546921D03*
X1552472Y1138622D03*
X1548771D03*
X1545071D03*
X1550622Y1141811D03*
X1546921D03*
X1552472Y1145000D03*
X1548771D03*
X1545071D03*
X1550622Y1148189D03*
X1546921D03*
X1552472Y1151378D03*
X1548771D03*
X1545071D03*
X1550622Y1154567D03*
X1546921D03*
X1552472Y1157756D03*
X1548771D03*
X1545071D03*
X1546921Y1160945D03*
X1545071Y1164134D03*
G54D115*
X215312Y1577778D03*
X240508D03*
X252717Y1577830D03*
X277913D03*
X516830D03*
X542026D03*
X1222952Y1610648D03*
X1248148D03*
X1260530Y1610830D03*
X1285726D03*
X1524704D03*
X1549900D03*
G54D322*
X1787234Y709079D03*
G54D50*
X65205Y1526394D03*
X100948D03*
X112601Y1360516D03*
X145201D03*
X177901D03*
X210801D03*
X243601D03*
X277201Y1314370D03*
X310097Y1314342D03*
X343001Y1314285D03*
X375801Y1314485D03*
X408383Y1333816D03*
X720157Y1378525D03*
X752939Y1378625D03*
X1084339Y1360497D03*
X1116939D03*
X1149639D03*
X1182539D03*
X1215339D03*
X1253330Y1314351D03*
X1286226Y1314323D03*
X1319130Y1314266D03*
X1351930Y1314466D03*
X1384512Y1333797D03*
X1667890Y1377814D03*
X1700672Y1377914D03*
X1752488Y1559430D03*
X1788231D03*
G54D23*
X27048Y1533228D03*
X79590Y1369350D03*
X137284Y1533228D03*
X215418Y658055D03*
X276440Y1357539D03*
X420125Y656008D03*
X443764Y1339823D03*
X523173Y578174D03*
X681440Y1385138D03*
X791678D03*
X873622Y1145275D03*
X983858D03*
X1052960Y1369350D03*
X1249812Y1357539D03*
X1370284Y582303D03*
X1417134Y1339823D03*
X1533552Y682342D03*
X1629732Y1383523D03*
X1664890Y642972D03*
X1714330Y1570984D03*
X1739968Y1383527D03*
X1761575Y159134D03*
X1824566Y1570988D03*
X1838150Y201929D03*
G54D170*
X428899Y222253D03*
Y240953D03*
X451931Y222253D03*
Y240953D03*
X506945Y224930D03*
Y243630D03*
X529977Y224930D03*
Y243630D03*
G54D161*
X394824Y1634154D03*
X389824D03*
X384824D03*
Y1655020D03*
X389824D03*
X394824D03*
X399824Y1634154D03*
Y1655020D03*
X1440579Y1640337D03*
X1445579D03*
X1450579D03*
X1440579Y1661203D03*
X1450579D03*
X1445579D03*
X1455579Y1640337D03*
Y1661203D03*
G54D215*
X662740Y370677D03*
X659000D03*
X655260D03*
Y380323D03*
X662740D03*
X1360629Y106559D03*
Y116205D03*
X1364369D03*
X1368109Y106559D03*
Y116205D03*
G54D224*
X723436Y648667D03*
X716822D03*
X1148544Y1556029D03*
X1141930D03*
X1469652Y1679401D03*
X1476266D03*
G54D233*
X731743Y-23871D03*
X1183222Y-20011D03*
Y-11D03*
Y19989D03*
X1442081Y-20011D03*
Y-11D03*
Y19989D03*
X1735375Y-24212D03*
G54D260*
X849385Y1541015D03*
X949271Y1479729D03*
G54D134*
X268312Y605247D03*
X281698Y594223D03*
G54D242*
X778687Y1573504D03*
Y1591222D03*
X792467Y1573504D03*
Y1591222D03*
X820687Y1573504D03*
Y1591222D03*
X834467Y1573504D03*
Y1591222D03*
X862687Y1573504D03*
Y1591222D03*
X876467Y1573504D03*
Y1591222D03*
X904687Y1573504D03*
Y1591222D03*
X918467Y1573504D03*
Y1591222D03*
G54D125*
X270414Y64236D03*
X288918D03*
X953693Y187871D03*
X972197D03*
X1686919Y386516D03*
X1705423D03*
X1730367Y75039D03*
X1748871D03*
G54D32*
X45876Y384395D03*
Y386364D03*
Y388333D03*
Y390301D03*
Y392269D03*
Y394238D03*
Y396207D03*
X64872Y388333D03*
Y386364D03*
Y384395D03*
Y396207D03*
Y394238D03*
Y392269D03*
Y390301D03*
G54D305*
X1627179Y576851D03*
Y611015D03*
G54D152*
X362651Y283902D03*
Y285870D03*
Y287838D03*
X370525Y283902D03*
Y287838D03*
Y285870D03*
X777703Y275290D03*
Y273322D03*
Y271354D03*
X769829D03*
Y273322D03*
Y275290D03*
G54D206*
X576672Y228055D03*
G54D116*
X230905Y1644448D03*
Y1658621D03*
Y1672795D03*
Y1686968D03*
Y1701141D03*
Y1715314D03*
Y1729488D03*
X246653Y1644448D03*
X238779Y1648385D03*
X246653Y1658621D03*
X238779Y1662558D03*
X246653Y1672795D03*
X238779Y1676732D03*
X246653Y1686968D03*
X238779Y1690905D03*
X246653Y1701141D03*
X238779Y1705078D03*
X246653Y1715314D03*
X238779Y1719251D03*
X246653Y1729488D03*
X238779Y1733425D03*
X254527Y1648385D03*
Y1662558D03*
Y1676732D03*
Y1690905D03*
Y1705078D03*
Y1719251D03*
Y1733425D03*
X262401Y1644448D03*
X270275Y1648385D03*
X262401Y1658621D03*
X270275Y1662558D03*
X262401Y1672795D03*
X270275Y1676732D03*
X262401Y1686968D03*
X270275Y1690905D03*
X262401Y1701141D03*
X270275Y1705078D03*
X262401Y1715314D03*
X270275Y1719251D03*
X262401Y1729488D03*
X270275Y1733425D03*
X278149Y1644448D03*
X286023Y1648385D03*
X278149Y1658621D03*
X286023Y1662558D03*
X278149Y1672795D03*
X286023Y1676732D03*
X278149Y1686968D03*
X286023Y1690905D03*
X278149Y1701141D03*
X286023Y1705078D03*
X278149Y1715314D03*
X286023Y1719251D03*
X278149Y1729488D03*
X286023Y1733425D03*
X297835Y1672795D03*
X305709Y1676732D03*
X297835Y1686968D03*
X305709Y1690905D03*
X297835Y1701141D03*
X305709Y1705078D03*
X297835Y1715314D03*
X305709Y1719251D03*
X297835Y1729488D03*
X305709Y1733425D03*
X313583Y1672795D03*
X321457Y1676732D03*
X313583Y1686968D03*
X321457Y1690905D03*
X313583Y1701141D03*
X321457Y1705078D03*
X313583Y1715314D03*
X321457Y1719251D03*
X313583Y1729488D03*
X321457Y1733425D03*
X329331Y1672795D03*
Y1686968D03*
Y1701141D03*
Y1715314D03*
Y1729488D03*
X345079Y1672795D03*
X337205Y1676732D03*
X345079Y1686968D03*
X337205Y1690905D03*
X345079Y1701141D03*
X337205Y1705078D03*
X345079Y1715314D03*
X337205Y1719251D03*
X345079Y1729488D03*
X337205Y1733425D03*
X352953Y1676732D03*
Y1690905D03*
Y1705078D03*
Y1719251D03*
Y1733425D03*
X495078Y1672795D03*
Y1686968D03*
Y1701141D03*
Y1715314D03*
Y1729488D03*
X510826Y1672795D03*
X502952Y1676732D03*
X510826Y1686968D03*
X502952Y1690905D03*
X510826Y1701141D03*
X502952Y1705078D03*
X510826Y1715314D03*
X502952Y1719251D03*
X510826Y1729488D03*
X502952Y1733425D03*
X526574Y1672795D03*
X518700Y1676732D03*
X526574Y1686968D03*
X518700Y1690905D03*
X526574Y1701141D03*
X518700Y1705078D03*
X526574Y1715314D03*
X518700Y1719251D03*
X526574Y1729488D03*
X518700Y1733425D03*
X542322Y1672795D03*
X534448Y1676732D03*
X542322Y1686968D03*
X534448Y1690905D03*
X542322Y1701141D03*
X534448Y1705078D03*
X542322Y1715314D03*
X534448Y1719251D03*
X542322Y1729488D03*
X534448Y1733425D03*
X550196Y1676732D03*
Y1690905D03*
Y1705078D03*
Y1719251D03*
Y1733425D03*
X562008Y1672795D03*
X569882Y1676732D03*
X562008Y1686968D03*
X569882Y1690905D03*
X562008Y1701141D03*
X569882Y1705078D03*
X562008Y1715314D03*
X569882Y1719251D03*
X562008Y1729488D03*
X569882Y1733425D03*
X577756Y1672795D03*
X585630Y1676732D03*
X577756Y1686968D03*
X585630Y1690905D03*
X577756Y1701141D03*
X585630Y1705078D03*
X577756Y1715314D03*
X585630Y1719251D03*
X577756Y1729488D03*
X585630Y1733425D03*
X593504Y1672795D03*
X601378Y1676732D03*
X593504Y1686968D03*
X601378Y1690905D03*
X593504Y1701141D03*
X601378Y1705078D03*
X593504Y1715314D03*
X601378Y1719251D03*
X593504Y1729488D03*
X601378Y1733425D03*
X609252Y1672795D03*
X617126Y1676732D03*
X609252Y1686968D03*
X617126Y1690905D03*
X609252Y1701141D03*
X617126Y1705078D03*
X609252Y1715314D03*
X617126Y1719251D03*
X609252Y1729488D03*
X617126Y1733425D03*
X1238778Y1672795D03*
Y1686968D03*
Y1701141D03*
Y1715314D03*
Y1729488D03*
X1254526Y1672795D03*
X1246652Y1676732D03*
X1254526Y1686968D03*
X1246652Y1690905D03*
X1254526Y1701141D03*
X1246652Y1705078D03*
X1254526Y1715314D03*
X1246652Y1719251D03*
X1254526Y1729488D03*
X1246652Y1733425D03*
X1270274Y1672795D03*
X1262400Y1676732D03*
X1270274Y1686968D03*
X1262400Y1690905D03*
X1270274Y1701141D03*
X1262400Y1705078D03*
X1270274Y1715314D03*
X1262400Y1719251D03*
X1270274Y1729488D03*
X1262400Y1733425D03*
X1286022Y1672795D03*
X1278148Y1676732D03*
X1286022Y1686968D03*
X1278148Y1690905D03*
X1286022Y1701141D03*
X1278148Y1705078D03*
X1286022Y1715314D03*
X1278148Y1719251D03*
X1286022Y1729488D03*
X1278148Y1733425D03*
X1305708Y1672795D03*
Y1686968D03*
X1293896Y1676732D03*
X1305708Y1701141D03*
X1293896Y1690905D03*
X1305708Y1715314D03*
X1293896Y1705078D03*
X1305708Y1729488D03*
X1293896Y1719251D03*
Y1733425D03*
X1313582Y1676732D03*
Y1690905D03*
Y1705078D03*
Y1719251D03*
Y1733425D03*
X1321456Y1672795D03*
X1329330Y1676732D03*
X1321456Y1686968D03*
X1329330Y1690905D03*
X1321456Y1701141D03*
X1329330Y1705078D03*
X1321456Y1715314D03*
X1329330Y1719251D03*
X1321456Y1729488D03*
X1329330Y1733425D03*
X1337204Y1672795D03*
X1345078Y1676732D03*
X1337204Y1686968D03*
X1345078Y1690905D03*
X1337204Y1701141D03*
X1345078Y1705078D03*
X1337204Y1715314D03*
X1345078Y1719251D03*
X1337204Y1729488D03*
X1345078Y1733425D03*
X1352952Y1672795D03*
X1360826Y1676732D03*
X1352952Y1686968D03*
X1360826Y1690905D03*
X1352952Y1701141D03*
X1360826Y1705078D03*
X1352952Y1715314D03*
X1360826Y1719251D03*
X1352952Y1729488D03*
X1360826Y1733425D03*
X1502952Y1672795D03*
X1510826Y1676732D03*
X1502952Y1686968D03*
X1510826Y1690905D03*
X1502952Y1701141D03*
X1510826Y1705078D03*
X1502952Y1715314D03*
X1510826Y1719251D03*
X1502952Y1729488D03*
X1510826Y1733425D03*
X1518700Y1672795D03*
X1526574Y1676732D03*
X1518700Y1686968D03*
X1526574Y1690905D03*
X1518700Y1701141D03*
X1526574Y1705078D03*
X1518700Y1715314D03*
X1526574Y1719251D03*
X1518700Y1729488D03*
X1526574Y1733425D03*
X1534448Y1672795D03*
X1542322Y1676732D03*
X1534448Y1686968D03*
X1542322Y1690905D03*
X1534448Y1701141D03*
X1542322Y1705078D03*
X1534448Y1715314D03*
X1542322Y1719251D03*
X1534448Y1729488D03*
X1542322Y1733425D03*
X1550196Y1672795D03*
X1558070Y1676732D03*
X1550196Y1686968D03*
X1558070Y1690905D03*
X1550196Y1701141D03*
X1558070Y1705078D03*
X1550196Y1715314D03*
X1558070Y1719251D03*
X1550196Y1729488D03*
X1558070Y1733425D03*
X1569882Y1672795D03*
Y1686968D03*
Y1701141D03*
Y1715314D03*
Y1729488D03*
X1585630Y1672795D03*
X1577756Y1676732D03*
X1585630Y1686968D03*
X1577756Y1690905D03*
X1585630Y1701141D03*
X1577756Y1705078D03*
X1585630Y1715314D03*
X1577756Y1719251D03*
X1585630Y1729488D03*
X1577756Y1733425D03*
X1601378Y1672795D03*
X1593504Y1676732D03*
X1601378Y1686968D03*
X1593504Y1690905D03*
X1601378Y1701141D03*
X1593504Y1705078D03*
X1601378Y1715314D03*
X1593504Y1719251D03*
X1601378Y1729488D03*
X1593504Y1733425D03*
X1617126Y1672795D03*
X1609252Y1676732D03*
X1617126Y1686968D03*
X1609252Y1690905D03*
X1617126Y1701141D03*
X1609252Y1705078D03*
X1617126Y1715314D03*
X1609252Y1719251D03*
X1617126Y1729488D03*
X1609252Y1733425D03*
X1625000Y1676732D03*
Y1690905D03*
Y1705078D03*
Y1719251D03*
Y1733425D03*
G54D14*
X11782Y171993D03*
X18691Y172165D03*
X33180Y298299D03*
X36524Y392288D03*
X32847Y534557D03*
X36372Y531312D03*
X50304Y58837D03*
X39008Y363429D03*
X51114D03*
X42809D03*
X48502Y504789D03*
X48626Y546777D03*
X52040Y1499314D03*
X50631Y1537188D03*
X48662Y1523352D03*
X51996Y1551459D03*
X50696Y1544386D03*
X46133Y1633413D03*
X51133D03*
X54616Y58837D03*
X63780Y298299D03*
X67681Y363429D03*
X59322D03*
X63429D03*
X56163Y414020D03*
X52902Y504602D03*
X58402D03*
X58633Y1590413D03*
X63633D03*
X56133Y1636513D03*
X61133D03*
X64427Y1646904D03*
X55427D03*
X69523Y414020D03*
X80378Y1409172D03*
X68768Y1547313D03*
X81006Y1596424D03*
X68133Y1590413D03*
X72660D03*
X77427Y1646904D03*
X78127Y1681904D03*
X70127D03*
X74127D03*
X94158Y1308118D03*
X90601Y1382806D03*
X94713Y1382854D03*
X86374Y1537688D03*
X84405Y1523352D03*
X82606Y1604724D03*
X86127Y1681904D03*
X92500Y1698967D03*
X98124Y1356733D03*
X98101Y1374054D03*
X101995Y1382685D03*
X107000Y1407517D03*
X104511Y1547013D03*
X112353Y1649104D03*
X120016Y294714D03*
Y315148D03*
X115590Y1381875D03*
X115353Y1690483D03*
X119353D03*
X130724Y1356733D03*
X130701Y1374054D03*
X134595Y1382685D03*
X141028Y1449129D03*
X137120Y1449175D03*
X133120D03*
X132353Y1649104D03*
X136353D03*
X132420Y1701528D03*
X139353Y1690604D03*
X131353D03*
X135353D03*
X144610Y424097D03*
X148190Y1381875D03*
X148000Y1414517D03*
X151000Y1442517D03*
X145028Y1449129D03*
X149028D03*
X152353Y1649104D03*
X151353Y1690604D03*
X143353D03*
X155353D03*
X163424Y1356733D03*
X163401Y1374054D03*
X167295Y1382685D03*
X158740Y1707517D03*
X183890Y390677D03*
X180890Y1381875D03*
X185760Y1707405D03*
X181760Y1725893D03*
X195979Y98159D03*
X190861Y125594D03*
X197645Y130704D03*
X196324Y1356733D03*
X196301Y1374054D03*
X200195Y1382685D03*
X189760Y1725893D03*
X208179Y98159D03*
X203061Y125594D03*
X213790Y1381875D03*
X229516Y152076D03*
X225090Y153487D03*
X229124Y1356733D03*
X229101Y1374054D03*
X243487Y104777D03*
X246297Y124060D03*
X242297D03*
X233595Y152088D03*
X244125Y663255D03*
X232995Y1382685D03*
X247487Y104777D03*
X261297Y124060D03*
X254297D03*
X250297D03*
X260100Y153979D03*
X254756Y156819D03*
X251424Y645276D03*
X246590Y1381875D03*
X271797Y124060D03*
X268297Y127560D03*
X275500Y231017D03*
X273069Y582087D03*
X272955Y663597D03*
X262724Y1310587D03*
X262701Y1327908D03*
X266595Y1336539D03*
X273597Y1519937D03*
X289357Y116020D03*
X284154Y679517D03*
X276855Y697496D03*
X280190Y1335729D03*
X279499Y1519937D03*
X302500Y250517D03*
X297815Y582971D03*
X305685Y697838D03*
X295620Y1310559D03*
X295597Y1327880D03*
X299491Y1336511D03*
X314602Y271108D03*
X316924Y699667D03*
X309655Y717356D03*
X313086Y1335701D03*
X325617Y81260D03*
X328524Y1310502D03*
X328501Y1327823D03*
X332395Y1336454D03*
X339811Y123194D03*
X346153Y270403D03*
X349984Y699399D03*
X342710Y717329D03*
X338455Y717988D03*
X345990Y1335644D03*
X352628Y283807D03*
X357582Y555307D03*
X353582D03*
X361324Y1310702D03*
X361301Y1328023D03*
X365195Y1336654D03*
X370064Y239653D03*
X371412Y272094D03*
X371962Y534184D03*
X375704Y717480D03*
X371515Y717720D03*
X378790Y1335844D03*
X395048Y123695D03*
X382184Y468868D03*
X393376Y469214D03*
X383024Y699467D03*
X393906Y1330033D03*
X393883Y1347354D03*
X384824Y1624230D03*
X394824D03*
X389824D03*
X384824Y1661637D03*
X394824D03*
X389824D03*
X406243Y102593D03*
X399264Y123661D03*
X400632Y141242D03*
X399299Y214588D03*
X402184Y468986D03*
Y501618D03*
X408739Y699611D03*
X404771Y693155D03*
X404555Y717788D03*
X397777Y1355985D03*
X401659Y1519937D03*
X407561D03*
X402969Y1622841D03*
X399824Y1661637D03*
X405000Y1677517D03*
X411299Y206637D03*
Y214588D03*
X415984Y468909D03*
Y501541D03*
X412771Y531155D03*
X416024Y681667D03*
X423921Y1006440D03*
X411372Y1355175D03*
X417000Y1665017D03*
Y1677517D03*
X433673Y77217D03*
X429997Y160642D03*
X433997Y153642D03*
X437997D03*
X439299Y214588D03*
X429784Y468832D03*
X439500Y493517D03*
X437309Y674944D03*
X437555Y699988D03*
X435141Y1006440D03*
X438882D03*
X427661D03*
X431401D03*
X427251Y1286211D03*
X441997Y160642D03*
X451299Y214588D03*
X443500Y486517D03*
X448424Y657067D03*
X441137Y674930D03*
X450102Y1006440D03*
X442622D03*
X446362D03*
X453842D03*
X453085Y1643950D03*
X466600Y142892D03*
X457997Y160642D03*
X465997D03*
X461931Y215195D03*
X458115Y241045D03*
X469038Y300655D03*
X469881Y648554D03*
X469955Y675388D03*
X457582Y1006440D03*
X461000Y1644017D03*
X475435Y206652D03*
X484754Y223469D03*
X481024Y630567D03*
X473732Y648556D03*
X483500Y1264879D03*
X478500Y1265017D03*
X474500D03*
X498314Y115435D03*
X485997Y160642D03*
X489997D03*
X494144Y215744D03*
X487107Y285246D03*
X488538Y298720D03*
X488544Y292041D03*
X487500Y1264879D03*
X492500D03*
X496500D03*
X501500Y419517D03*
Y426517D03*
X512000Y429517D03*
X514324Y596467D03*
X502998Y614430D03*
X506964Y614438D03*
X502555Y648888D03*
X515539Y82659D03*
X522088Y204377D03*
X543131Y123347D03*
X536177Y243722D03*
X535855Y614788D03*
X537770Y1519937D03*
X543672D03*
X554196Y184773D03*
X556038Y309655D03*
X566460Y157586D03*
X574107Y294246D03*
X570216Y764529D03*
X582193Y90190D03*
Y83190D03*
X588194Y175067D03*
X575538Y307720D03*
X575567Y301185D03*
X585585Y374569D03*
X579385Y376519D03*
Y387319D03*
X585585D03*
X579385Y401250D03*
X575216Y764529D03*
X595260Y157586D03*
X602293Y206278D03*
X598294Y198278D03*
X602294D03*
X608793Y206278D03*
X608794Y198278D03*
X618705Y292822D03*
X615385Y387319D03*
Y376519D03*
Y406938D03*
X625310Y175626D03*
X626705Y292822D03*
X622705D03*
X621585Y374569D03*
Y387319D03*
X619500Y439017D03*
X626703Y1350201D03*
X630000Y1401517D03*
X635060Y143160D03*
X646231Y150068D03*
X642500Y419017D03*
X638000Y422517D03*
X643563Y1386914D03*
X647445Y1386938D03*
X635000Y1401517D03*
X637794Y1718487D03*
X653821Y84279D03*
X649500Y376517D03*
X655702Y1385440D03*
X659559Y1385382D03*
X651877Y1385407D03*
X652800Y1691317D03*
X656800D03*
X675843Y104202D03*
X666885Y405272D03*
X665832Y1527517D03*
X673113Y1729778D03*
Y1719116D03*
X680623Y108902D03*
X687453Y128185D03*
X683453D03*
X689440Y363421D03*
X690800Y376879D03*
X687500Y393379D03*
X687310Y507879D03*
X692500D03*
X679500Y521017D03*
X688500Y540379D03*
X688120Y1516543D03*
X704953Y128185D03*
X694453D03*
X700963Y128245D03*
X707545Y363338D03*
X703520Y363421D03*
X708300Y376879D03*
X704300D03*
X700300D03*
X707500Y393379D03*
X699500D03*
X695500D03*
X703500D03*
X700500Y507879D03*
X696500D03*
Y524379D03*
X700500Y540379D03*
X704500Y550379D03*
X704056Y577598D03*
X698996D03*
X708056D03*
X694996D03*
X698699Y1345887D03*
X705680Y1374742D03*
X705657Y1392063D03*
X701661Y1392085D03*
X697731Y1392055D03*
X698500Y1591017D03*
X696030Y1627794D03*
X699799Y1627710D03*
X723500Y363379D03*
X715395Y363369D03*
X712300Y376879D03*
X720300D03*
X715500Y393379D03*
X711500D03*
X720500Y550379D03*
Y540379D03*
X720787Y630848D03*
X716721Y630784D03*
X711702Y649273D03*
X709551Y1400694D03*
X723146Y1399694D03*
X710217Y1435755D03*
X723050Y1599450D03*
X717110Y1599540D03*
X715152Y1627598D03*
X729380Y75035D03*
X734380D03*
X723933Y135505D03*
X731500Y363379D03*
X727564Y376879D03*
X735500Y393379D03*
X732500Y507879D03*
X728500D03*
X736500D03*
X728500Y540379D03*
X736500D03*
X732500Y540517D03*
X738462Y1374842D03*
X738439Y1392163D03*
X732723Y1627037D03*
X736723D03*
X728723D03*
X732434Y1685190D03*
X728454Y1685021D03*
X737468Y1687220D03*
X745500Y199517D03*
X747500Y376879D03*
X743500Y393379D03*
X747500D03*
X751500D03*
X739652Y393361D03*
X744500Y507879D03*
X752500D03*
X748500D03*
X740895Y524398D03*
X748500Y524379D03*
X752500D03*
X744500D03*
X752500Y540379D03*
X742333Y1400794D03*
X740723Y1627037D03*
X752187Y1685511D03*
X741326Y1683829D03*
X760193Y100745D03*
X761000Y212517D03*
X759500Y376879D03*
Y393379D03*
X755500D03*
X764500Y507879D03*
X756500D03*
X760500D03*
X756500Y524379D03*
X760500D03*
X764500D03*
X765000Y540379D03*
X755928Y1399794D03*
X757770Y1628300D03*
X761770D03*
X754030Y1656100D03*
X767381Y1670258D03*
X754030Y1663100D03*
X762030D03*
X767368Y1662579D03*
X773766Y281339D03*
X781456Y378134D03*
X775500Y393379D03*
X771500D03*
X773000Y540379D03*
X768700Y540517D03*
X779447Y1334273D03*
X770450Y1581050D03*
X789277Y1524346D03*
X809817Y561954D03*
X807669Y1301733D03*
X812750Y1581950D03*
X819114Y117715D03*
X823114D03*
X827114D03*
X826614Y147215D03*
X824500Y508517D03*
X820500D03*
X831114Y117715D03*
X839360Y117599D03*
X840221Y184879D03*
X840220Y197879D03*
X839000Y386017D03*
X841872Y535202D03*
X844936Y90268D03*
X844221Y184879D03*
X844220Y197879D03*
X848500Y455017D03*
X852000Y486017D03*
X848762Y524505D03*
X854750Y1581950D03*
X871500Y316517D03*
X867190Y384777D03*
X871190D03*
X864065Y516053D03*
X886503Y278804D03*
X876923Y1242437D03*
X889368Y1141595D03*
X893368D03*
X895394Y1159848D03*
X896750Y1581950D03*
X916268Y272376D03*
X945263Y274673D03*
X936393Y1141595D03*
X940393D03*
X942419Y1159848D03*
X935907Y1242437D03*
X965442Y171902D03*
X981445Y179600D03*
X977195Y207940D03*
X1005699Y171360D03*
X999915Y179090D03*
X996415D03*
X1005395Y218440D03*
X1009735Y157960D03*
X1014828Y261782D03*
Y270944D03*
X1015334Y291328D03*
X1007011Y542016D03*
X1019961Y557449D03*
X1023220Y186116D03*
X1024961Y557449D03*
X1039000Y557517D03*
X1064915Y1308005D03*
X1066363Y1382567D03*
X1062405Y1382535D03*
X1064221Y1656937D03*
X1063751Y1648011D03*
X1069322Y401065D03*
X1069862Y1356714D03*
X1073733Y1382666D03*
X1069839Y1374035D03*
X1068094Y1648012D03*
X1068221Y1656937D03*
X1087328Y1381856D03*
X1094514Y1722933D03*
X1102462Y1356714D03*
X1102439Y1374035D03*
X1106333Y1382666D03*
X1108747Y1528897D03*
X1109558Y1544603D03*
X1105000Y1676517D03*
X1098514Y1715933D03*
X1119928Y1381856D03*
X1114617Y1528897D03*
X1115005Y1579568D03*
X1116000Y1665517D03*
X1120303Y1676452D03*
X1119361Y1716251D03*
X1135162Y1356714D03*
X1135139Y1374035D03*
X1139033Y1382666D03*
X1129846Y1456465D03*
X1131256Y1569044D03*
X1140117Y1665669D03*
X1152628Y1381856D03*
X1144107Y1665583D03*
X1168062Y1356714D03*
X1168039Y1374035D03*
X1180849Y461707D03*
X1178340Y469682D03*
X1171933Y1382666D03*
X1185528Y1381856D03*
X1195488Y88067D03*
X1215581Y85863D03*
X1200862Y1356714D03*
X1200839Y1374035D03*
X1204733Y1382666D03*
X1208000Y1394017D03*
X1210254Y1713953D03*
Y1706953D03*
Y1727953D03*
Y1720953D03*
X1206254Y1724803D03*
X1223455Y85863D03*
X1218328Y1381856D03*
X1238853Y1310568D03*
X1238830Y1327889D03*
X1242724Y1336520D03*
X1245000Y1427017D03*
Y1434017D03*
Y1441017D03*
X1241000D03*
X1253152Y87412D03*
Y98042D03*
X1256319Y1335710D03*
X1247000Y1403517D03*
X1256859Y1420017D03*
X1249000Y1427017D03*
Y1434017D03*
X1253000D03*
X1263472Y87381D03*
X1271749Y1310540D03*
X1271726Y1327861D03*
X1275620Y1336492D03*
X1289215Y1335682D03*
X1281470Y1552937D03*
X1287372D03*
X1296386Y545340D03*
X1299986D03*
X1296156Y555965D03*
X1304653Y1310483D03*
X1304630Y1327804D03*
X1307857Y105870D03*
X1305187Y565788D03*
X1308524Y1336435D03*
X1331930Y61462D03*
X1322119Y1335625D03*
X1343840Y61428D03*
X1337453Y1310683D03*
X1337430Y1328004D03*
X1341324Y1336635D03*
X1355750Y61428D03*
X1361976Y614610D03*
X1350261Y632598D03*
X1354597D03*
X1354919Y1335825D03*
X1367950Y61428D03*
X1370035Y1330014D03*
X1373906Y1355966D03*
X1370012Y1347335D03*
X1383507Y632931D03*
X1387297Y665498D03*
X1387501Y1355156D03*
X1394676Y647510D03*
X1407543Y1006439D03*
X1403803D03*
X1400063D03*
X1416207Y665831D03*
X1420007Y697748D03*
X1415024Y1006439D03*
X1411283D03*
X1418764D03*
X1422504D03*
X1417711Y1258883D03*
X1421211D03*
X1409532Y1552937D03*
X1415434D03*
X1415622Y1610284D03*
X1410622D03*
X1413622Y1637859D03*
X1434262Y55409D03*
X1439049Y109960D03*
X1429169Y109830D03*
X1427276Y680090D03*
X1433724Y1006439D03*
X1429984D03*
X1426244D03*
X1438532Y1275277D03*
X1448549Y117160D03*
X1443049Y109960D03*
X1448807Y698411D03*
X1452765Y717424D03*
X1449334Y1272009D03*
X1453334D03*
X1442532Y1275277D03*
X1450500Y1627017D03*
X1445500D03*
X1440500D03*
X1450500Y1617517D03*
X1442579Y1667820D03*
X1447579D03*
X1452579D03*
X1459896Y58505D03*
X1454549Y109960D03*
X1460194Y699667D03*
X1457579Y1667820D03*
X1481725Y717988D03*
X1493276Y699667D03*
X1485897Y717655D03*
X1513644Y246442D03*
X1505477Y1270905D03*
X1526076Y699667D03*
X1518697Y717655D03*
X1514807Y717988D03*
X1533454Y88238D03*
X1537454D03*
X1542697Y562104D03*
X1547827Y695547D03*
X1551827D03*
X1547607Y717988D03*
X1556178Y1262880D03*
X1558077Y1273305D03*
X1554377D03*
X1545644Y1552937D03*
X1551546D03*
X1559206Y677727D03*
X1560157Y1262880D03*
X1584597Y661946D03*
X1580597D03*
X1580737Y696048D03*
X1583177Y1262305D03*
X1587177D03*
X1575680Y1299996D03*
X1588800Y303688D03*
X1591976Y643958D03*
X1591177Y1262305D03*
X1617400Y303688D03*
X1617506Y564943D03*
X1617597Y642946D03*
X1613597D03*
X1613507Y662279D03*
X1629000Y386017D03*
Y393017D03*
X1624976Y624958D03*
X1646510Y428561D03*
X1646507Y643279D03*
X1645155Y1391337D03*
X1634327Y1406457D03*
X1662000Y218017D03*
X1651910Y230004D03*
X1652610Y397219D03*
X1661110Y428719D03*
X1653413Y1374031D03*
X1657284Y1399983D03*
X1653390Y1391352D03*
X1649197Y1391285D03*
X1653667Y1440258D03*
X1658167D03*
X1662465Y1438691D03*
X1657892Y1452377D03*
X1653614Y1452356D03*
X1650513Y1708701D03*
Y1715701D03*
Y1723851D03*
Y1730851D03*
X1673872Y428162D03*
X1670879Y1398983D03*
X1666290Y1438724D03*
X1670147Y1438666D03*
X1673706Y1560517D03*
X1675360Y1709019D03*
Y1723769D03*
X1684942Y228429D03*
X1686154Y428702D03*
X1686195Y1374131D03*
X1690066Y1400083D03*
X1686172Y1391452D03*
X1688243Y1666319D03*
X1692415Y1666257D03*
X1679816Y1666320D03*
X1685513Y1715701D03*
Y1708701D03*
X1704624Y428192D03*
X1701124D03*
X1703661Y1399083D03*
X1718608Y101101D03*
X1721418Y125184D03*
X1717418D03*
X1713312Y138239D03*
X1715044Y407062D03*
X1718931Y407054D03*
X1710408Y420462D03*
X1720845Y1673851D03*
X1710360Y1709019D03*
X1722608Y105901D03*
X1736418Y125184D03*
X1729418D03*
X1725418D03*
X1730364Y171468D03*
X1722500Y368879D03*
X1725500Y377879D03*
X1735945Y1556388D03*
X1728633Y1705207D03*
X1724633Y1712207D03*
Y1705207D03*
Y1720357D03*
Y1727357D03*
X1746918Y125184D03*
X1743418Y128684D03*
X1740688Y1531121D03*
X1737914Y1570224D03*
X1737979Y1577422D03*
X1739279Y1584495D03*
X1750380Y1710325D03*
X1749480Y1720675D03*
X1764478Y117144D03*
X1756051Y1580349D03*
X1758963Y1685982D03*
X1763463D03*
X1771688Y1556388D03*
X1773657Y1570724D03*
X1790738Y82384D03*
X1784133Y162916D03*
Y155827D03*
X1783448Y207474D03*
X1791794Y1580049D03*
X1819705Y163889D03*
G54D323*
X1900275Y-39973D03*
Y572227D03*
X1898799Y1198198D03*
Y1810398D03*
X1910275Y-39973D03*
Y572227D03*
X1908799Y1198198D03*
Y1810398D03*
X1921395Y-39963D03*
X1931395D03*
Y572237D03*
X1921395D03*
X1931395D03*
X1921395D03*
Y1184437D03*
X1931395D03*
X1929766Y1198160D03*
X1919766D03*
Y1810360D03*
X1929766D03*
X1942395Y-39783D03*
Y572417D03*
D03*
X1940886Y1198170D03*
X1942395Y1184617D03*
X1940886Y1810370D03*
X1952395Y-39783D03*
X1963362Y-39821D03*
Y572379D03*
X1952395Y572417D03*
D03*
X1963362Y572379D03*
X1950886Y1198170D03*
X1952395Y1184617D03*
X1963362Y1184579D03*
X1961856Y1198170D03*
X1950886Y1810370D03*
X1961856D03*
X1973362Y-39821D03*
Y572379D03*
D03*
Y1184579D03*
X1971856Y1198170D03*
Y1810370D03*
X1984482Y-39811D03*
Y572389D03*
D03*
Y1184589D03*
X1982856Y1198350D03*
X1992856D03*
Y1810550D03*
X1982856D03*
X1994482Y-39811D03*
X2005452D03*
Y572389D03*
X1994482D03*
D03*
X2005452D03*
X1994482Y1184589D03*
X2005452D03*
X2003823Y1198312D03*
Y1810512D03*
X2015452Y-39811D03*
Y572389D03*
D03*
Y1184589D03*
X2013823Y1198312D03*
Y1810512D03*
X2036452Y-39631D03*
X2026452D03*
Y572569D03*
X2036452D03*
X2026452D03*
X2036452D03*
Y1184769D03*
X2026452D03*
X2047419Y-39669D03*
Y572531D03*
D03*
Y1184731D03*
X2057419Y-39669D03*
Y572531D03*
D03*
Y1184731D03*
X2068539Y572541D03*
X2078539D03*
Y1184741D03*
X2068539D03*
G54D41*
X57646Y12480D03*
X137272D03*
X186622D03*
X266858D03*
X315598D03*
X502528Y33267D03*
X582154D03*
X631504D03*
X711740D03*
X760480D03*
X1183858Y207205D03*
Y217205D03*
X1173858D03*
X1193858Y207205D03*
Y217205D03*
X1351260Y164213D03*
Y174213D03*
X1361260Y164213D03*
Y174213D03*
X1371260Y164213D03*
X1381260D03*
X1371260Y174213D03*
X1381260D03*
X1391260Y164213D03*
X1532055Y12480D03*
X1611681D03*
X1661031D03*
X1741267D03*
X1790007D03*
G54D314*
X1797245Y201297D03*
G54D107*
X184530Y1514243D03*
X186105Y1516970D03*
X184530Y1527880D03*
X186105Y1530608D03*
X189254Y1514243D03*
X193979D03*
X198703D03*
X187680Y1519698D03*
X192404D03*
X197128D03*
X190829Y1516970D03*
X195554D03*
X200278D03*
X189254Y1536063D03*
X193979D03*
X198703D03*
X187680Y1533336D03*
X192404D03*
X197128D03*
X190829Y1530608D03*
X195554D03*
X200278D03*
X203428Y1514243D03*
X208152D03*
X212876D03*
X216026Y1519698D03*
X201853D03*
X206577D03*
X211302D03*
X214451Y1516970D03*
X205002D03*
X209727D03*
X203428Y1536063D03*
X208152D03*
X212876D03*
X216026Y1533336D03*
X201853D03*
X206577D03*
X211302D03*
X214451Y1530608D03*
X205002D03*
X209727D03*
X217601Y1514243D03*
X222325D03*
X227050D03*
X220750Y1519698D03*
X225475D03*
X230199D03*
X219176Y1516970D03*
X223900D03*
X228624D03*
X217601Y1536063D03*
X222325D03*
X227050D03*
X220750Y1533336D03*
X225475D03*
X230199D03*
X219176Y1530608D03*
X223900D03*
X228624D03*
X231774Y1514243D03*
X236498D03*
X241223D03*
X245947D03*
X234924Y1519698D03*
X239648D03*
X244372D03*
X233349Y1516970D03*
X238073D03*
X242798D03*
X231774Y1536063D03*
X236498D03*
X241223D03*
X245947D03*
X234924Y1533336D03*
X239648D03*
X244372D03*
X233349Y1530608D03*
X238073D03*
X242798D03*
X255396Y1514243D03*
X250672D03*
X249097Y1519698D03*
X253821D03*
X258546D03*
X247522Y1516970D03*
X252247D03*
X256971D03*
X255396Y1536063D03*
X260121D03*
X250672D03*
X249097Y1533336D03*
X253821D03*
X258546D03*
X247522Y1530608D03*
X252247D03*
X256971D03*
X312592Y1514243D03*
X317316D03*
X315742Y1519698D03*
X320466D03*
X314167Y1516970D03*
X318891D03*
X312592Y1527880D03*
X317316Y1536063D03*
X315742Y1533336D03*
X320466D03*
X314167Y1530608D03*
X318891D03*
X322041Y1514243D03*
X326765D03*
X331490D03*
X325190Y1519698D03*
X329915D03*
X334639D03*
X323616Y1516970D03*
X328340D03*
X333064D03*
X322041Y1536063D03*
X326765D03*
X331490D03*
X325190Y1533336D03*
X329915D03*
X334639D03*
X323616Y1530608D03*
X328340D03*
X333064D03*
X336214Y1514243D03*
X340938D03*
X345663D03*
X350387D03*
X344088Y1519698D03*
X348812D03*
X339364D03*
X342513Y1516970D03*
X347238D03*
X337789D03*
X336214Y1536063D03*
X340938D03*
X345663D03*
X350387D03*
X344088Y1533336D03*
X348812D03*
X339364D03*
X342513Y1530608D03*
X347238D03*
X337789D03*
X355112Y1514243D03*
X359836D03*
X364560D03*
X353537Y1519698D03*
X358261D03*
X362986D03*
X351962Y1516970D03*
X356686D03*
X361411D03*
X355112Y1536063D03*
X359836D03*
X364560D03*
X353537Y1533336D03*
X358261D03*
X362986D03*
X351962Y1530608D03*
X356686D03*
X361411D03*
X369285Y1514243D03*
X374009D03*
X378734D03*
X367710Y1519698D03*
X372434D03*
X377159D03*
X366135Y1516970D03*
X370860D03*
X375584D03*
X380309D03*
X369285Y1536063D03*
X374009D03*
X378734D03*
X367710Y1533336D03*
X372434D03*
X377159D03*
X366135Y1530608D03*
X370860D03*
X375584D03*
X380309D03*
X383458Y1514243D03*
X381883Y1519698D03*
X386608D03*
X385033Y1516970D03*
X383458Y1536063D03*
X388183D03*
X381883Y1533336D03*
X386608D03*
X385033Y1530608D03*
X448703Y1514243D03*
X453427D03*
X451853Y1519698D03*
X450278Y1516970D03*
X455002D03*
X448703Y1527880D03*
X453427Y1536063D03*
X451853Y1533336D03*
X450278Y1530608D03*
X455002D03*
X458152Y1514243D03*
X462876D03*
X467601D03*
X456577Y1519698D03*
X461301D03*
X466026D03*
X459727Y1516970D03*
X464451D03*
X469175D03*
X458152Y1536063D03*
X462876D03*
X467601D03*
X456577Y1533336D03*
X461301D03*
X466026D03*
X459727Y1530608D03*
X464451D03*
X469175D03*
X472325Y1514243D03*
X477049D03*
X481774D03*
X480199Y1519698D03*
X470750D03*
X475475D03*
X478624Y1516970D03*
X483349D03*
X473900D03*
X472325Y1536063D03*
X477049D03*
X481774D03*
X480199Y1533336D03*
X470750D03*
X475475D03*
X478624Y1530608D03*
X483349D03*
X473900D03*
X486498Y1514243D03*
X491223D03*
X495947D03*
X484923Y1519698D03*
X489648D03*
X494372D03*
X499097D03*
X488073Y1516970D03*
X492797D03*
X497522D03*
X486498Y1536063D03*
X491223D03*
X495947D03*
X484923Y1533336D03*
X489648D03*
X494372D03*
X499097D03*
X488073Y1530608D03*
X492797D03*
X497522D03*
X500671Y1514243D03*
X505396D03*
X510120D03*
X503821Y1519698D03*
X508545D03*
X513270D03*
X502246Y1516970D03*
X506971D03*
X511695D03*
X500671Y1536063D03*
X505396D03*
X510120D03*
X503821Y1533336D03*
X508545D03*
X513270D03*
X502246Y1530608D03*
X506971D03*
X511695D03*
X519569Y1514243D03*
X514845D03*
X517994Y1519698D03*
X522719D03*
X516420Y1516970D03*
X521144D03*
X519569Y1536063D03*
X524294D03*
X514845D03*
X517994Y1533336D03*
X522719D03*
X516420Y1530608D03*
X521144D03*
X576765Y1514243D03*
X581489D03*
X586214D03*
X579915Y1519698D03*
X584639D03*
X578340Y1516970D03*
X583064D03*
X587789D03*
X576765Y1527880D03*
X581489Y1536063D03*
X586214D03*
X579915Y1533336D03*
X584639D03*
X578340Y1530608D03*
X583064D03*
X587789D03*
X590938Y1514243D03*
X595663D03*
X600387D03*
X589363Y1519698D03*
X594088D03*
X598812D03*
X603537D03*
X592513Y1516970D03*
X597237D03*
X601962D03*
X590938Y1536063D03*
X595663D03*
X600387D03*
X589363Y1533336D03*
X594088D03*
X598812D03*
X603537D03*
X592513Y1530608D03*
X597237D03*
X601962D03*
X605111Y1514243D03*
X609836D03*
X614560D03*
X608261Y1519698D03*
X612985D03*
X617710D03*
X606686Y1516970D03*
X611411D03*
X616135D03*
X605111Y1536063D03*
X609836D03*
X614560D03*
X608261Y1533336D03*
X612985D03*
X617710D03*
X606686Y1530608D03*
X611411D03*
X616135D03*
X619285Y1514243D03*
X624009D03*
X628733D03*
X633458D03*
X622434Y1519698D03*
X627159D03*
X631883D03*
X620859Y1516970D03*
X625584D03*
X630308D03*
X619285Y1536063D03*
X624009D03*
X628733D03*
X633458D03*
X622434Y1533336D03*
X627159D03*
X631883D03*
X620859Y1530608D03*
X625584D03*
X630308D03*
X647631Y1514243D03*
X638182D03*
X642907D03*
X636607Y1519698D03*
X641332D03*
X646056D03*
X635033Y1516970D03*
X639757D03*
X644482D03*
X647631Y1536063D03*
X638182D03*
X642907D03*
X636607Y1533336D03*
X641332D03*
X646056D03*
X635033Y1530608D03*
X639757D03*
X644482D03*
X650781Y1519698D03*
X649206Y1516970D03*
X652356Y1536063D03*
X650781Y1533336D03*
X649206Y1530608D03*
X1192403Y1547243D03*
X1197127D03*
X1193978Y1549970D03*
X1198702D03*
X1192403Y1560880D03*
X1195553Y1566336D03*
X1200277D03*
X1193978Y1563608D03*
X1198702D03*
X1195553Y1552698D03*
X1200277D03*
X1197127Y1569063D03*
X1201852Y1547243D03*
X1206576D03*
X1211301D03*
X1203427Y1549970D03*
X1208151D03*
X1212875D03*
X1205001Y1566336D03*
X1209726D03*
X1214450D03*
X1203427Y1563608D03*
X1208151D03*
X1212875D03*
X1205001Y1552698D03*
X1209726D03*
X1214450D03*
X1201852Y1569063D03*
X1206576D03*
X1211301D03*
X1216025Y1547243D03*
X1220749D03*
X1225474D03*
X1230198D03*
X1222324Y1549970D03*
X1227049D03*
X1217600D03*
X1223899Y1566336D03*
X1228623D03*
X1219175D03*
X1222324Y1563608D03*
X1227049D03*
X1217600D03*
X1223899Y1552698D03*
X1228623D03*
X1219175D03*
X1216025Y1569063D03*
X1220749D03*
X1225474D03*
X1230198D03*
X1234923Y1547243D03*
X1239647D03*
X1244371D03*
X1231773Y1549970D03*
X1236497D03*
X1241222D03*
X1233348Y1566336D03*
X1238072D03*
X1242797D03*
X1231773Y1563608D03*
X1236497D03*
X1241222D03*
X1233348Y1552698D03*
X1238072D03*
X1242797D03*
X1234923Y1569063D03*
X1239647D03*
X1244371D03*
X1249096Y1547243D03*
X1253820D03*
X1258545D03*
X1245946Y1549970D03*
X1250671D03*
X1255395D03*
X1247521Y1566336D03*
X1252245D03*
X1256970D03*
X1245946Y1563608D03*
X1250671D03*
X1255395D03*
X1247521Y1552698D03*
X1252245D03*
X1256970D03*
X1249096Y1569063D03*
X1253820D03*
X1258545D03*
X1263269Y1547243D03*
X1260120Y1549970D03*
X1264844D03*
X1261694Y1566336D03*
X1266419D03*
X1260120Y1563608D03*
X1264844D03*
X1261694Y1552698D03*
X1266419D03*
X1263269Y1569063D03*
X1267994D03*
X1320465Y1547243D03*
X1325189D03*
X1329914D03*
X1322040Y1549970D03*
X1326764D03*
X1331489D03*
X1320465Y1560880D03*
X1323615Y1566336D03*
X1328339D03*
X1333063D03*
X1322040Y1563608D03*
X1326764D03*
X1331489D03*
X1323615Y1552698D03*
X1328339D03*
X1333063D03*
X1325189Y1569063D03*
X1329914D03*
X1334638Y1547243D03*
X1339363D03*
X1344087D03*
X1348811D03*
X1336213Y1549970D03*
X1340937D03*
X1345662D03*
X1337788Y1566336D03*
X1342512D03*
X1347237D03*
X1336213Y1563608D03*
X1340937D03*
X1345662D03*
X1337788Y1552698D03*
X1342512D03*
X1347237D03*
X1334638Y1569063D03*
X1339363D03*
X1344087D03*
X1348811D03*
X1353536Y1547243D03*
X1358260D03*
X1362985D03*
X1350386Y1549970D03*
X1355111D03*
X1359835D03*
X1351961Y1566336D03*
X1356685D03*
X1361410D03*
X1350386Y1563608D03*
X1355111D03*
X1359835D03*
X1351961Y1552698D03*
X1356685D03*
X1361410D03*
X1353536Y1569063D03*
X1358260D03*
X1362985D03*
X1367709Y1547243D03*
X1372433D03*
X1377158D03*
X1364559Y1549970D03*
X1369284D03*
X1374008D03*
X1378733D03*
X1366134Y1566336D03*
X1370859D03*
X1375583D03*
X1364559Y1563608D03*
X1369284D03*
X1374008D03*
X1378733D03*
X1366134Y1552698D03*
X1370859D03*
X1375583D03*
X1367709Y1569063D03*
X1372433D03*
X1377158D03*
X1391331Y1547243D03*
X1381882D03*
X1386607D03*
X1383457Y1549970D03*
X1388182D03*
X1392906D03*
X1380307Y1566336D03*
X1385032D03*
X1389756D03*
X1383457Y1563608D03*
X1388182D03*
X1392906D03*
X1380307Y1552698D03*
X1385032D03*
X1389756D03*
X1391331Y1569063D03*
X1381882D03*
X1386607D03*
X1394481Y1566336D03*
Y1552698D03*
X1396056Y1569063D03*
X1456577Y1547243D03*
X1461301D03*
X1466026D03*
X1458152Y1549970D03*
X1462876D03*
X1467601D03*
X1456577Y1560880D03*
X1459727Y1566336D03*
X1464451D03*
X1458152Y1563608D03*
X1462876D03*
X1467601D03*
X1459727Y1552698D03*
X1464451D03*
X1461301Y1569063D03*
X1466026D03*
X1470750Y1547243D03*
X1475475D03*
X1480199D03*
X1472325Y1549970D03*
X1477049D03*
X1481774D03*
X1469175Y1566336D03*
X1473900D03*
X1478624D03*
X1483349D03*
X1472325Y1563608D03*
X1477049D03*
X1481774D03*
X1469175Y1552698D03*
X1473900D03*
X1478624D03*
X1483349D03*
X1470750Y1569063D03*
X1475475D03*
X1480199D03*
X1484923Y1547243D03*
X1489648D03*
X1494372D03*
X1486498Y1549970D03*
X1491223D03*
X1495947D03*
X1488073Y1566336D03*
X1492797D03*
X1497522D03*
X1486498Y1563608D03*
X1491223D03*
X1495947D03*
X1488073Y1552698D03*
X1492797D03*
X1497522D03*
X1484923Y1569063D03*
X1489648D03*
X1494372D03*
X1499097Y1547243D03*
X1503821D03*
X1508545D03*
X1513270D03*
X1500671Y1549970D03*
X1505396D03*
X1510120D03*
X1502246Y1566336D03*
X1506971D03*
X1511695D03*
X1500671Y1563608D03*
X1505396D03*
X1510120D03*
X1502246Y1552698D03*
X1506971D03*
X1511695D03*
X1499097Y1569063D03*
X1503821D03*
X1508545D03*
X1513270D03*
X1527443Y1547243D03*
X1517994D03*
X1522719D03*
X1514845Y1549970D03*
X1519569D03*
X1524294D03*
X1516419Y1566336D03*
X1521144D03*
X1525868D03*
X1514845Y1563608D03*
X1519569D03*
X1524294D03*
X1516419Y1552698D03*
X1521144D03*
X1525868D03*
X1527443Y1569063D03*
X1517994D03*
X1522719D03*
X1529018Y1549970D03*
X1530593Y1566336D03*
X1529018Y1563608D03*
X1530593Y1552698D03*
X1532168Y1569063D03*
X1584639Y1547243D03*
X1586214Y1549970D03*
X1584639Y1560880D03*
X1587789Y1566336D03*
X1586214Y1563608D03*
X1587789Y1552698D03*
X1589363Y1547243D03*
X1594088D03*
X1598812D03*
X1590938Y1549970D03*
X1595663D03*
X1600387D03*
X1592513Y1566336D03*
X1597237D03*
X1601962D03*
X1590938Y1563608D03*
X1595663D03*
X1600387D03*
X1592513Y1552698D03*
X1597237D03*
X1601962D03*
X1589363Y1569063D03*
X1594088D03*
X1598812D03*
X1603537Y1547243D03*
X1608261D03*
X1612985D03*
X1617710D03*
X1614560Y1549970D03*
X1605111D03*
X1609836D03*
X1616135Y1566336D03*
X1606686D03*
X1611411D03*
X1614560Y1563608D03*
X1605111D03*
X1609836D03*
X1616135Y1552698D03*
X1606686D03*
X1611411D03*
X1603537Y1569063D03*
X1608261D03*
X1612985D03*
X1617710D03*
X1622434Y1547243D03*
X1627159D03*
X1631883D03*
X1619285Y1549970D03*
X1624009D03*
X1628733D03*
X1620859Y1566336D03*
X1625584D03*
X1630308D03*
X1619285Y1563608D03*
X1624009D03*
X1628733D03*
X1620859Y1552698D03*
X1625584D03*
X1630308D03*
X1622434Y1569063D03*
X1627159D03*
X1631883D03*
X1636607Y1547243D03*
X1641332D03*
X1646056D03*
X1633458Y1549970D03*
X1638182D03*
X1642907D03*
X1647631D03*
X1635033Y1566336D03*
X1639757D03*
X1644481D03*
X1633458Y1563608D03*
X1638182D03*
X1642907D03*
X1647631D03*
X1635033Y1552698D03*
X1639757D03*
X1644481D03*
X1636607Y1569063D03*
X1641332D03*
X1646056D03*
X1655505Y1547243D03*
X1650781D03*
X1652356Y1549970D03*
X1657080D03*
X1649206Y1566336D03*
X1653930D03*
X1658655D03*
X1652356Y1563608D03*
X1657080D03*
X1649206Y1552698D03*
X1653930D03*
X1658655D03*
X1655505Y1569063D03*
X1660230D03*
X1650781D03*
G54D143*
X312693Y59753D03*
X328441D03*
X747269Y79238D03*
X763017D03*
X1655999Y385598D03*
X1671747D03*
X1784364Y61037D03*
X1800112D03*
G54D251*
X796079Y1334469D03*
G54D126*
X275630Y109804D03*
X708786Y113929D03*
X1750751Y110928D03*
G54D234*
X733380Y1582361D03*
X785577Y1582363D03*
X827577D03*
X869577D03*
X911577D03*
G54D15*
X23031Y197224D03*
Y202224D03*
Y207224D03*
Y212224D03*
X39173Y197224D03*
Y202224D03*
Y207224D03*
Y212224D03*
X105975Y197241D03*
Y202241D03*
Y207241D03*
Y212241D03*
X122117Y197241D03*
Y202241D03*
Y207241D03*
Y212241D03*
X1255315Y236594D03*
Y241594D03*
Y246594D03*
Y251594D03*
X1271457Y236594D03*
Y241594D03*
Y246594D03*
Y251594D03*
X1341535Y236594D03*
Y251594D03*
Y246594D03*
Y241594D03*
X1357677Y236594D03*
Y251594D03*
Y246594D03*
Y241594D03*
G54D144*
X318333Y78520D03*
X316364D03*
X314395D03*
X312427D03*
X310459D03*
X308490D03*
X306521D03*
X318333Y80489D03*
X316364D03*
X314395D03*
X312427D03*
X310459D03*
X308490D03*
X306521D03*
X318333Y82457D03*
X316364D03*
X314395D03*
X312427D03*
X310459D03*
X308490D03*
X306521D03*
X318333Y84426D03*
X316364D03*
X314395D03*
X312427D03*
X310459D03*
X308490D03*
X306521D03*
X354139Y232608D03*
X356108D03*
X358077D03*
X360045D03*
X362013D03*
X363982D03*
X354139Y230639D03*
X356108D03*
X358077D03*
X360045D03*
X362013D03*
X363982D03*
X354139Y228671D03*
X356108D03*
X358077D03*
X360045D03*
X362013D03*
X363982D03*
X354139Y226702D03*
X356108D03*
X358077D03*
X360045D03*
X362013D03*
X363982D03*
X365951Y232608D03*
Y230639D03*
Y228671D03*
Y226702D03*
X750940Y98005D03*
X748971D03*
X747003D03*
X745035D03*
X743066D03*
X741097D03*
X750940Y99974D03*
X748971D03*
X747003D03*
X745035D03*
X743066D03*
X741097D03*
X750940Y101942D03*
X748971D03*
X747003D03*
X745035D03*
X743066D03*
X741097D03*
X750940Y103911D03*
X748971D03*
X747003D03*
X745035D03*
X743066D03*
X741097D03*
X752909Y98005D03*
Y99974D03*
Y101942D03*
Y103911D03*
X871345Y276064D03*
X869376D03*
X867407D03*
X871345Y278033D03*
X869376D03*
X867407D03*
X871345Y280001D03*
X869376D03*
X867407D03*
X871345Y281970D03*
X869376D03*
X867407D03*
X879219Y276064D03*
X877250D03*
X875281D03*
X873313D03*
X879219Y278033D03*
X877250D03*
X875281D03*
X873313D03*
X879219Y280001D03*
X877250D03*
X875281D03*
X873313D03*
X879219Y281970D03*
X877250D03*
X875281D03*
X873313D03*
X992452Y159667D03*
Y161636D03*
Y163605D03*
Y165573D03*
X994421Y159667D03*
Y161636D03*
Y163605D03*
Y165573D03*
X996389Y159667D03*
Y161636D03*
Y163605D03*
Y165573D03*
X998358Y159667D03*
Y161636D03*
Y163605D03*
Y165573D03*
X992452Y167541D03*
Y169510D03*
Y171479D03*
X994421Y167541D03*
Y169510D03*
Y171479D03*
X996389Y167541D03*
Y169510D03*
Y171479D03*
X998358Y167541D03*
Y169510D03*
Y171479D03*
X1697161Y408769D03*
Y410738D03*
Y412707D03*
Y414675D03*
Y416643D03*
Y418612D03*
X1699130Y408769D03*
Y410738D03*
Y412707D03*
Y414675D03*
Y416643D03*
Y418612D03*
X1701098Y408769D03*
Y410738D03*
Y412707D03*
Y414675D03*
Y416643D03*
Y418612D03*
X1703067Y408769D03*
Y410738D03*
Y412707D03*
Y414675D03*
Y416643D03*
Y418612D03*
X1697161Y420581D03*
X1699130D03*
X1701098D03*
X1703067D03*
X1779516Y79644D03*
X1777548D03*
X1775580D03*
X1773611D03*
X1771642D03*
X1779516Y81613D03*
X1777548D03*
X1775580D03*
X1773611D03*
X1771642D03*
X1779516Y83581D03*
X1777548D03*
X1775580D03*
X1773611D03*
X1771642D03*
X1779516Y85550D03*
X1777548D03*
X1775580D03*
X1773611D03*
X1771642D03*
X1783454Y79644D03*
X1781485D03*
X1783454Y81613D03*
X1781485D03*
X1783454Y83581D03*
X1781485D03*
X1783454Y85550D03*
X1781485D03*
G54D171*
X430520Y248768D03*
Y253768D03*
Y258768D03*
Y263768D03*
X450992Y253768D03*
Y248768D03*
Y263768D03*
Y258768D03*
X1133070Y1579453D03*
Y1584453D03*
Y1589453D03*
Y1594453D03*
X1153542Y1579453D03*
Y1594453D03*
Y1589453D03*
Y1584453D03*
X1205182Y431875D03*
Y436875D03*
Y441875D03*
Y446875D03*
X1225654Y431875D03*
Y446875D03*
Y441875D03*
Y436875D03*
X1217866Y455376D03*
Y460376D03*
Y465376D03*
Y470376D03*
X1238338Y460376D03*
Y455376D03*
Y470376D03*
Y465376D03*
G54D24*
X44000Y154200D03*
X31818Y1424257D03*
X441043Y1672205D03*
Y1718465D03*
X1416437Y1672205D03*
Y1718465D03*
X1800449Y126194D03*
X1804650Y1667292D03*
G54D270*
X913386Y179390D03*
Y177027D03*
Y174665D03*
Y172303D03*
Y169941D03*
Y167579D03*
Y195925D03*
Y193563D03*
Y191201D03*
Y188838D03*
Y186476D03*
Y184114D03*
Y181752D03*
Y210098D03*
Y207736D03*
Y205374D03*
Y203012D03*
Y200649D03*
Y198287D03*
Y224272D03*
Y221909D03*
Y219547D03*
Y217185D03*
Y214823D03*
Y212461D03*
Y231358D03*
Y228996D03*
Y226634D03*
X931496Y179390D03*
Y177027D03*
Y174665D03*
Y172303D03*
Y169941D03*
Y167579D03*
Y195925D03*
Y193563D03*
Y191201D03*
Y188838D03*
Y186476D03*
Y184114D03*
Y181752D03*
Y210098D03*
Y207736D03*
Y205374D03*
Y203012D03*
Y200649D03*
Y198287D03*
Y224272D03*
Y221909D03*
Y219547D03*
Y217185D03*
Y214823D03*
Y212461D03*
Y231358D03*
Y228996D03*
Y226634D03*
G54D42*
X65933Y32756D03*
Y44370D03*
X68295Y32756D03*
X70657D03*
X73020D03*
X75382D03*
X77744D03*
X80106D03*
X68295Y44370D03*
X70657D03*
X73020D03*
X75382D03*
X77744D03*
X80106D03*
X82468Y32756D03*
X84831D03*
X87193D03*
X89555D03*
X91917D03*
X94279D03*
X96642D03*
X82468Y44370D03*
X84831D03*
X87193D03*
X89555D03*
X91917D03*
X94279D03*
X96642D03*
X99004Y32756D03*
X101366D03*
X103728D03*
X106090D03*
X108453D03*
X110815D03*
X99004Y44370D03*
X101366D03*
X103728D03*
X106090D03*
X108453D03*
X110815D03*
X113177Y32756D03*
X115539D03*
X117902D03*
X120264D03*
X122626D03*
X124988D03*
X113177Y44370D03*
X115539D03*
X117902D03*
X120264D03*
X122626D03*
X124988D03*
X127350Y32756D03*
X129713D03*
X127350Y44370D03*
X129713D03*
X149043Y32756D03*
X151405D03*
X153768D03*
X156130D03*
X149043Y44370D03*
X151405D03*
X153768D03*
X156130D03*
X158492Y32756D03*
X160854D03*
X163216D03*
X165579D03*
X167941D03*
X170303D03*
X158492Y44370D03*
X160854D03*
X163216D03*
X165579D03*
X167941D03*
X170303D03*
X172665Y32756D03*
X175028D03*
X177390D03*
X179752D03*
X172665Y44370D03*
X175028D03*
X177390D03*
X179752D03*
X195539Y32756D03*
X197902D03*
X200264D03*
X195539Y44370D03*
X197902D03*
X200264D03*
X202626Y32756D03*
X204988D03*
X207350D03*
X209713D03*
X212075D03*
X214437D03*
X202626Y44370D03*
X204988D03*
X207350D03*
X209713D03*
X212075D03*
X214437D03*
X216799Y32756D03*
X219161D03*
X221524D03*
X223886D03*
X226248D03*
X228610D03*
X230972D03*
X216799Y44370D03*
X219161D03*
X221524D03*
X223886D03*
X226248D03*
X228610D03*
X230972D03*
X233335Y32756D03*
X235697D03*
X238059D03*
X240421D03*
X242783D03*
X245146D03*
X233335Y44370D03*
X235697D03*
X238059D03*
X240421D03*
X242783D03*
X245146D03*
X247508Y32756D03*
X249870D03*
X252232D03*
X254594D03*
X256957D03*
X259319D03*
X247508Y44370D03*
X249870D03*
X252232D03*
X254594D03*
X256957D03*
X259319D03*
X276622Y32756D03*
X278984D03*
X281346D03*
X283709D03*
X286071D03*
X288433D03*
X290795D03*
X276622Y44370D03*
X278984D03*
X281346D03*
X283709D03*
X286071D03*
X288433D03*
X290795D03*
X293157Y32756D03*
X295520D03*
X297882D03*
X300244D03*
X302606D03*
X304968D03*
X293157Y44370D03*
X295520D03*
X297882D03*
X300244D03*
X302606D03*
X304968D03*
X307331Y32756D03*
Y44370D03*
X510815Y53543D03*
X513177D03*
X510815Y65157D03*
X513177D03*
X515539Y53543D03*
X517902D03*
X520264D03*
X522626D03*
X524988D03*
X527350D03*
X515539Y65157D03*
X517902D03*
X520264D03*
X522626D03*
X524988D03*
X527350D03*
X529713Y53543D03*
X532075D03*
X534437D03*
X536799D03*
X539161D03*
X541524D03*
X543886D03*
X529713Y65157D03*
X532075D03*
X534437D03*
X536799D03*
X539161D03*
X541524D03*
X543886D03*
X546248Y53543D03*
X548610D03*
X550972D03*
X553335D03*
X555697D03*
X558059D03*
X546248Y65157D03*
X548610D03*
X550972D03*
X553335D03*
X555697D03*
X558059D03*
X560421Y53543D03*
X562784D03*
X565146D03*
X567508D03*
X569870D03*
X572232D03*
X560421Y65157D03*
X562784D03*
X565146D03*
X567508D03*
X569870D03*
X572232D03*
X574595Y53543D03*
Y65157D03*
X593925Y53543D03*
X596287D03*
X598650D03*
X601012D03*
X603374D03*
X593925Y65157D03*
X596287D03*
X598650D03*
X601012D03*
X603374D03*
X605736Y53543D03*
X608098D03*
X610461D03*
X612823D03*
X615185D03*
X617547D03*
X605736Y65157D03*
X608098D03*
X610461D03*
X612823D03*
X615185D03*
X617547D03*
X619910Y53543D03*
X622272D03*
X624634D03*
X619910Y65157D03*
X622272D03*
X624634D03*
X640421Y53543D03*
X642784D03*
X645146D03*
X647508D03*
X640421Y65157D03*
X642784D03*
X645146D03*
X647508D03*
X649870Y53543D03*
X652232D03*
X654595D03*
X656957D03*
X659319D03*
X661681D03*
X649870Y65157D03*
X652232D03*
X654595D03*
X656957D03*
X659319D03*
X661681D03*
X664043Y53543D03*
X666406D03*
X668768D03*
X671130D03*
X673492D03*
X675854D03*
X678217D03*
X664043Y65157D03*
X666406D03*
X668768D03*
X671130D03*
X673492D03*
X675854D03*
X678217D03*
X680579Y53543D03*
X682941D03*
X685303D03*
X687665D03*
X690028D03*
X692390D03*
X680579Y65157D03*
X682941D03*
X685303D03*
X687665D03*
X690028D03*
X692390D03*
X694752Y53543D03*
X697114D03*
X699476D03*
X701839D03*
X704201D03*
X694752Y65157D03*
X697114D03*
X699476D03*
X701839D03*
X704201D03*
X721504Y53543D03*
Y65157D03*
X723866Y53543D03*
X726228D03*
X728591D03*
X730953D03*
X733315D03*
X735677D03*
X738039D03*
X723866Y65157D03*
X726228D03*
X728591D03*
X730953D03*
X733315D03*
X735677D03*
X738039D03*
X740402Y53543D03*
X742764D03*
X745126D03*
X747488D03*
X749850D03*
X752213D03*
X740402Y65157D03*
X742764D03*
X745126D03*
X747488D03*
X749850D03*
X752213D03*
X1540342Y32756D03*
X1542704D03*
X1540342Y44370D03*
X1542704D03*
X1545066Y32756D03*
X1547429D03*
X1549791D03*
X1552153D03*
X1554515D03*
X1556877D03*
X1545066Y44370D03*
X1547429D03*
X1549791D03*
X1552153D03*
X1554515D03*
X1556877D03*
X1559240Y32756D03*
X1561602D03*
X1563964D03*
X1566326D03*
X1568688D03*
X1571051D03*
X1559240Y44370D03*
X1561602D03*
X1563964D03*
X1566326D03*
X1568688D03*
X1571051D03*
X1573413Y32756D03*
X1575775D03*
X1578137D03*
X1580499D03*
X1582862D03*
X1585224D03*
X1587586D03*
X1573413Y44370D03*
X1575775D03*
X1578137D03*
X1580499D03*
X1582862D03*
X1585224D03*
X1587586D03*
X1589948Y32756D03*
X1592311D03*
X1594673D03*
X1597035D03*
X1599397D03*
X1601759D03*
X1589948Y44370D03*
X1592311D03*
X1594673D03*
X1597035D03*
X1599397D03*
X1601759D03*
X1604122Y32756D03*
Y44370D03*
X1623452Y32756D03*
X1625814D03*
X1628177D03*
X1630539D03*
X1623452Y44370D03*
X1625814D03*
X1628177D03*
X1630539D03*
X1632901Y32756D03*
X1635263D03*
X1637625D03*
X1639988D03*
X1642350D03*
X1644712D03*
X1647074D03*
X1632901Y44370D03*
X1635263D03*
X1637625D03*
X1639988D03*
X1642350D03*
X1644712D03*
X1647074D03*
X1649437Y32756D03*
X1651799D03*
X1654161D03*
X1649437Y44370D03*
X1651799D03*
X1654161D03*
X1669948Y32756D03*
X1672311D03*
X1674673D03*
X1677035D03*
X1669948Y44370D03*
X1672311D03*
X1674673D03*
X1677035D03*
X1679397Y32756D03*
X1681759D03*
X1684122D03*
X1686484D03*
X1688846D03*
X1691208D03*
X1679397Y44370D03*
X1681759D03*
X1684122D03*
X1686484D03*
X1688846D03*
X1691208D03*
X1693570Y32756D03*
X1695933D03*
X1698295D03*
X1700657D03*
X1703019D03*
X1705381D03*
X1693570Y44370D03*
X1695933D03*
X1698295D03*
X1700657D03*
X1703019D03*
X1705381D03*
X1707744Y32756D03*
X1710106D03*
X1712468D03*
X1714830D03*
X1717192D03*
X1719555D03*
X1721917D03*
X1707744Y44370D03*
X1710106D03*
X1712468D03*
X1714830D03*
X1717192D03*
X1719555D03*
X1721917D03*
X1724279Y32756D03*
X1726641D03*
X1729003D03*
X1731366D03*
X1733728D03*
X1724279Y44370D03*
X1726641D03*
X1729003D03*
X1731366D03*
X1733728D03*
X1751031Y32756D03*
Y44370D03*
X1753393Y32756D03*
X1755755D03*
X1758118D03*
X1760480D03*
X1762842D03*
X1765204D03*
X1753393Y44370D03*
X1755755D03*
X1758118D03*
X1760480D03*
X1762842D03*
X1765204D03*
X1767566Y32756D03*
X1769929D03*
X1772291D03*
X1774653D03*
X1777015D03*
X1779377D03*
X1781740D03*
X1767566Y44370D03*
X1769929D03*
X1772291D03*
X1774653D03*
X1777015D03*
X1779377D03*
X1781740D03*
G54D135*
X269887Y600916D03*
Y598554D03*
X280123D03*
G54D216*
X663382Y516260D03*
Y523740D03*
X673618Y520000D03*
G54D162*
X404743Y483094D03*
X402184D03*
X399625D03*
Y490476D03*
X402184D03*
X404743D03*
X418543Y483017D03*
X415984D03*
X413425D03*
Y490399D03*
X415984D03*
X418543D03*
X432343Y482940D03*
X429784D03*
X427225D03*
Y490322D03*
X429784D03*
X432343D03*
G54D207*
X584276Y486000D03*
X593724D03*
X798724Y366000D03*
X789276D03*
X811224Y399500D03*
X801776D03*
X810224Y409500D03*
X800776D03*
G54D225*
X723082Y651187D03*
Y646147D03*
X717176Y651187D03*
Y646147D03*
X1148190Y1558549D03*
Y1553509D03*
X1142284Y1558549D03*
Y1553509D03*
X1470006Y1676881D03*
Y1681921D03*
X1475912Y1676881D03*
Y1681921D03*
G54D243*
X776768Y1581379D03*
Y1579410D03*
Y1577442D03*
Y1587284D03*
Y1585316D03*
Y1583347D03*
X794386Y1577442D03*
Y1581379D03*
Y1579410D03*
Y1587284D03*
Y1583347D03*
Y1585316D03*
X818768Y1581379D03*
Y1579410D03*
Y1577442D03*
Y1587284D03*
Y1585316D03*
Y1583347D03*
X836386Y1577442D03*
Y1581379D03*
Y1579410D03*
Y1587284D03*
Y1583347D03*
Y1585316D03*
X860768Y1581379D03*
Y1579410D03*
Y1577442D03*
Y1587284D03*
Y1585316D03*
Y1583347D03*
X878386Y1577442D03*
Y1581379D03*
Y1579410D03*
Y1587284D03*
Y1583347D03*
Y1585316D03*
X902768Y1581379D03*
Y1579410D03*
Y1577442D03*
Y1587284D03*
Y1585316D03*
Y1583347D03*
X920386Y1577442D03*
Y1581379D03*
Y1579410D03*
Y1587284D03*
Y1583347D03*
Y1585316D03*
G54D261*
X845291Y1526035D03*
X853479D03*
X945177Y1464749D03*
X953365D03*
G54D315*
X1787943Y192193D03*
X1806547D03*
G54D51*
X55756Y1531020D03*
Y1532792D03*
Y1534564D03*
Y1536335D03*
Y1538107D03*
Y1539879D03*
X96966Y159744D03*
Y157775D03*
Y155807D03*
Y153838D03*
X85942D03*
Y155807D03*
Y157775D03*
Y159744D03*
X91499Y1531020D03*
Y1532792D03*
Y1534564D03*
Y1536335D03*
Y1538107D03*
Y1539879D03*
X103152Y1370457D03*
Y1368686D03*
Y1366914D03*
Y1365142D03*
Y1372229D03*
Y1374001D03*
X135752Y1370457D03*
Y1368686D03*
Y1366914D03*
Y1365142D03*
Y1372229D03*
Y1374001D03*
X168452Y1370457D03*
Y1368686D03*
Y1366914D03*
Y1365142D03*
Y1372229D03*
Y1374001D03*
X201352Y1370457D03*
Y1368686D03*
Y1366914D03*
Y1365142D03*
Y1372229D03*
Y1374001D03*
X234152Y1370457D03*
Y1368686D03*
Y1366914D03*
Y1365142D03*
Y1372229D03*
Y1374001D03*
X267904Y656116D03*
Y664975D03*
Y663203D03*
Y661431D03*
Y659660D03*
Y657888D03*
X267752Y1327855D03*
Y1324311D03*
Y1322540D03*
Y1320768D03*
Y1318996D03*
Y1326083D03*
X280741Y151850D03*
Y153819D03*
Y155787D03*
Y157756D03*
X291765D03*
Y155787D03*
Y153819D03*
Y151850D03*
X300634Y699216D03*
Y697444D03*
Y695672D03*
Y693901D03*
Y692129D03*
Y690357D03*
X300648Y1327827D03*
Y1324283D03*
Y1322512D03*
Y1320740D03*
Y1318968D03*
Y1326055D03*
X333404Y715822D03*
Y714051D03*
Y712279D03*
Y710507D03*
Y719366D03*
Y717594D03*
X333552Y1327770D03*
Y1324226D03*
Y1322455D03*
Y1320683D03*
Y1318911D03*
Y1325998D03*
X366464Y717326D03*
Y715554D03*
Y713783D03*
Y712011D03*
Y710239D03*
Y719098D03*
X366352Y1327970D03*
Y1324426D03*
Y1322655D03*
Y1320883D03*
Y1319111D03*
Y1326198D03*
X399504Y717394D03*
Y715622D03*
Y713851D03*
Y712079D03*
Y710307D03*
Y719166D03*
X398934Y1341986D03*
Y1340214D03*
Y1338442D03*
Y1347301D03*
Y1343757D03*
Y1345529D03*
X432504Y701366D03*
Y699594D03*
Y697822D03*
Y696051D03*
Y694279D03*
Y692507D03*
X464904Y671451D03*
Y669679D03*
Y667907D03*
Y676766D03*
Y674994D03*
Y673222D03*
X497504Y641407D03*
Y650266D03*
Y648494D03*
Y646722D03*
Y644951D03*
Y643179D03*
X530804Y612622D03*
Y610851D03*
Y609079D03*
Y607307D03*
Y616166D03*
Y614394D03*
X615741Y223893D03*
Y221924D03*
X604717D03*
Y223893D03*
X615741Y227830D03*
Y225861D03*
X604717D03*
Y227830D03*
X710708Y1386695D03*
Y1384923D03*
Y1383151D03*
Y1392010D03*
Y1388466D03*
Y1390238D03*
X743490Y1386795D03*
Y1385023D03*
Y1383251D03*
Y1392110D03*
Y1388566D03*
Y1390338D03*
X818002Y133945D03*
Y135914D03*
Y137882D03*
Y139851D03*
X829026Y135914D03*
Y133945D03*
Y139851D03*
Y137882D03*
X841967Y211438D03*
Y213407D03*
Y215375D03*
Y217344D03*
X852991D03*
Y215375D03*
Y213407D03*
Y211438D03*
X1074890Y1370438D03*
Y1368667D03*
Y1366895D03*
Y1365123D03*
Y1372210D03*
Y1373982D03*
X1107490Y1370438D03*
Y1368667D03*
Y1366895D03*
Y1365123D03*
Y1372210D03*
Y1373982D03*
X1140190Y1370438D03*
Y1368667D03*
Y1366895D03*
Y1365123D03*
Y1372210D03*
Y1373982D03*
X1173090Y1370438D03*
Y1368667D03*
Y1366895D03*
Y1365123D03*
Y1372210D03*
Y1373982D03*
X1205890Y1370438D03*
Y1368667D03*
Y1366895D03*
Y1365123D03*
Y1372210D03*
Y1373982D03*
X1243881Y1327836D03*
Y1324292D03*
Y1322521D03*
Y1320749D03*
Y1318977D03*
Y1326064D03*
X1274390Y403772D03*
Y405741D03*
Y407709D03*
Y409678D03*
X1285414Y403772D03*
Y409678D03*
Y407709D03*
Y405741D03*
X1276777Y1327808D03*
Y1324264D03*
Y1322493D03*
Y1320721D03*
Y1318949D03*
Y1326036D03*
X1309681Y1327751D03*
Y1324207D03*
Y1322436D03*
Y1320664D03*
Y1318892D03*
Y1325979D03*
X1342481Y1327951D03*
Y1324407D03*
Y1322636D03*
Y1320864D03*
Y1319092D03*
Y1326179D03*
X1378456Y627222D03*
Y625450D03*
Y634309D03*
Y632537D03*
Y630765D03*
Y628994D03*
X1375063Y1341967D03*
Y1340195D03*
Y1338423D03*
Y1347282D03*
Y1343738D03*
Y1345510D03*
X1411156Y667209D03*
Y665437D03*
Y663665D03*
Y661894D03*
Y660122D03*
Y658350D03*
X1443756Y699789D03*
Y698017D03*
Y696245D03*
Y694474D03*
Y692702D03*
Y690930D03*
X1476674Y715822D03*
Y714051D03*
Y712279D03*
Y710507D03*
Y719366D03*
Y717594D03*
X1509756Y715990D03*
Y714219D03*
Y712447D03*
Y710675D03*
Y719534D03*
Y717762D03*
X1542556Y715822D03*
Y714051D03*
Y712279D03*
Y710507D03*
Y719366D03*
Y717594D03*
X1550705Y297463D03*
Y299432D03*
Y301400D03*
Y303369D03*
X1561729Y299432D03*
Y297463D03*
Y303369D03*
Y301400D03*
X1575686Y697426D03*
Y695654D03*
Y693882D03*
Y692111D03*
Y690339D03*
Y688567D03*
X1608456Y656570D03*
Y654798D03*
Y663657D03*
Y661885D03*
Y660113D03*
Y658342D03*
X1641456Y642885D03*
Y641113D03*
Y639342D03*
Y637570D03*
Y635798D03*
Y644657D03*
X1658441Y1387755D03*
Y1385984D03*
Y1384212D03*
Y1382440D03*
Y1391299D03*
Y1389527D03*
X1691223Y1387855D03*
Y1386084D03*
Y1384312D03*
Y1382540D03*
Y1391399D03*
Y1389627D03*
X1683561Y1683292D03*
Y1685261D03*
Y1689198D03*
Y1687229D03*
X1694585Y1683292D03*
Y1685261D03*
Y1689198D03*
Y1687229D03*
X1729480Y367431D03*
Y369400D03*
Y371368D03*
Y373337D03*
X1740504D03*
Y371368D03*
Y369400D03*
Y367431D03*
X1743039Y1564056D03*
Y1565828D03*
Y1567600D03*
Y1569371D03*
Y1571143D03*
Y1572915D03*
X1778782Y1564056D03*
Y1565828D03*
Y1567600D03*
Y1569371D03*
Y1571143D03*
Y1572915D03*
G54D108*
X178582Y1572490D03*
X184382D03*
X172782D03*
X178582D03*
X251487Y92733D03*
X257287D03*
Y97633D03*
X251487D03*
X329886Y598794D03*
X324086D03*
X424100Y1644500D03*
X436100Y1627500D03*
X429900Y1644500D03*
X441900Y1627500D03*
X684643Y96858D03*
X690443D03*
Y101758D03*
X684643D03*
X797536Y1364193D03*
X803336D03*
X1120110Y1580298D03*
X1125910D03*
X1180655Y1605490D03*
X1190107Y182851D03*
X1195907D03*
X1186455Y1605490D03*
D03*
X1192255D03*
X1295078Y157495D03*
X1300878D03*
X1307700Y518723D03*
X1313500D03*
X1614959Y525962D03*
X1620759D03*
X1726608Y94527D03*
X1732408D03*
Y99727D03*
X1726608D03*
G54D33*
X44967Y416860D03*
D03*
Y413710D03*
X50339Y416945D03*
Y413795D03*
Y416945D03*
X44967Y420010D03*
X50339Y420095D03*
X60189Y417070D03*
Y413920D03*
X65533Y414040D03*
Y410890D03*
Y417190D03*
Y414040D03*
X60189Y413920D03*
Y410770D03*
X238297Y123968D03*
Y127118D03*
X556280Y119790D03*
X551280D03*
X556280Y126090D03*
Y122940D03*
X551280Y126090D03*
Y122940D03*
X556280D03*
X551280D03*
X568360Y119635D03*
X573360D03*
X568360Y122785D03*
X573360D03*
X568360Y125935D03*
Y122785D03*
X573360Y125935D03*
Y122785D03*
X714129Y664242D03*
Y667392D03*
Y661092D03*
Y664242D03*
X726201Y664244D03*
Y667394D03*
Y661094D03*
Y664244D03*
X1016770Y233573D03*
Y230423D03*
X1256785Y754715D03*
Y757865D03*
D03*
Y761015D03*
X1263706Y754715D03*
Y757865D03*
D03*
Y761015D03*
X1713000Y654925D03*
Y651775D03*
Y658075D03*
Y654925D03*
Y670425D03*
Y673575D03*
Y676725D03*
Y673575D03*
G54D324*
X1900275Y-29973D03*
Y562227D03*
X1898799Y1208198D03*
Y1800398D03*
X1910275Y-29973D03*
Y562227D03*
X1908799Y1208198D03*
Y1800398D03*
X1921395Y-29963D03*
X1931395D03*
Y562237D03*
X1921395D03*
X1931395Y582237D03*
X1921395D03*
Y1174437D03*
X1931395D03*
X1929766Y1208160D03*
X1919766D03*
Y1800360D03*
X1929766D03*
X1942395Y-29783D03*
Y562417D03*
Y582417D03*
Y1174617D03*
X1940886Y1208170D03*
Y1800370D03*
X1952395Y-29783D03*
Y562417D03*
Y582417D03*
Y1174617D03*
X1950886Y1208170D03*
X1961856D03*
X1950886Y1800370D03*
X1961856D03*
X1963362Y-29821D03*
X1973362D03*
Y562379D03*
X1963362D03*
X1973362Y582379D03*
X1963362D03*
Y1174579D03*
X1973362D03*
X1971856Y1208170D03*
Y1800370D03*
X1984482Y-29811D03*
Y562389D03*
Y582389D03*
Y1174589D03*
X1982856Y1208350D03*
Y1800550D03*
X1994482Y-29811D03*
X2005452D03*
X1994482Y562389D03*
X2005452D03*
Y582389D03*
X1994482D03*
Y1174589D03*
X2005452D03*
X1992856Y1208350D03*
X2003823Y1208312D03*
X1992856Y1800550D03*
X2003823Y1800512D03*
X2015452Y-29811D03*
Y562389D03*
Y582389D03*
Y1174589D03*
X2013823Y1208312D03*
Y1800512D03*
X2036452Y-29631D03*
X2026452D03*
Y562569D03*
X2036452D03*
X2026452Y582569D03*
X2036452D03*
Y1174769D03*
X2026452D03*
X2047419Y-29669D03*
Y562531D03*
Y582531D03*
Y1174731D03*
X2057419Y-29669D03*
Y562531D03*
Y582531D03*
Y1174731D03*
X2068539Y582541D03*
X2078539D03*
Y1174741D03*
X2068539D03*
G54D117*
X230905Y1649173D03*
Y1653897D03*
Y1663346D03*
Y1668070D03*
Y1677519D03*
Y1682244D03*
Y1691692D03*
Y1696417D03*
Y1705866D03*
Y1710590D03*
Y1720039D03*
Y1724763D03*
X238779Y1643661D03*
X246653Y1649173D03*
Y1653897D03*
X238779Y1653110D03*
Y1657834D03*
X246653Y1663346D03*
Y1668070D03*
X238779Y1667283D03*
Y1672007D03*
X246653Y1677519D03*
Y1682244D03*
X238779Y1681456D03*
Y1686180D03*
X246653Y1691692D03*
Y1696417D03*
X238779Y1695629D03*
Y1700354D03*
X246653Y1705866D03*
Y1710590D03*
X238779Y1709803D03*
Y1714527D03*
X246653Y1720039D03*
Y1724763D03*
X238779Y1723976D03*
Y1728700D03*
X246653Y1734212D03*
X254527Y1643661D03*
Y1653110D03*
Y1657834D03*
Y1667283D03*
Y1672007D03*
Y1681456D03*
Y1686180D03*
Y1695629D03*
Y1700354D03*
Y1709803D03*
Y1714527D03*
Y1723976D03*
Y1728700D03*
X270275Y1643661D03*
X262401Y1649173D03*
X270275Y1653110D03*
X262401Y1653897D03*
X270275Y1657834D03*
X262401Y1663346D03*
X270275Y1667283D03*
X262401Y1668070D03*
X270275Y1672007D03*
X262401Y1677519D03*
X270275Y1681456D03*
X262401Y1682244D03*
X270275Y1686180D03*
X262401Y1691692D03*
X270275Y1695629D03*
X262401Y1696417D03*
X270275Y1700354D03*
X262401Y1705866D03*
X270275Y1709803D03*
X262401Y1710590D03*
X270275Y1714527D03*
X262401Y1720039D03*
X270275Y1723976D03*
X262401Y1724763D03*
X270275Y1728700D03*
X262401Y1734212D03*
X286023Y1643661D03*
X278149Y1649173D03*
X286023Y1653110D03*
X278149Y1653897D03*
X286023Y1657834D03*
X278149Y1663346D03*
X286023Y1667283D03*
X278149Y1668070D03*
X286023Y1672007D03*
X278149Y1677519D03*
X286023Y1681456D03*
X278149Y1682244D03*
X286023Y1686180D03*
X278149Y1691692D03*
X286023Y1695629D03*
X278149Y1696417D03*
X286023Y1700354D03*
X278149Y1705866D03*
X286023Y1709803D03*
X278149Y1710590D03*
X286023Y1714527D03*
X278149Y1720039D03*
X286023Y1723976D03*
X278149Y1724763D03*
X286023Y1728700D03*
X278149Y1734212D03*
X305709Y1672007D03*
X297835Y1677519D03*
X305709Y1681456D03*
X297835Y1682244D03*
X305709Y1686180D03*
X297835Y1691692D03*
X305709Y1695629D03*
X297835Y1696417D03*
X305709Y1700354D03*
X297835Y1705866D03*
X305709Y1709803D03*
X297835Y1710590D03*
X305709Y1714527D03*
X297835Y1720039D03*
X305709Y1723976D03*
X297835Y1724763D03*
X305709Y1728700D03*
X321457Y1672007D03*
X313583Y1677519D03*
X321457Y1681456D03*
X313583Y1682244D03*
X321457Y1686180D03*
X313583Y1691692D03*
X321457Y1695629D03*
X313583Y1696417D03*
X321457Y1700354D03*
X313583Y1705866D03*
X321457Y1709803D03*
X313583Y1710590D03*
X321457Y1714527D03*
X313583Y1720039D03*
X321457Y1723976D03*
X313583Y1724763D03*
X321457Y1728700D03*
X313583Y1734212D03*
X329331Y1677519D03*
Y1682244D03*
Y1691692D03*
Y1696417D03*
Y1705866D03*
Y1710590D03*
Y1720039D03*
Y1724763D03*
Y1734212D03*
X337205Y1672007D03*
X345079Y1677519D03*
Y1682244D03*
X337205Y1681456D03*
Y1686180D03*
X345079Y1691692D03*
Y1696417D03*
X337205Y1695629D03*
Y1700354D03*
X345079Y1705866D03*
Y1710590D03*
X337205Y1709803D03*
Y1714527D03*
X345079Y1720039D03*
Y1724763D03*
X337205Y1723976D03*
Y1728700D03*
X345079Y1734212D03*
X352953Y1672007D03*
Y1681456D03*
Y1686180D03*
Y1695629D03*
Y1700354D03*
Y1709803D03*
Y1714527D03*
Y1723976D03*
Y1728700D03*
X495078Y1677519D03*
Y1682244D03*
Y1691692D03*
Y1696417D03*
Y1705866D03*
Y1710590D03*
Y1720039D03*
Y1724763D03*
X502952Y1672007D03*
X510826Y1677519D03*
Y1682244D03*
X502952Y1681456D03*
Y1686180D03*
X510826Y1691692D03*
Y1696417D03*
X502952Y1695629D03*
Y1700354D03*
X510826Y1705866D03*
Y1710590D03*
X502952Y1709803D03*
Y1714527D03*
X510826Y1720039D03*
Y1724763D03*
X502952Y1723976D03*
Y1728700D03*
X510826Y1734212D03*
X518700Y1672007D03*
Y1681456D03*
Y1686180D03*
X526574Y1677519D03*
Y1682244D03*
X518700Y1695629D03*
Y1700354D03*
X526574Y1691692D03*
Y1696417D03*
X518700Y1709803D03*
Y1714527D03*
X526574Y1705866D03*
Y1710590D03*
X518700Y1723976D03*
Y1728700D03*
X526574Y1720039D03*
Y1724763D03*
Y1734212D03*
X534448Y1672007D03*
X542322Y1677519D03*
Y1682244D03*
X534448Y1681456D03*
Y1686180D03*
X542322Y1691692D03*
Y1696417D03*
X534448Y1695629D03*
Y1700354D03*
X542322Y1705866D03*
Y1710590D03*
X534448Y1709803D03*
Y1714527D03*
X542322Y1720039D03*
Y1724763D03*
X534448Y1723976D03*
Y1728700D03*
X542322Y1734212D03*
X550196Y1672007D03*
Y1681456D03*
Y1686180D03*
Y1695629D03*
Y1700354D03*
Y1709803D03*
Y1714527D03*
Y1723976D03*
Y1728700D03*
X569882Y1672007D03*
X562008Y1677519D03*
X569882Y1681456D03*
X562008Y1682244D03*
X569882Y1686180D03*
X562008Y1691692D03*
X569882Y1695629D03*
X562008Y1696417D03*
X569882Y1700354D03*
X562008Y1705866D03*
X569882Y1709803D03*
X562008Y1710590D03*
X569882Y1714527D03*
X562008Y1720039D03*
X569882Y1723976D03*
X562008Y1724763D03*
X569882Y1728700D03*
X585630Y1672007D03*
X577756Y1677519D03*
X585630Y1681456D03*
X577756Y1682244D03*
X585630Y1686180D03*
X577756Y1691692D03*
X585630Y1695629D03*
X577756Y1696417D03*
X585630Y1700354D03*
X577756Y1705866D03*
X585630Y1709803D03*
X577756Y1710590D03*
X585630Y1714527D03*
X577756Y1720039D03*
X585630Y1723976D03*
X577756Y1724763D03*
X585630Y1728700D03*
X577756Y1734212D03*
X601378Y1672007D03*
X593504Y1677519D03*
X601378Y1681456D03*
X593504Y1682244D03*
X601378Y1686180D03*
X593504Y1691692D03*
X601378Y1695629D03*
X593504Y1696417D03*
X601378Y1700354D03*
X593504Y1705866D03*
X601378Y1709803D03*
X593504Y1710590D03*
X601378Y1714527D03*
X593504Y1720039D03*
X601378Y1723976D03*
X593504Y1724763D03*
X601378Y1728700D03*
X593504Y1734212D03*
X617126Y1672007D03*
X609252Y1677519D03*
X617126Y1681456D03*
X609252Y1682244D03*
X617126Y1686180D03*
X609252Y1691692D03*
X617126Y1695629D03*
X609252Y1696417D03*
X617126Y1700354D03*
X609252Y1705866D03*
X617126Y1709803D03*
X609252Y1710590D03*
X617126Y1714527D03*
X609252Y1720039D03*
X617126Y1723976D03*
X609252Y1724763D03*
X617126Y1728700D03*
X609252Y1734212D03*
X1238778Y1677519D03*
Y1682244D03*
Y1691692D03*
Y1696417D03*
Y1705866D03*
Y1710590D03*
Y1720039D03*
Y1724763D03*
X1246652Y1672007D03*
X1254526Y1677519D03*
Y1682244D03*
X1246652Y1681456D03*
Y1686180D03*
X1254526Y1691692D03*
Y1696417D03*
X1246652Y1695629D03*
Y1700354D03*
X1254526Y1705866D03*
Y1710590D03*
X1246652Y1709803D03*
Y1714527D03*
X1254526Y1720039D03*
Y1724763D03*
X1246652Y1723976D03*
Y1728700D03*
X1254526Y1734212D03*
X1262400Y1672007D03*
Y1681456D03*
Y1686180D03*
X1270274Y1677519D03*
Y1682244D03*
X1262400Y1695629D03*
Y1700354D03*
X1270274Y1691692D03*
Y1696417D03*
X1262400Y1709803D03*
Y1714527D03*
X1270274Y1705866D03*
Y1710590D03*
X1262400Y1723976D03*
Y1728700D03*
X1270274Y1720039D03*
Y1724763D03*
Y1734212D03*
X1278148Y1672007D03*
X1286022Y1677519D03*
Y1682244D03*
X1278148Y1681456D03*
Y1686180D03*
X1286022Y1691692D03*
Y1696417D03*
X1278148Y1695629D03*
Y1700354D03*
X1286022Y1705866D03*
Y1710590D03*
X1278148Y1709803D03*
Y1714527D03*
X1286022Y1720039D03*
Y1724763D03*
X1278148Y1723976D03*
Y1728700D03*
X1286022Y1734212D03*
X1293896Y1672007D03*
Y1681456D03*
Y1686180D03*
Y1695629D03*
Y1700354D03*
Y1709803D03*
Y1714527D03*
Y1723976D03*
Y1728700D03*
X1313582Y1672007D03*
X1305708Y1677519D03*
X1313582Y1681456D03*
X1305708Y1682244D03*
X1313582Y1686180D03*
X1305708Y1691692D03*
X1313582Y1695629D03*
X1305708Y1696417D03*
X1313582Y1700354D03*
X1305708Y1705866D03*
X1313582Y1709803D03*
X1305708Y1710590D03*
X1313582Y1714527D03*
X1305708Y1720039D03*
X1313582Y1723976D03*
X1305708Y1724763D03*
X1313582Y1728700D03*
X1329330Y1672007D03*
X1321456Y1677519D03*
X1329330Y1681456D03*
X1321456Y1682244D03*
X1329330Y1686180D03*
X1321456Y1691692D03*
X1329330Y1695629D03*
X1321456Y1696417D03*
X1329330Y1700354D03*
X1321456Y1705866D03*
X1329330Y1709803D03*
X1321456Y1710590D03*
X1329330Y1714527D03*
X1321456Y1720039D03*
X1329330Y1723976D03*
X1321456Y1724763D03*
X1329330Y1728700D03*
X1321456Y1734212D03*
X1345078Y1672007D03*
X1337204Y1677519D03*
X1345078Y1681456D03*
X1337204Y1682244D03*
X1345078Y1686180D03*
X1337204Y1691692D03*
X1345078Y1695629D03*
X1337204Y1696417D03*
X1345078Y1700354D03*
X1337204Y1705866D03*
X1345078Y1709803D03*
X1337204Y1710590D03*
X1345078Y1714527D03*
X1337204Y1720039D03*
X1345078Y1723976D03*
X1337204Y1724763D03*
X1345078Y1728700D03*
X1337204Y1734212D03*
X1360826Y1672007D03*
X1352952Y1677519D03*
X1360826Y1681456D03*
X1352952Y1682244D03*
X1360826Y1686180D03*
X1352952Y1691692D03*
X1360826Y1695629D03*
X1352952Y1696417D03*
X1360826Y1700354D03*
X1352952Y1705866D03*
X1360826Y1709803D03*
X1352952Y1710590D03*
X1360826Y1714527D03*
X1352952Y1720039D03*
X1360826Y1723976D03*
X1352952Y1724763D03*
X1360826Y1728700D03*
X1352952Y1734212D03*
X1510826Y1672007D03*
X1502952Y1677519D03*
X1510826Y1681456D03*
X1502952Y1682244D03*
X1510826Y1686180D03*
X1502952Y1691692D03*
X1510826Y1695629D03*
X1502952Y1696417D03*
X1510826Y1700354D03*
X1502952Y1705866D03*
X1510826Y1709803D03*
X1502952Y1710590D03*
X1510826Y1714527D03*
X1502952Y1720039D03*
X1510826Y1723976D03*
X1502952Y1724763D03*
X1510826Y1728700D03*
X1526574Y1672007D03*
X1518700Y1677519D03*
X1526574Y1681456D03*
X1518700Y1682244D03*
X1526574Y1686180D03*
X1518700Y1691692D03*
X1526574Y1695629D03*
X1518700Y1696417D03*
X1526574Y1700354D03*
X1518700Y1705866D03*
X1526574Y1709803D03*
X1518700Y1710590D03*
X1526574Y1714527D03*
X1518700Y1720039D03*
X1526574Y1723976D03*
X1518700Y1724763D03*
X1526574Y1728700D03*
X1518700Y1734212D03*
X1542322Y1672007D03*
X1534448Y1677519D03*
X1542322Y1681456D03*
X1534448Y1682244D03*
X1542322Y1686180D03*
X1534448Y1691692D03*
X1542322Y1695629D03*
X1534448Y1696417D03*
X1542322Y1700354D03*
X1534448Y1705866D03*
X1542322Y1709803D03*
X1534448Y1710590D03*
X1542322Y1714527D03*
X1534448Y1720039D03*
X1542322Y1723976D03*
X1534448Y1724763D03*
X1542322Y1728700D03*
X1534448Y1734212D03*
X1558070Y1672007D03*
X1550196Y1677519D03*
X1558070Y1681456D03*
X1550196Y1682244D03*
X1558070Y1686180D03*
X1550196Y1691692D03*
X1558070Y1695629D03*
X1550196Y1696417D03*
X1558070Y1700354D03*
X1550196Y1705866D03*
X1558070Y1709803D03*
X1550196Y1710590D03*
X1558070Y1714527D03*
X1550196Y1720039D03*
X1558070Y1723976D03*
X1550196Y1724763D03*
X1558070Y1728700D03*
X1550196Y1734212D03*
X1569882Y1677519D03*
Y1682244D03*
Y1691692D03*
Y1696417D03*
Y1705866D03*
Y1710590D03*
Y1720039D03*
Y1724763D03*
X1577756Y1672007D03*
X1585630Y1677519D03*
Y1682244D03*
X1577756Y1681456D03*
Y1686180D03*
X1585630Y1691692D03*
Y1696417D03*
X1577756Y1695629D03*
Y1700354D03*
X1585630Y1705866D03*
Y1710590D03*
X1577756Y1709803D03*
Y1714527D03*
X1585630Y1720039D03*
Y1724763D03*
X1577756Y1723976D03*
Y1728700D03*
X1585630Y1734212D03*
X1593504Y1672007D03*
Y1681456D03*
Y1686180D03*
X1601378Y1677519D03*
Y1682244D03*
X1593504Y1695629D03*
Y1700354D03*
X1601378Y1691692D03*
Y1696417D03*
X1593504Y1709803D03*
Y1714527D03*
X1601378Y1705866D03*
Y1710590D03*
X1593504Y1723976D03*
Y1728700D03*
X1601378Y1720039D03*
Y1724763D03*
Y1734212D03*
X1609252Y1672007D03*
X1617126Y1677519D03*
Y1682244D03*
X1609252Y1681456D03*
Y1686180D03*
X1617126Y1691692D03*
Y1696417D03*
X1609252Y1695629D03*
Y1700354D03*
X1617126Y1705866D03*
Y1710590D03*
X1609252Y1709803D03*
Y1714527D03*
X1617126Y1720039D03*
Y1724763D03*
X1609252Y1723976D03*
Y1728700D03*
X1617126Y1734212D03*
X1625000Y1672007D03*
Y1681456D03*
Y1686180D03*
Y1695629D03*
Y1700354D03*
Y1709803D03*
Y1714527D03*
Y1723976D03*
Y1728700D03*
G54D60*
X79729Y289822D03*
Y310256D03*
X89729Y289822D03*
Y310256D03*
X757184Y1702772D03*
Y1712772D03*
X1072863Y1409176D03*
Y1419176D03*
X1080970Y1640958D03*
Y1650958D03*
X1225530Y67471D03*
X1299439Y102812D03*
Y112812D03*
X1454797Y80345D03*
X1530377Y581353D03*
X1540377D03*
G54D153*
X373673Y-28871D03*
Y-18871D03*
D03*
Y-8871D03*
X398673Y-28871D03*
Y-18871D03*
D03*
Y-8871D03*
X718093Y-28871D03*
Y-18871D03*
D03*
Y-8871D03*
X743093Y-28871D03*
Y-18871D03*
D03*
Y-8871D03*
X825152Y-35011D03*
Y-25011D03*
Y-15011D03*
Y-25011D03*
Y-15011D03*
Y-5011D03*
D03*
Y4989D03*
Y14989D03*
D03*
Y4989D03*
Y24989D03*
X850152Y-35011D03*
Y-25011D03*
Y-15011D03*
Y-25011D03*
Y-15011D03*
Y-5011D03*
D03*
Y4989D03*
Y14989D03*
D03*
Y4989D03*
Y24989D03*
X1169572Y-35011D03*
Y-15011D03*
Y-25011D03*
D03*
Y-15011D03*
Y-5011D03*
D03*
Y4989D03*
Y14989D03*
Y4989D03*
Y14989D03*
Y24989D03*
X1194572Y-35011D03*
Y-15011D03*
Y-25011D03*
D03*
Y-15011D03*
Y-5011D03*
D03*
Y4989D03*
Y14989D03*
Y4989D03*
Y14989D03*
Y24989D03*
X1228672Y-35011D03*
Y-25011D03*
Y-15011D03*
Y-25011D03*
Y-15011D03*
Y-5011D03*
D03*
Y4989D03*
Y14989D03*
D03*
Y4989D03*
Y24989D03*
X1253672Y-35011D03*
Y-25011D03*
Y-15011D03*
Y-25011D03*
Y-15011D03*
Y-5011D03*
D03*
Y4989D03*
Y14989D03*
D03*
Y4989D03*
Y24989D03*
X1428431Y-35011D03*
Y-15011D03*
Y-25011D03*
D03*
Y-15011D03*
Y-5011D03*
D03*
Y4989D03*
Y14989D03*
Y4989D03*
Y14989D03*
Y24989D03*
X1453431Y-35011D03*
Y-15011D03*
Y-25011D03*
D03*
Y-15011D03*
Y-5011D03*
D03*
Y4989D03*
Y14989D03*
Y4989D03*
Y14989D03*
Y24989D03*
X1521966Y-29212D03*
D03*
Y-39212D03*
Y-19212D03*
X1546966Y-29212D03*
D03*
Y-39212D03*
Y-19212D03*
X1721725Y-29212D03*
Y-39212D03*
Y-29212D03*
Y-19212D03*
X1746725Y-29212D03*
Y-39212D03*
Y-29212D03*
Y-19212D03*
G54D252*
X804455Y1345269D03*
G54D306*
X1658169Y414202D03*
G54D180*
X473445Y288569D03*
X560445Y297569D03*
G54D325*
G01X-476840Y-884638D02*
Y2768362D01*
X5911000D01*
Y-884638D01*
X-476840D01*
G01X8000Y-625138D02*
Y-630138D01*
G01X6543Y-625138D02*
X9457D01*
G01X14367Y-630138D02*
X11833D01*
Y-625138D01*
X14367D01*
G01X13353Y-627555D02*
X11833D01*
G01X16933Y-625138D02*
Y-630138D01*
X19467D01*
G01X23300Y-630305D02*
X23173Y-630221D01*
Y-630055D01*
X23300Y-629971D01*
X23427Y-630055D01*
Y-630221D01*
X23300Y-630305D01*
G01Y-628055D02*
X23173Y-627971D01*
Y-627805D01*
X23300Y-627721D01*
X23427Y-627805D01*
Y-627971D01*
X23300Y-628055D01*
G01X28083Y-631805D02*
X27450Y-630971D01*
X27133Y-630138D01*
Y-626805D01*
X27450Y-625971D01*
X28083Y-625138D01*
G01X33500D02*
X32993Y-625305D01*
X32613Y-625721D01*
X32360Y-626221D01*
X32170Y-626888D01*
X32107Y-627638D01*
X32170Y-628388D01*
X32360Y-629055D01*
X32613Y-629555D01*
X32993Y-629971D01*
X33500Y-630138D01*
X34007Y-629971D01*
X34387Y-629555D01*
X34640Y-629055D01*
X34830Y-628388D01*
X34893Y-627638D01*
X34830Y-626888D01*
X34640Y-626221D01*
X34387Y-625721D01*
X34007Y-625305D01*
X33500Y-625138D01*
G01X37207Y-629138D02*
X37587Y-629721D01*
X38093Y-630055D01*
X38663Y-630138D01*
X39170Y-630055D01*
X39677Y-629638D01*
X39993Y-629138D01*
X40057Y-628638D01*
X39930Y-628055D01*
X39487Y-627638D01*
X39043Y-627471D01*
X38473D01*
G01X39043D02*
X39423Y-627221D01*
X39740Y-626805D01*
X39867Y-626305D01*
X39740Y-625805D01*
X39423Y-625388D01*
X38853Y-625138D01*
X38283Y-625221D01*
X37713Y-625555D01*
G01X44017Y-631805D02*
X44650Y-630971D01*
X44967Y-630138D01*
Y-626805D01*
X44650Y-625971D01*
X44017Y-625138D01*
G01X47407Y-629138D02*
X47787Y-629721D01*
X48293Y-630055D01*
X48863Y-630138D01*
X49370Y-630055D01*
X49877Y-629638D01*
X50193Y-629138D01*
X50257Y-628638D01*
X50130Y-628055D01*
X49687Y-627638D01*
X49243Y-627471D01*
X48673D01*
G01X49243D02*
X49623Y-627221D01*
X49940Y-626805D01*
X50067Y-626305D01*
X49940Y-625805D01*
X49623Y-625388D01*
X49053Y-625138D01*
X48483Y-625221D01*
X47913Y-625555D01*
G01X52697Y-625971D02*
X53077Y-625471D01*
X53520Y-625221D01*
X54027Y-625138D01*
X54660Y-625305D01*
X55103Y-625721D01*
X55230Y-626221D01*
X55167Y-626721D01*
X54913Y-627138D01*
X53647Y-627971D01*
X53077Y-628555D01*
X52697Y-629388D01*
X52570Y-630138D01*
X55230D01*
G01X58873D02*
X59000Y-629055D01*
X59190Y-628138D01*
X59443Y-627305D01*
X59760Y-626388D01*
X60267Y-625138D01*
X57733D01*
G01X63277Y-628471D02*
X64923D01*
G01X67997Y-625971D02*
X68377Y-625471D01*
X68820Y-625221D01*
X69327Y-625138D01*
X69960Y-625305D01*
X70403Y-625721D01*
X70530Y-626221D01*
X70467Y-626721D01*
X70213Y-627138D01*
X68947Y-627971D01*
X68377Y-628555D01*
X67997Y-629388D01*
X67870Y-630138D01*
X70530D01*
G01X72907Y-629138D02*
X73287Y-629721D01*
X73793Y-630055D01*
X74363Y-630138D01*
X74870Y-630055D01*
X75377Y-629638D01*
X75693Y-629138D01*
X75757Y-628638D01*
X75630Y-628055D01*
X75187Y-627638D01*
X74743Y-627471D01*
X74173D01*
G01X74743D02*
X75123Y-627221D01*
X75440Y-626805D01*
X75567Y-626305D01*
X75440Y-625805D01*
X75123Y-625388D01*
X74553Y-625138D01*
X73983Y-625221D01*
X73413Y-625555D01*
G01X80160Y-630138D02*
Y-625138D01*
X77817Y-628721D01*
X80983D01*
G01X83107Y-629388D02*
X83487Y-629805D01*
X83930Y-630055D01*
X84500Y-630138D01*
X85070Y-629971D01*
X85513Y-629638D01*
X85830Y-629055D01*
X85893Y-628388D01*
X85767Y-627721D01*
X85450Y-627305D01*
X85007Y-626971D01*
X84563Y-626888D01*
X84120Y-626971D01*
X83550Y-627305D01*
X83740Y-625138D01*
X85450D01*
G01X93497Y-630138D02*
Y-625138D01*
X95903D01*
G01X95017Y-627555D02*
X93497D01*
G01X98217Y-630138D02*
X99800Y-625138D01*
X101383Y-630138D01*
G01X100813Y-628388D02*
X98787D01*
G01X103570Y-630138D02*
X106230Y-625138D01*
G01X103570D02*
X106230Y-630138D01*
G01X110000Y-630305D02*
X109873Y-630221D01*
Y-630055D01*
X110000Y-629971D01*
X110127Y-630055D01*
Y-630221D01*
X110000Y-630305D01*
G01Y-628055D02*
X109873Y-627971D01*
Y-627805D01*
X110000Y-627721D01*
X110127Y-627805D01*
Y-627971D01*
X110000Y-628055D01*
G01X114783Y-631805D02*
X114150Y-630971D01*
X113833Y-630138D01*
Y-626805D01*
X114150Y-625971D01*
X114783Y-625138D01*
G01X120200D02*
X119693Y-625305D01*
X119313Y-625721D01*
X119060Y-626221D01*
X118870Y-626888D01*
X118807Y-627638D01*
X118870Y-628388D01*
X119060Y-629055D01*
X119313Y-629555D01*
X119693Y-629971D01*
X120200Y-630138D01*
X120707Y-629971D01*
X121087Y-629555D01*
X121340Y-629055D01*
X121530Y-628388D01*
X121593Y-627638D01*
X121530Y-626888D01*
X121340Y-626221D01*
X121087Y-625721D01*
X120707Y-625305D01*
X120200Y-625138D01*
G01X123907Y-629138D02*
X124287Y-629721D01*
X124793Y-630055D01*
X125363Y-630138D01*
X125870Y-630055D01*
X126377Y-629638D01*
X126693Y-629138D01*
X126757Y-628638D01*
X126630Y-628055D01*
X126187Y-627638D01*
X125743Y-627471D01*
X125173D01*
G01X125743D02*
X126123Y-627221D01*
X126440Y-626805D01*
X126567Y-626305D01*
X126440Y-625805D01*
X126123Y-625388D01*
X125553Y-625138D01*
X124983Y-625221D01*
X124413Y-625555D01*
G01X130717Y-631805D02*
X131350Y-630971D01*
X131667Y-630138D01*
Y-626805D01*
X131350Y-625971D01*
X130717Y-625138D01*
G01X134107Y-629138D02*
X134487Y-629721D01*
X134993Y-630055D01*
X135563Y-630138D01*
X136070Y-630055D01*
X136577Y-629638D01*
X136893Y-629138D01*
X136957Y-628638D01*
X136830Y-628055D01*
X136387Y-627638D01*
X135943Y-627471D01*
X135373D01*
G01X135943D02*
X136323Y-627221D01*
X136640Y-626805D01*
X136767Y-626305D01*
X136640Y-625805D01*
X136323Y-625388D01*
X135753Y-625138D01*
X135183Y-625221D01*
X134613Y-625555D01*
G01X139523Y-629555D02*
X139967Y-629971D01*
X140473Y-630138D01*
X140980Y-629971D01*
X141423Y-629471D01*
X141740Y-628721D01*
X141867Y-627971D01*
Y-627055D01*
X141740Y-626305D01*
X141423Y-625638D01*
X141043Y-625305D01*
X140600Y-625138D01*
X140093Y-625305D01*
X139713Y-625638D01*
X139460Y-626138D01*
X139333Y-626805D01*
X139460Y-627388D01*
X139777Y-627971D01*
X140157Y-628305D01*
X140600Y-628388D01*
X141107Y-628221D01*
X141487Y-627805D01*
X141867Y-627055D01*
G01X145573Y-630138D02*
X145700Y-629055D01*
X145890Y-628138D01*
X146143Y-627305D01*
X146460Y-626388D01*
X146967Y-625138D01*
X144433D01*
G01X149977Y-628471D02*
X151623D01*
G01X154507Y-629138D02*
X154887Y-629721D01*
X155393Y-630055D01*
X155963Y-630138D01*
X156470Y-630055D01*
X156977Y-629638D01*
X157293Y-629138D01*
X157357Y-628638D01*
X157230Y-628055D01*
X156787Y-627638D01*
X156343Y-627471D01*
X155773D01*
G01X156343D02*
X156723Y-627221D01*
X157040Y-626805D01*
X157167Y-626305D01*
X157040Y-625805D01*
X156723Y-625388D01*
X156153Y-625138D01*
X155583Y-625221D01*
X155013Y-625555D01*
G01X159797Y-628055D02*
X160240Y-627471D01*
X160620Y-627138D01*
X161127Y-626971D01*
X161570Y-627138D01*
X161887Y-627471D01*
X162140Y-627971D01*
X162203Y-628555D01*
X162140Y-629055D01*
X161887Y-629555D01*
X161507Y-629971D01*
X161063Y-630138D01*
X160557Y-629971D01*
X160113Y-629471D01*
X159860Y-628721D01*
X159797Y-627888D01*
X159923Y-626805D01*
X160113Y-626221D01*
X160430Y-625638D01*
X160873Y-625221D01*
X161317Y-625138D01*
X161760Y-625305D01*
X162077Y-625721D01*
G01X166100Y-630138D02*
Y-625138D01*
X165340Y-626138D01*
G01Y-630138D02*
X166860D01*
G01X171960D02*
Y-625138D01*
X169617Y-628721D01*
X172783D01*
G01X-4000Y-560138D02*
Y-635138D01*
X496000D01*
Y-560138D01*
X-4000D01*
G01X191000D02*
Y-635138D01*
G01Y-610138D02*
X294000D01*
Y-585138D01*
G01X191000D02*
X294000D01*
G01X296000Y-560138D02*
Y-635138D01*
G01X294000Y-560138D02*
Y-635138D01*
G01X301507Y-620138D02*
Y-615138D01*
X302773D01*
X303280Y-615388D01*
X303660Y-615721D01*
X303977Y-616221D01*
X304230Y-616805D01*
X304293Y-617638D01*
X304230Y-618471D01*
X303977Y-619055D01*
X303660Y-619555D01*
X303280Y-619888D01*
X302773Y-620138D01*
X301507D01*
G01X306417D02*
X308000Y-615138D01*
X309583Y-620138D01*
G01X309013Y-618388D02*
X306987D01*
G01X313100Y-615138D02*
Y-620138D01*
G01X311643Y-615138D02*
X314557D01*
G01X319467Y-620138D02*
X316933D01*
Y-615138D01*
X319467D01*
G01X318453Y-617555D02*
X316933D01*
G01X323300Y-620305D02*
X323173Y-620221D01*
Y-620055D01*
X323300Y-619971D01*
X323427Y-620055D01*
Y-620221D01*
X323300Y-620305D01*
G01Y-618055D02*
X323173Y-617971D01*
Y-617805D01*
X323300Y-617721D01*
X323427Y-617805D01*
Y-617971D01*
X323300Y-618055D01*
G01X296000Y-610138D02*
X496000D01*
G01X301633Y-595138D02*
Y-590138D01*
X303153D01*
X303660Y-590388D01*
X304040Y-590971D01*
X304167Y-591638D01*
X304040Y-592305D01*
X303723Y-592805D01*
X303153Y-593055D01*
X301633D01*
G01X306860Y-595305D02*
X309140Y-590138D01*
G01X311643Y-595138D02*
Y-590138D01*
X314557Y-595138D01*
Y-590138D01*
G01X318200Y-595305D02*
X318073Y-595221D01*
Y-595055D01*
X318200Y-594971D01*
X318327Y-595055D01*
Y-595221D01*
X318200Y-595305D01*
G01Y-593055D02*
X318073Y-592971D01*
Y-592805D01*
X318200Y-592721D01*
X318327Y-592805D01*
Y-592971D01*
X318200Y-593055D01*
G01X296000Y-585138D02*
X496000D01*
G01X301633Y-570138D02*
Y-565138D01*
X303153D01*
X303660Y-565388D01*
X304040Y-565971D01*
X304167Y-566638D01*
X304040Y-567305D01*
X303723Y-567805D01*
X303153Y-568055D01*
X301633D01*
G01X306733Y-570138D02*
Y-565138D01*
X308317D01*
X308823Y-565388D01*
X309140Y-565721D01*
X309267Y-566388D01*
X309140Y-567055D01*
X308760Y-567471D01*
X308317Y-567721D01*
X306733D01*
G01X308317D02*
X309267Y-570138D01*
G01X313100D02*
X312593Y-570055D01*
X312150Y-569721D01*
X311770Y-569221D01*
X311517Y-568638D01*
X311390Y-567971D01*
Y-567305D01*
X311517Y-566638D01*
X311770Y-566055D01*
X312150Y-565555D01*
X312593Y-565221D01*
X313100Y-565138D01*
X313607Y-565221D01*
X314050Y-565555D01*
X314430Y-566055D01*
X314683Y-566638D01*
X314810Y-567305D01*
Y-567971D01*
X314683Y-568638D01*
X314430Y-569221D01*
X314050Y-569721D01*
X313607Y-570055D01*
X313100Y-570138D01*
G01X316933Y-569138D02*
X317250Y-569638D01*
X317630Y-569971D01*
X318073Y-570138D01*
X318580Y-569971D01*
X318960Y-569638D01*
X319340Y-569138D01*
X319467Y-568471D01*
Y-565138D01*
G01X324567Y-570138D02*
X322033D01*
Y-565138D01*
X324567D01*
G01X323553Y-567555D02*
X322033D01*
G01X329793Y-565555D02*
X329413Y-565305D01*
X328970Y-565138D01*
X328463D01*
X327893Y-565388D01*
X327450Y-565805D01*
X327133Y-566305D01*
X326880Y-567138D01*
X326817Y-567888D01*
X326943Y-568638D01*
X327133Y-569138D01*
X327513Y-569638D01*
X327957Y-569971D01*
X328400Y-570138D01*
X328843D01*
X329287Y-569971D01*
X329667Y-569721D01*
X329983Y-569388D01*
G01X333500Y-565138D02*
Y-570138D01*
G01X332043Y-565138D02*
X334957D01*
G01X338600Y-570305D02*
X338473Y-570221D01*
Y-570055D01*
X338600Y-569971D01*
X338727Y-570055D01*
Y-570221D01*
X338600Y-570305D01*
G01Y-568055D02*
X338473Y-567971D01*
Y-567805D01*
X338600Y-567721D01*
X338727Y-567805D01*
Y-567971D01*
X338600Y-568055D01*
G01X411000Y-610138D02*
Y-635138D01*
G01X413633Y-612638D02*
Y-617638D01*
X416167D01*
G01X419240Y-612638D02*
X420760D01*
G01X420000D02*
Y-617638D01*
G01X419240D02*
X420760D01*
G01X425607Y-614971D02*
X425860Y-614721D01*
X426050Y-614305D01*
X426177Y-613721D01*
X426050Y-613221D01*
X425797Y-612888D01*
X425353Y-612638D01*
X423643D01*
Y-617638D01*
X425733D01*
X426177Y-617305D01*
X426430Y-616805D01*
X426557Y-616221D01*
X426430Y-615638D01*
X426050Y-615138D01*
X425607Y-614971D01*
X423643D01*
G01X430200Y-617805D02*
X430073Y-617721D01*
Y-617555D01*
X430200Y-617471D01*
X430327Y-617555D01*
Y-617721D01*
X430200Y-617805D01*
G01Y-615555D02*
X430073Y-615471D01*
Y-615305D01*
X430200Y-615221D01*
X430327Y-615305D01*
Y-615471D01*
X430200Y-615555D01*
G01X454000Y-610138D02*
Y-635138D01*
G01Y-585138D02*
Y-610138D01*
G01X459013Y-637305D02*
X459120Y-637180D01*
X459200Y-636971D01*
X459253Y-636680D01*
X459200Y-636430D01*
X459093Y-636263D01*
X458907Y-636138D01*
X458187D01*
Y-638638D01*
X459067D01*
X459253Y-638471D01*
X459360Y-638221D01*
X459413Y-637930D01*
X459360Y-637638D01*
X459200Y-637388D01*
X459013Y-637305D01*
X458187D01*
G01X461480Y-638638D02*
Y-636971D01*
G01Y-637263D02*
X461373Y-637096D01*
X461213Y-637013D01*
X461027Y-636971D01*
X460840Y-637055D01*
X460680Y-637221D01*
X460573Y-637471D01*
X460520Y-637805D01*
X460573Y-638138D01*
X460680Y-638388D01*
X460840Y-638555D01*
X461027Y-638638D01*
X461213Y-638596D01*
X461373Y-638471D01*
X461480Y-638305D01*
G01X462800Y-638346D02*
X462933Y-638513D01*
X463120Y-638638D01*
X463280D01*
X463440Y-638555D01*
X463547Y-638430D01*
X463600Y-638263D01*
X463573Y-638013D01*
X463467Y-637888D01*
X462987Y-637638D01*
X462880Y-637346D01*
X462933Y-637138D01*
X463040Y-637013D01*
X463200Y-636971D01*
X463360Y-637013D01*
X463520Y-637138D01*
G01X465000Y-637513D02*
X465853D01*
X465773Y-637221D01*
X465640Y-637055D01*
X465453Y-636971D01*
X465267Y-637013D01*
X465107Y-637138D01*
X465000Y-637430D01*
X464947Y-637680D01*
Y-637930D01*
X465000Y-638180D01*
X465133Y-638430D01*
X465293Y-638596D01*
X465480Y-638638D01*
X465667Y-638555D01*
X465853Y-638305D01*
G01X467120Y-638638D02*
Y-636138D01*
G01Y-637388D02*
X467253Y-637138D01*
X467413Y-637013D01*
X467573Y-636971D01*
X467813Y-637055D01*
X467973Y-637221D01*
X468080Y-637513D01*
Y-637846D01*
X468027Y-638180D01*
X467920Y-638430D01*
X467733Y-638596D01*
X467573Y-638638D01*
X467413Y-638596D01*
X467253Y-638471D01*
X467120Y-638263D01*
G01X469800Y-638638D02*
X469640Y-638596D01*
X469480Y-638430D01*
X469373Y-638138D01*
X469320Y-637805D01*
X469373Y-637471D01*
X469480Y-637180D01*
X469640Y-637013D01*
X469800Y-636971D01*
X469960Y-637013D01*
X470120Y-637180D01*
X470227Y-637471D01*
X470253Y-637805D01*
X470227Y-638138D01*
X470120Y-638430D01*
X469960Y-638596D01*
X469800Y-638638D01*
G01X472480D02*
Y-636971D01*
G01Y-637263D02*
X472373Y-637096D01*
X472213Y-637013D01*
X472027Y-636971D01*
X471840Y-637055D01*
X471680Y-637221D01*
X471573Y-637471D01*
X471520Y-637805D01*
X471573Y-638138D01*
X471680Y-638388D01*
X471840Y-638555D01*
X472027Y-638638D01*
X472213Y-638596D01*
X472373Y-638471D01*
X472480Y-638305D01*
G01X473827Y-638638D02*
Y-636971D01*
G01Y-637305D02*
X473960Y-637138D01*
X474093Y-637013D01*
X474280Y-636971D01*
X474413Y-637013D01*
X474573Y-637138D01*
G01X476880Y-636138D02*
Y-638638D01*
G01Y-638263D02*
X476773Y-638471D01*
X476613Y-638596D01*
X476427Y-638638D01*
X476213Y-638555D01*
X476053Y-638346D01*
X475947Y-638096D01*
X475920Y-637805D01*
X475947Y-637513D01*
X476053Y-637263D01*
X476213Y-637055D01*
X476427Y-636971D01*
X476613Y-637013D01*
X476747Y-637096D01*
X476880Y-637263D01*
G01X480267Y-638638D02*
Y-636138D01*
X480933D01*
X481147Y-636263D01*
X481280Y-636430D01*
X481333Y-636763D01*
X481280Y-637096D01*
X481120Y-637305D01*
X480933Y-637430D01*
X480267D01*
G01X480933D02*
X481333Y-638638D01*
G01X482600Y-637513D02*
X483453D01*
X483373Y-637221D01*
X483240Y-637055D01*
X483053Y-636971D01*
X482867Y-637013D01*
X482707Y-637138D01*
X482600Y-637430D01*
X482547Y-637680D01*
Y-637930D01*
X482600Y-638180D01*
X482733Y-638430D01*
X482893Y-638596D01*
X483080Y-638638D01*
X483267Y-638555D01*
X483453Y-638305D01*
G01X484720Y-636971D02*
X485200Y-638638D01*
X485680Y-636971D01*
G01X487400Y-638721D02*
X487347Y-638680D01*
Y-638596D01*
X487400Y-638555D01*
X487453Y-638596D01*
Y-638680D01*
X487400Y-638721D01*
G01X489147Y-638346D02*
X489333Y-638555D01*
X489547Y-638638D01*
X489760Y-638555D01*
X489947Y-638305D01*
X490080Y-637930D01*
X490133Y-637555D01*
Y-637096D01*
X490080Y-636721D01*
X489947Y-636388D01*
X489787Y-636221D01*
X489600Y-636138D01*
X489387Y-636221D01*
X489227Y-636388D01*
X489120Y-636638D01*
X489067Y-636971D01*
X489120Y-637263D01*
X489253Y-637555D01*
X489413Y-637721D01*
X489600Y-637763D01*
X489813Y-637680D01*
X489973Y-637471D01*
X490133Y-637096D01*
G01X492013Y-637305D02*
X492120Y-637180D01*
X492200Y-636971D01*
X492253Y-636680D01*
X492200Y-636430D01*
X492093Y-636263D01*
X491907Y-636138D01*
X491187D01*
Y-638638D01*
X492067D01*
X492253Y-638471D01*
X492360Y-638221D01*
X492413Y-637930D01*
X492360Y-637638D01*
X492200Y-637388D01*
X492013Y-637305D01*
X491187D01*
G01X457900Y-612638D02*
Y-617638D01*
G01X456443Y-612638D02*
X459357D01*
G01X463000Y-617638D02*
X462620Y-617555D01*
X462240Y-617221D01*
X461987Y-616638D01*
X461860Y-615971D01*
X461987Y-615305D01*
X462240Y-614721D01*
X462620Y-614388D01*
X463000Y-614305D01*
X463380Y-614388D01*
X463760Y-614721D01*
X464013Y-615305D01*
X464077Y-615971D01*
X464013Y-616638D01*
X463760Y-617221D01*
X463380Y-617555D01*
X463000Y-617638D01*
G01X468100D02*
X467720Y-617555D01*
X467340Y-617221D01*
X467087Y-616638D01*
X466960Y-615971D01*
X467087Y-615305D01*
X467340Y-614721D01*
X467720Y-614388D01*
X468100Y-614305D01*
X468480Y-614388D01*
X468860Y-614721D01*
X469113Y-615305D01*
X469177Y-615971D01*
X469113Y-616638D01*
X468860Y-617221D01*
X468480Y-617555D01*
X468100Y-617638D01*
G01X473200D02*
Y-612638D01*
G01X478300Y-617805D02*
X478173Y-617721D01*
Y-617555D01*
X478300Y-617471D01*
X478427Y-617555D01*
Y-617721D01*
X478300Y-617805D01*
G01Y-615555D02*
X478173Y-615471D01*
Y-615305D01*
X478300Y-615221D01*
X478427Y-615305D01*
Y-615471D01*
X478300Y-615555D01*
G01X456633Y-592638D02*
Y-587638D01*
X458217D01*
X458723Y-587888D01*
X459040Y-588221D01*
X459167Y-588888D01*
X459040Y-589555D01*
X458660Y-589971D01*
X458217Y-590221D01*
X456633D01*
G01X458217D02*
X459167Y-592638D01*
G01X464267D02*
X461733D01*
Y-587638D01*
X464267D01*
G01X463253Y-590055D02*
X461733D01*
G01X466517Y-587638D02*
X468100Y-592638D01*
X469683Y-587638D01*
G01X473200Y-592805D02*
X473073Y-592721D01*
Y-592555D01*
X473200Y-592471D01*
X473327Y-592555D01*
Y-592721D01*
X473200Y-592805D01*
G01Y-590555D02*
X473073Y-590471D01*
Y-590305D01*
X473200Y-590221D01*
X473327Y-590305D01*
Y-590471D01*
X473200Y-590555D01*
G01X-476840Y-884638D02*
Y2768362D01*
X5911000D01*
Y-884638D01*
X-476840D01*
G01X8820Y-607488D02*
X10387D01*
Y-609378D01*
X9917Y-610008D01*
X9368Y-610428D01*
X8585Y-610638D01*
X7802Y-610428D01*
X7253Y-610008D01*
X6783Y-609378D01*
X6470Y-608643D01*
X6313Y-607803D01*
Y-607068D01*
X6470Y-606438D01*
X6783Y-605703D01*
X7253Y-605073D01*
X7723Y-604653D01*
X8350Y-604338D01*
X8898D01*
X9525Y-604548D01*
X9995Y-604968D01*
G01X12927Y-604338D02*
Y-608853D01*
X13240Y-609798D01*
X13867Y-610428D01*
X14650Y-610638D01*
X15433Y-610428D01*
X16060Y-609798D01*
X16373Y-608853D01*
Y-604338D01*
G01X20010D02*
X21890D01*
G01X20950D02*
Y-610638D01*
G01X20010D02*
X21890D01*
G01X25605Y-609798D02*
X26232Y-610323D01*
X26937Y-610638D01*
X27563D01*
X28190Y-610323D01*
X28660Y-609798D01*
X28895Y-609063D01*
X28738Y-608328D01*
X28347Y-607698D01*
X27642Y-607278D01*
X26702Y-607068D01*
X26153Y-606648D01*
X25918Y-605913D01*
X26075Y-605178D01*
X26467Y-604653D01*
X27015Y-604338D01*
X27563D01*
X28112Y-604548D01*
X28582Y-605073D01*
G01X31905Y-610638D02*
Y-604338D01*
G01X35195D02*
Y-610638D01*
G01Y-607488D02*
X31905D01*
G01X37892Y-610638D02*
X39850Y-604338D01*
X41808Y-610638D01*
G01X41103Y-608433D02*
X38597D01*
G01X44348Y-610638D02*
Y-604338D01*
X47952Y-610638D01*
Y-604338D01*
G01X57027Y-610638D02*
Y-604338D01*
X58593D01*
X59220Y-604653D01*
X59690Y-605073D01*
X60082Y-605703D01*
X60395Y-606438D01*
X60473Y-607488D01*
X60395Y-608538D01*
X60082Y-609273D01*
X59690Y-609903D01*
X59220Y-610323D01*
X58593Y-610638D01*
X57027D01*
G01X64110Y-604338D02*
X65990D01*
G01X65050D02*
Y-610638D01*
G01X64110D02*
X65990D01*
G01X69705Y-609798D02*
X70332Y-610323D01*
X71037Y-610638D01*
X71663D01*
X72290Y-610323D01*
X72760Y-609798D01*
X72995Y-609063D01*
X72838Y-608328D01*
X72447Y-607698D01*
X71742Y-607278D01*
X70802Y-607068D01*
X70253Y-606648D01*
X70018Y-605913D01*
X70175Y-605178D01*
X70567Y-604653D01*
X71115Y-604338D01*
X71663D01*
X72212Y-604548D01*
X72682Y-605073D01*
G01X77650Y-604338D02*
Y-610638D01*
G01X75848Y-604338D02*
X79452D01*
G01X83950Y-610848D02*
X83793Y-610743D01*
Y-610533D01*
X83950Y-610428D01*
X84107Y-610533D01*
Y-610743D01*
X83950Y-610848D01*
G01X90093Y-611793D02*
X90407Y-610428D01*
G01X96550Y-604338D02*
Y-610638D01*
G01X94748Y-604338D02*
X98352D01*
G01X100892Y-610638D02*
X102850Y-604338D01*
X104808Y-610638D01*
G01X104103Y-608433D02*
X101597D01*
G01X109150Y-610638D02*
X108523Y-610533D01*
X107975Y-610113D01*
X107505Y-609483D01*
X107192Y-608748D01*
X107035Y-607908D01*
Y-607068D01*
X107192Y-606228D01*
X107505Y-605493D01*
X107975Y-604863D01*
X108523Y-604443D01*
X109150Y-604338D01*
X109777Y-604443D01*
X110325Y-604863D01*
X110795Y-605493D01*
X111108Y-606228D01*
X111265Y-607068D01*
Y-607908D01*
X111108Y-608748D01*
X110795Y-609483D01*
X110325Y-610113D01*
X109777Y-610533D01*
X109150Y-610638D01*
G01X115450D02*
Y-607803D01*
X113883Y-604338D01*
G01X117017D02*
X115450Y-607803D01*
G01X120027Y-604338D02*
Y-608853D01*
X120340Y-609798D01*
X120967Y-610428D01*
X121750Y-610638D01*
X122533Y-610428D01*
X123160Y-609798D01*
X123473Y-608853D01*
Y-604338D01*
G01X126092Y-610638D02*
X128050Y-604338D01*
X130008Y-610638D01*
G01X129303Y-608433D02*
X126797D01*
G01X132548Y-610638D02*
Y-604338D01*
X136152Y-610638D01*
Y-604338D01*
G01X10073Y-614863D02*
X9603Y-614548D01*
X9055Y-614338D01*
X8428D01*
X7723Y-614653D01*
X7175Y-615178D01*
X6783Y-615808D01*
X6470Y-616858D01*
X6392Y-617803D01*
X6548Y-618748D01*
X6783Y-619378D01*
X7253Y-620008D01*
X7802Y-620428D01*
X8350Y-620638D01*
X8898D01*
X9447Y-620428D01*
X9917Y-620113D01*
X10308Y-619693D01*
G01X13710Y-614338D02*
X15590D01*
G01X14650D02*
Y-620638D01*
G01X13710D02*
X15590D01*
G01X20950Y-614338D02*
Y-620638D01*
G01X19148Y-614338D02*
X22752D01*
G01X27250Y-620638D02*
Y-617803D01*
X25683Y-614338D01*
G01X28817D02*
X27250Y-617803D01*
G01X38127Y-619378D02*
X38597Y-620113D01*
X39223Y-620533D01*
X39928Y-620638D01*
X40555Y-620533D01*
X41182Y-620008D01*
X41573Y-619378D01*
X41652Y-618748D01*
X41495Y-618013D01*
X40947Y-617488D01*
X40398Y-617278D01*
X39693D01*
G01X40398D02*
X40868Y-616963D01*
X41260Y-616438D01*
X41417Y-615808D01*
X41260Y-615178D01*
X40868Y-614653D01*
X40163Y-614338D01*
X39458Y-614443D01*
X38753Y-614863D01*
G01X44427Y-619378D02*
X44897Y-620113D01*
X45523Y-620533D01*
X46228Y-620638D01*
X46855Y-620533D01*
X47482Y-620008D01*
X47873Y-619378D01*
X47952Y-618748D01*
X47795Y-618013D01*
X47247Y-617488D01*
X46698Y-617278D01*
X45993D01*
G01X46698D02*
X47168Y-616963D01*
X47560Y-616438D01*
X47717Y-615808D01*
X47560Y-615178D01*
X47168Y-614653D01*
X46463Y-614338D01*
X45758Y-614443D01*
X45053Y-614863D01*
G01X50727Y-619378D02*
X51197Y-620113D01*
X51823Y-620533D01*
X52528Y-620638D01*
X53155Y-620533D01*
X53782Y-620008D01*
X54173Y-619378D01*
X54252Y-618748D01*
X54095Y-618013D01*
X53547Y-617488D01*
X52998Y-617278D01*
X52293D01*
G01X52998D02*
X53468Y-616963D01*
X53860Y-616438D01*
X54017Y-615808D01*
X53860Y-615178D01*
X53468Y-614653D01*
X52763Y-614338D01*
X52058Y-614443D01*
X51353Y-614863D01*
G01X58593Y-620638D02*
X58750Y-619273D01*
X58985Y-618118D01*
X59298Y-617068D01*
X59690Y-615913D01*
X60317Y-614338D01*
X57183D01*
G01X64893Y-620638D02*
X65050Y-619273D01*
X65285Y-618118D01*
X65598Y-617068D01*
X65990Y-615913D01*
X66617Y-614338D01*
X63483D01*
G01X71193Y-621793D02*
X71507Y-620428D01*
G01X77650Y-614338D02*
Y-620638D01*
G01X75848Y-614338D02*
X79452D01*
G01X81992Y-620638D02*
X83950Y-614338D01*
X85908Y-620638D01*
G01X85203Y-618433D02*
X82697D01*
G01X89310Y-614338D02*
X91190D01*
G01X90250D02*
Y-620638D01*
G01X89310D02*
X91190D01*
G01X94200Y-614338D02*
X95297Y-620638D01*
X96550Y-614338D01*
X97803Y-620638D01*
X98900Y-614338D01*
G01X100892Y-620638D02*
X102850Y-614338D01*
X104808Y-620638D01*
G01X104103Y-618433D02*
X101597D01*
G01X107348Y-620638D02*
Y-614338D01*
X110952Y-620638D01*
Y-614338D01*
G01X121358Y-622738D02*
X120575Y-621688D01*
X120183Y-620638D01*
Y-616438D01*
X120575Y-615388D01*
X121358Y-614338D01*
G01X132783Y-620638D02*
Y-614338D01*
X134742D01*
X135368Y-614653D01*
X135760Y-615073D01*
X135917Y-615913D01*
X135760Y-616753D01*
X135290Y-617278D01*
X134742Y-617593D01*
X132783D01*
G01X134742D02*
X135917Y-620638D01*
G01X140650Y-620848D02*
X140493Y-620743D01*
Y-620533D01*
X140650Y-620428D01*
X140807Y-620533D01*
Y-620743D01*
X140650Y-620848D01*
G01X146950Y-620638D02*
X146323Y-620533D01*
X145775Y-620113D01*
X145305Y-619483D01*
X144992Y-618748D01*
X144835Y-617908D01*
Y-617068D01*
X144992Y-616228D01*
X145305Y-615493D01*
X145775Y-614863D01*
X146323Y-614443D01*
X146950Y-614338D01*
X147577Y-614443D01*
X148125Y-614863D01*
X148595Y-615493D01*
X148908Y-616228D01*
X149065Y-617068D01*
Y-617908D01*
X148908Y-618748D01*
X148595Y-619483D01*
X148125Y-620113D01*
X147577Y-620533D01*
X146950Y-620638D01*
G01X153250Y-620848D02*
X153093Y-620743D01*
Y-620533D01*
X153250Y-620428D01*
X153407Y-620533D01*
Y-620743D01*
X153250Y-620848D01*
G01X161273Y-614863D02*
X160803Y-614548D01*
X160255Y-614338D01*
X159628D01*
X158923Y-614653D01*
X158375Y-615178D01*
X157983Y-615808D01*
X157670Y-616858D01*
X157592Y-617803D01*
X157748Y-618748D01*
X157983Y-619378D01*
X158453Y-620008D01*
X159002Y-620428D01*
X159550Y-620638D01*
X160098D01*
X160647Y-620428D01*
X161117Y-620113D01*
X161508Y-619693D01*
G01X165850Y-620848D02*
X165693Y-620743D01*
Y-620533D01*
X165850Y-620428D01*
X166007Y-620533D01*
Y-620743D01*
X165850Y-620848D01*
G01X172542Y-622738D02*
X173325Y-621688D01*
X173717Y-620638D01*
Y-616438D01*
X173325Y-615388D01*
X172542Y-614338D01*
G01X6548Y-600638D02*
Y-594338D01*
X10152Y-600638D01*
Y-594338D01*
G01X14650Y-600638D02*
X14023Y-600533D01*
X13475Y-600113D01*
X13005Y-599483D01*
X12692Y-598748D01*
X12535Y-597908D01*
Y-597068D01*
X12692Y-596228D01*
X13005Y-595493D01*
X13475Y-594863D01*
X14023Y-594443D01*
X14650Y-594338D01*
X15277Y-594443D01*
X15825Y-594863D01*
X16295Y-595493D01*
X16608Y-596228D01*
X16765Y-597068D01*
Y-597908D01*
X16608Y-598748D01*
X16295Y-599483D01*
X15825Y-600113D01*
X15277Y-600533D01*
X14650Y-600638D01*
G01X20950Y-600848D02*
X20793Y-600743D01*
Y-600533D01*
X20950Y-600428D01*
X21107Y-600533D01*
Y-600743D01*
X20950Y-600848D01*
G01X25762Y-595388D02*
X26232Y-594758D01*
X26780Y-594443D01*
X27407Y-594338D01*
X28190Y-594548D01*
X28738Y-595073D01*
X28895Y-595703D01*
X28817Y-596333D01*
X28503Y-596858D01*
X26937Y-597908D01*
X26232Y-598643D01*
X25762Y-599693D01*
X25605Y-600638D01*
X28895D01*
G01X33550D02*
Y-594338D01*
X32610Y-595598D01*
G01Y-600638D02*
X34490D01*
G01X39850D02*
Y-594338D01*
X38910Y-595598D01*
G01Y-600638D02*
X40790D01*
G01X45993Y-601793D02*
X46307Y-600428D01*
G01X50100Y-594338D02*
X51197Y-600638D01*
X52450Y-594338D01*
X53703Y-600638D01*
X54800Y-594338D01*
G01X60317Y-600638D02*
X57183D01*
Y-594338D01*
X60317D01*
G01X59063Y-597383D02*
X57183D01*
G01X63248Y-600638D02*
Y-594338D01*
X66852Y-600638D01*
Y-594338D01*
G01X69705Y-600638D02*
Y-594338D01*
G01X72995D02*
Y-600638D01*
G01Y-597488D02*
X69705D01*
G01X75927Y-594338D02*
Y-598853D01*
X76240Y-599798D01*
X76867Y-600428D01*
X77650Y-600638D01*
X78433Y-600428D01*
X79060Y-599798D01*
X79373Y-598853D01*
Y-594338D01*
G01X81992Y-600638D02*
X83950Y-594338D01*
X85908Y-600638D01*
G01X85203Y-598433D02*
X82697D01*
G01X95062Y-595388D02*
X95532Y-594758D01*
X96080Y-594443D01*
X96707Y-594338D01*
X97490Y-594548D01*
X98038Y-595073D01*
X98195Y-595703D01*
X98117Y-596333D01*
X97803Y-596858D01*
X96237Y-597908D01*
X95532Y-598643D01*
X95062Y-599693D01*
X94905Y-600638D01*
X98195D01*
G01X101048D02*
Y-594338D01*
X104652Y-600638D01*
Y-594338D01*
G01X107427Y-600638D02*
Y-594338D01*
X108993D01*
X109620Y-594653D01*
X110090Y-595073D01*
X110482Y-595703D01*
X110795Y-596438D01*
X110873Y-597488D01*
X110795Y-598538D01*
X110482Y-599273D01*
X110090Y-599903D01*
X109620Y-600323D01*
X108993Y-600638D01*
X107427D01*
G01X120183D02*
Y-594338D01*
X122142D01*
X122768Y-594653D01*
X123160Y-595073D01*
X123317Y-595913D01*
X123160Y-596753D01*
X122690Y-597278D01*
X122142Y-597593D01*
X120183D01*
G01X122142D02*
X123317Y-600638D01*
G01X126327D02*
Y-594338D01*
X127893D01*
X128520Y-594653D01*
X128990Y-595073D01*
X129382Y-595703D01*
X129695Y-596438D01*
X129773Y-597488D01*
X129695Y-598538D01*
X129382Y-599273D01*
X128990Y-599903D01*
X128520Y-600323D01*
X127893Y-600638D01*
X126327D01*
G01X134350Y-600848D02*
X134193Y-600743D01*
Y-600533D01*
X134350Y-600428D01*
X134507Y-600533D01*
Y-600743D01*
X134350Y-600848D01*
G01X30650Y-589938D02*
X28130Y-589521D01*
X25925Y-587855D01*
X24035Y-585355D01*
X22775Y-582438D01*
X22145Y-579105D01*
Y-575771D01*
X22775Y-572438D01*
X24035Y-569521D01*
X25925Y-567022D01*
X28130Y-565355D01*
X30650Y-564938D01*
X33170Y-565355D01*
X35375Y-567022D01*
X37265Y-569521D01*
X38525Y-572438D01*
X39155Y-575771D01*
Y-579105D01*
X38525Y-582438D01*
X37265Y-585355D01*
X35375Y-587855D01*
X33170Y-589521D01*
X30650Y-589938D01*
G01X33170Y-583271D02*
X36950Y-589938D01*
G01X50495Y-573272D02*
Y-584938D01*
X51755Y-587855D01*
X53645Y-589521D01*
X55850Y-589938D01*
X58055Y-589521D01*
X59945Y-587855D01*
X61205Y-584938D01*
G01Y-589938D02*
Y-573272D01*
G01X86720Y-589938D02*
Y-573272D01*
G01Y-576188D02*
X85460Y-574522D01*
X83570Y-573688D01*
X81365Y-573272D01*
X79160Y-574105D01*
X77270Y-575771D01*
X76010Y-578272D01*
X75380Y-581605D01*
X76010Y-584938D01*
X77270Y-587439D01*
X79160Y-589105D01*
X81365Y-589938D01*
X83570Y-589521D01*
X85460Y-588272D01*
X86720Y-586605D01*
G01X100895Y-589938D02*
Y-573272D01*
G01Y-577438D02*
X102155Y-575355D01*
X104045Y-573688D01*
X106565Y-573272D01*
X108770Y-573688D01*
X110660Y-575355D01*
X111605Y-578272D01*
Y-589938D01*
G01X131450Y-564938D02*
Y-589938D01*
G01X127040Y-573272D02*
X135860D01*
G01X162320Y-589938D02*
Y-573272D01*
G01Y-576188D02*
X161060Y-574522D01*
X159170Y-573688D01*
X156965Y-573272D01*
X154760Y-574105D01*
X152870Y-575771D01*
X151610Y-578272D01*
X150980Y-581605D01*
X151610Y-584938D01*
X152870Y-587439D01*
X154760Y-589105D01*
X156965Y-589938D01*
X159170Y-589521D01*
X161060Y-588272D01*
X162320Y-586605D01*
G01X215400Y-602638D02*
Y-594638D01*
X218000Y-601305D01*
X220600Y-594638D01*
Y-602638D01*
G01X223500D02*
X226000Y-594638D01*
X228500Y-602638D01*
G01X227600Y-599838D02*
X224400D01*
G01X231900Y-601572D02*
X232700Y-602238D01*
X233600Y-602638D01*
X234400D01*
X235200Y-602238D01*
X235800Y-601572D01*
X236100Y-600638D01*
X235900Y-599705D01*
X235400Y-598905D01*
X234500Y-598371D01*
X233300Y-598105D01*
X232600Y-597571D01*
X232300Y-596638D01*
X232500Y-595705D01*
X233000Y-595038D01*
X233700Y-594638D01*
X234400D01*
X235100Y-594905D01*
X235700Y-595571D01*
G01X239800Y-602638D02*
Y-594638D01*
G01X243600D02*
X239800Y-599572D01*
G01X244200Y-602638D02*
X241500Y-597305D01*
G01X248700Y-599971D02*
X251300D01*
G01X258000Y-594638D02*
Y-602638D01*
G01X255700Y-594638D02*
X260300D01*
G01X266000Y-602638D02*
X265200Y-602505D01*
X264500Y-601971D01*
X263900Y-601171D01*
X263500Y-600238D01*
X263300Y-599171D01*
Y-598105D01*
X263500Y-597038D01*
X263900Y-596105D01*
X264500Y-595305D01*
X265200Y-594771D01*
X266000Y-594638D01*
X266800Y-594771D01*
X267500Y-595305D01*
X268100Y-596105D01*
X268500Y-597038D01*
X268700Y-598105D01*
Y-599171D01*
X268500Y-600238D01*
X268100Y-601171D01*
X267500Y-601971D01*
X266800Y-602505D01*
X266000Y-602638D01*
G01X272000D02*
Y-594638D01*
X274400D01*
X275200Y-595038D01*
X275800Y-595971D01*
X276000Y-597038D01*
X275800Y-598105D01*
X275300Y-598905D01*
X274400Y-599305D01*
X272000D01*
G01X202000Y-569638D02*
Y-577638D01*
X206000D01*
G01X213800D02*
Y-572305D01*
G01Y-573238D02*
X213400Y-572705D01*
X212800Y-572438D01*
X212100Y-572305D01*
X211400Y-572571D01*
X210800Y-573105D01*
X210400Y-573905D01*
X210200Y-574971D01*
X210400Y-576038D01*
X210800Y-576838D01*
X211400Y-577371D01*
X212100Y-577638D01*
X212800Y-577505D01*
X213400Y-577105D01*
X213800Y-576572D01*
G01X217900Y-580038D02*
X218500Y-580305D01*
X219300Y-580038D01*
X219800Y-579505D01*
X220200Y-578838D01*
X220800Y-576705D01*
X222100Y-572305D01*
G01X218900D02*
X220800Y-576705D01*
G01X226500Y-574038D02*
X229700D01*
X229400Y-573105D01*
X228900Y-572571D01*
X228200Y-572305D01*
X227500Y-572438D01*
X226900Y-572838D01*
X226500Y-573771D01*
X226300Y-574572D01*
Y-575371D01*
X226500Y-576171D01*
X227000Y-576971D01*
X227600Y-577505D01*
X228300Y-577638D01*
X229000Y-577371D01*
X229700Y-576572D01*
G01X234600Y-577638D02*
Y-572305D01*
G01Y-573371D02*
X235100Y-572838D01*
X235600Y-572438D01*
X236300Y-572305D01*
X236800Y-572438D01*
X237400Y-572838D01*
G01X226000Y-626038D02*
X226500Y-626838D01*
X227100Y-627371D01*
X227800Y-627638D01*
X228600Y-627371D01*
X229200Y-626838D01*
X229800Y-626038D01*
X230000Y-624971D01*
Y-619638D01*
G01X237800Y-627638D02*
Y-622305D01*
G01Y-623238D02*
X237400Y-622705D01*
X236800Y-622438D01*
X236100Y-622305D01*
X235400Y-622571D01*
X234800Y-623105D01*
X234400Y-623905D01*
X234200Y-624971D01*
X234400Y-626038D01*
X234800Y-626838D01*
X235400Y-627371D01*
X236100Y-627638D01*
X236800Y-627505D01*
X237400Y-627105D01*
X237800Y-626572D01*
G01X245600Y-622971D02*
X244900Y-622438D01*
X244300Y-622305D01*
X243500Y-622571D01*
X242900Y-623105D01*
X242500Y-624038D01*
X242400Y-624971D01*
X242500Y-625905D01*
X242900Y-626705D01*
X243500Y-627371D01*
X244300Y-627638D01*
X245000Y-627371D01*
X245600Y-626838D01*
G01X250300Y-627638D02*
Y-619638D01*
G01X253500Y-622305D02*
X250300Y-625371D01*
G01X251600Y-624171D02*
X253700Y-627638D01*
G01X328600Y-620971D02*
X329200Y-620171D01*
X329900Y-619771D01*
X330700Y-619638D01*
X331700Y-619905D01*
X332400Y-620571D01*
X332600Y-621371D01*
X332500Y-622172D01*
X332100Y-622838D01*
X330100Y-624171D01*
X329200Y-625105D01*
X328600Y-626438D01*
X328400Y-627638D01*
X332600D01*
G01X338500Y-619638D02*
X337700Y-619905D01*
X337100Y-620571D01*
X336700Y-621371D01*
X336400Y-622438D01*
X336300Y-623638D01*
X336400Y-624838D01*
X336700Y-625905D01*
X337100Y-626705D01*
X337700Y-627371D01*
X338500Y-627638D01*
X339300Y-627371D01*
X339900Y-626705D01*
X340300Y-625905D01*
X340600Y-624838D01*
X340700Y-623638D01*
X340600Y-622438D01*
X340300Y-621371D01*
X339900Y-620571D01*
X339300Y-619905D01*
X338500Y-619638D01*
G01X344600Y-620971D02*
X345200Y-620171D01*
X345900Y-619771D01*
X346700Y-619638D01*
X347700Y-619905D01*
X348400Y-620571D01*
X348600Y-621371D01*
X348500Y-622172D01*
X348100Y-622838D01*
X346100Y-624171D01*
X345200Y-625105D01*
X344600Y-626438D01*
X344400Y-627638D01*
X348600D01*
G01X352300Y-626038D02*
X352900Y-626971D01*
X353700Y-627505D01*
X354600Y-627638D01*
X355400Y-627505D01*
X356200Y-626838D01*
X356700Y-626038D01*
X356800Y-625238D01*
X356600Y-624305D01*
X355900Y-623638D01*
X355200Y-623371D01*
X354300D01*
G01X355200D02*
X355800Y-622971D01*
X356300Y-622305D01*
X356500Y-621505D01*
X356300Y-620705D01*
X355800Y-620038D01*
X354900Y-619638D01*
X354000Y-619771D01*
X353100Y-620305D01*
G01X360700Y-627905D02*
X364300Y-619638D01*
G01X370500D02*
X369700Y-619905D01*
X369100Y-620571D01*
X368700Y-621371D01*
X368400Y-622438D01*
X368300Y-623638D01*
X368400Y-624838D01*
X368700Y-625905D01*
X369100Y-626705D01*
X369700Y-627371D01*
X370500Y-627638D01*
X371300Y-627371D01*
X371900Y-626705D01*
X372300Y-625905D01*
X372600Y-624838D01*
X372700Y-623638D01*
X372600Y-622438D01*
X372300Y-621371D01*
X371900Y-620571D01*
X371300Y-619905D01*
X370500Y-619638D01*
G01X379700Y-627638D02*
Y-619638D01*
X376000Y-625371D01*
X381000D01*
G01X384700Y-627905D02*
X388300Y-619638D01*
G01X394500Y-627638D02*
Y-619638D01*
X393300Y-621238D01*
G01Y-627638D02*
X395700D01*
G01X402300D02*
X402500Y-625905D01*
X402800Y-624438D01*
X403200Y-623105D01*
X403700Y-621638D01*
X404500Y-619638D01*
X400500D01*
G01X328300Y-602638D02*
Y-594638D01*
X330300D01*
X331100Y-595038D01*
X331700Y-595571D01*
X332200Y-596371D01*
X332600Y-597305D01*
X332700Y-598638D01*
X332600Y-599971D01*
X332200Y-600905D01*
X331700Y-601705D01*
X331100Y-602238D01*
X330300Y-602638D01*
X328300D01*
G01X336000D02*
X338500Y-594638D01*
X341000Y-602638D01*
G01X340100Y-599838D02*
X336900D01*
G01X344600Y-602638D02*
Y-594638D01*
X348400D01*
G01X347000Y-598505D02*
X344600D01*
G01X354500Y-594638D02*
X353700Y-594905D01*
X353100Y-595571D01*
X352700Y-596371D01*
X352400Y-597438D01*
X352300Y-598638D01*
X352400Y-599838D01*
X352700Y-600905D01*
X353100Y-601705D01*
X353700Y-602371D01*
X354500Y-602638D01*
X355300Y-602371D01*
X355900Y-601705D01*
X356300Y-600905D01*
X356600Y-599838D01*
X356700Y-598638D01*
X356600Y-597438D01*
X356300Y-596371D01*
X355900Y-595571D01*
X355300Y-594905D01*
X354500Y-594638D01*
G01X362500D02*
Y-602638D01*
G01X360200Y-594638D02*
X364800D01*
G01X367900Y-602638D02*
Y-594638D01*
X370500Y-601305D01*
X373100Y-594638D01*
Y-602638D01*
G01X379300Y-598371D02*
X379700Y-597971D01*
X380000Y-597305D01*
X380200Y-596371D01*
X380000Y-595571D01*
X379600Y-595038D01*
X378900Y-594638D01*
X376200D01*
Y-602638D01*
X379500D01*
X380200Y-602105D01*
X380600Y-601305D01*
X380800Y-600371D01*
X380600Y-599438D01*
X380000Y-598638D01*
X379300Y-598371D01*
X376200D01*
G01X384300Y-601038D02*
X384900Y-601971D01*
X385700Y-602505D01*
X386600Y-602638D01*
X387400Y-602505D01*
X388200Y-601838D01*
X388700Y-601038D01*
X388800Y-600238D01*
X388600Y-599305D01*
X387900Y-598638D01*
X387200Y-598371D01*
X386300D01*
G01X387200D02*
X387800Y-597971D01*
X388300Y-597305D01*
X388500Y-596505D01*
X388300Y-595705D01*
X387800Y-595038D01*
X386900Y-594638D01*
X386000Y-594771D01*
X385100Y-595305D01*
G01X393300Y-594638D02*
X395700D01*
G01X394500D02*
Y-602638D01*
G01X393300D02*
X395700D01*
G01X404700Y-595305D02*
X404100Y-594905D01*
X403400Y-594638D01*
X402600D01*
X401700Y-595038D01*
X401000Y-595705D01*
X400500Y-596505D01*
X400100Y-597838D01*
X400000Y-599038D01*
X400200Y-600238D01*
X400500Y-601038D01*
X401100Y-601838D01*
X401800Y-602371D01*
X402500Y-602638D01*
X403200D01*
X403900Y-602371D01*
X404500Y-601971D01*
X405000Y-601438D01*
G01X410500Y-594638D02*
X409700Y-594905D01*
X409100Y-595571D01*
X408700Y-596371D01*
X408400Y-597438D01*
X408300Y-598638D01*
X408400Y-599838D01*
X408700Y-600905D01*
X409100Y-601705D01*
X409700Y-602371D01*
X410500Y-602638D01*
X411300Y-602371D01*
X411900Y-601705D01*
X412300Y-600905D01*
X412600Y-599838D01*
X412700Y-598638D01*
X412600Y-597438D01*
X412300Y-596371D01*
X411900Y-595571D01*
X411300Y-594905D01*
X410500Y-594638D01*
G01X346100Y-577638D02*
Y-569638D01*
X349900D01*
G01X348500Y-573505D02*
X346100D01*
G01X356000Y-569638D02*
X355200Y-569905D01*
X354600Y-570571D01*
X354200Y-571371D01*
X353900Y-572438D01*
X353800Y-573638D01*
X353900Y-574838D01*
X354200Y-575905D01*
X354600Y-576705D01*
X355200Y-577371D01*
X356000Y-577638D01*
X356800Y-577371D01*
X357400Y-576705D01*
X357800Y-575905D01*
X358100Y-574838D01*
X358200Y-573638D01*
X358100Y-572438D01*
X357800Y-571371D01*
X357400Y-570571D01*
X356800Y-569905D01*
X356000Y-569638D01*
G01X364000D02*
Y-577638D01*
G01X361700Y-569638D02*
X366300D01*
G01X372600Y-573638D02*
X374600D01*
Y-576038D01*
X374000Y-576838D01*
X373300Y-577371D01*
X372300Y-577638D01*
X371300Y-577371D01*
X370600Y-576838D01*
X370000Y-576038D01*
X369600Y-575105D01*
X369400Y-574038D01*
Y-573105D01*
X369600Y-572305D01*
X370000Y-571371D01*
X370600Y-570571D01*
X371200Y-570038D01*
X372000Y-569638D01*
X372700D01*
X373500Y-569905D01*
X374100Y-570438D01*
G01X377000Y-580305D02*
X383000D01*
G01X385400Y-577638D02*
Y-569638D01*
X388000Y-576305D01*
X390600Y-569638D01*
Y-577638D01*
G01X396800Y-573371D02*
X397200Y-572971D01*
X397500Y-572305D01*
X397700Y-571371D01*
X397500Y-570571D01*
X397100Y-570038D01*
X396400Y-569638D01*
X393700D01*
Y-577638D01*
X397000D01*
X397700Y-577105D01*
X398100Y-576305D01*
X398300Y-575371D01*
X398100Y-574438D01*
X397500Y-573638D01*
X396800Y-573371D01*
X393700D01*
G01X417000Y-630638D02*
Y-622638D01*
X415800Y-624238D01*
G01Y-630638D02*
X418200D01*
G01X423100Y-627305D02*
X423800Y-626371D01*
X424400Y-625838D01*
X425200Y-625571D01*
X425900Y-625838D01*
X426400Y-626371D01*
X426800Y-627171D01*
X426900Y-628105D01*
X426800Y-628905D01*
X426400Y-629705D01*
X425800Y-630371D01*
X425100Y-630638D01*
X424300Y-630371D01*
X423600Y-629572D01*
X423200Y-628371D01*
X423100Y-627038D01*
X423300Y-625305D01*
X423600Y-624371D01*
X424100Y-623438D01*
X424800Y-622771D01*
X425500Y-622638D01*
X426200Y-622905D01*
X426700Y-623571D01*
G01X433000Y-630905D02*
X432800Y-630771D01*
Y-630505D01*
X433000Y-630371D01*
X433200Y-630505D01*
Y-630771D01*
X433000Y-630905D01*
G01X439100Y-627305D02*
X439800Y-626371D01*
X440400Y-625838D01*
X441200Y-625571D01*
X441900Y-625838D01*
X442400Y-626371D01*
X442800Y-627171D01*
X442900Y-628105D01*
X442800Y-628905D01*
X442400Y-629705D01*
X441800Y-630371D01*
X441100Y-630638D01*
X440300Y-630371D01*
X439600Y-629572D01*
X439200Y-628371D01*
X439100Y-627038D01*
X439300Y-625305D01*
X439600Y-624371D01*
X440100Y-623438D01*
X440800Y-622771D01*
X441500Y-622638D01*
X442200Y-622905D01*
X442700Y-623571D01*
G01X462000Y-630638D02*
Y-622638D01*
X460800Y-624238D01*
G01Y-630638D02*
X463200D01*
G01X469800D02*
X470000Y-628905D01*
X470300Y-627438D01*
X470700Y-626105D01*
X471200Y-624638D01*
X472000Y-622638D01*
X468000D01*
G01X478000Y-630905D02*
X477800Y-630771D01*
Y-630505D01*
X478000Y-630371D01*
X478200Y-630505D01*
Y-630771D01*
X478000Y-630905D01*
G01X484100Y-623971D02*
X484700Y-623171D01*
X485400Y-622771D01*
X486200Y-622638D01*
X487200Y-622905D01*
X487900Y-623571D01*
X488100Y-624371D01*
X488000Y-625172D01*
X487600Y-625838D01*
X485600Y-627171D01*
X484700Y-628105D01*
X484100Y-629438D01*
X483900Y-630638D01*
X488100D01*
G01X486200Y-598305D02*
X485600Y-597905D01*
X484900Y-597638D01*
X484100D01*
X483200Y-598038D01*
X482500Y-598705D01*
X482000Y-599505D01*
X481600Y-600838D01*
X481500Y-602038D01*
X481700Y-603238D01*
X482000Y-604038D01*
X482600Y-604838D01*
X483300Y-605371D01*
X484000Y-605638D01*
X484700D01*
X485400Y-605371D01*
X486000Y-604971D01*
X486500Y-604438D01*
G54D16*
X17363Y230264D03*
X10543Y230308D03*
X36595Y385068D03*
X32774Y525886D03*
X46834Y363428D03*
X50631Y1530187D03*
X42150Y1550596D03*
X46150D03*
X45633Y1595412D03*
X50133D03*
X55190Y363428D03*
X64442Y504481D03*
X53299Y546811D03*
X63148Y546776D03*
X58365D03*
X59427Y1646903D03*
X66127Y1681903D03*
X76378Y1409171D03*
X72378D03*
X79323Y1530043D03*
X72768Y1547312D03*
X76806Y1596423D03*
X78406Y1604723D03*
X73427Y1646903D03*
X68427D03*
X82127Y1681903D03*
X86374Y1530687D03*
X90127Y1681903D03*
X92257Y1721347D03*
X98101Y1363553D03*
X108511Y1547012D03*
X115016Y294713D03*
Y315147D03*
X118407Y521307D03*
X126910Y1364151D03*
X119632Y1381874D03*
X115066Y1529743D03*
X120353Y1649103D03*
X124353D03*
X116353D03*
X123353Y1690482D03*
X140360Y424096D03*
X130701Y1363553D03*
X140353Y1649103D03*
X128353D03*
X127353Y1690603D03*
X132767Y1723257D03*
X150318Y210474D03*
Y218474D03*
X152232Y1381874D03*
X143500Y1442516D03*
X147000D03*
X148353Y1649103D03*
X144253D03*
X147253Y1690603D03*
X154740Y1707516D03*
X149900Y1712882D03*
Y1719882D03*
X159510Y1363924D03*
X163401Y1363553D03*
X159427Y1690603D03*
X167500Y1715516D03*
X162740Y1707516D03*
X184932Y1381874D03*
X181760Y1707404D03*
X185760Y1725892D03*
X189410Y390676D03*
X192210Y1364151D03*
X196301Y1363553D03*
X194000Y1715016D03*
X189760Y1707404D03*
X211000Y1712016D03*
X228675Y564125D03*
X225110Y1364151D03*
X229101Y1363553D03*
X217832Y1381874D03*
X236266Y62378D03*
X240266D03*
X244266D03*
X232817Y564093D03*
X239843Y712264D03*
X248266Y62378D03*
X251487Y104776D03*
X255270Y211986D03*
X255466Y645275D03*
X257910Y1364151D03*
X250632Y1381874D03*
X275797Y124059D03*
X269405Y582051D03*
X262466Y595169D03*
X263866Y587970D03*
X269061Y644465D03*
X272955Y653096D03*
X272932Y670417D03*
X262701Y1317407D03*
X261778Y1364141D03*
X279783Y124084D03*
X288597Y215535D03*
X288949Y246427D03*
X276801Y578594D03*
X288196Y679516D03*
X284232Y1335728D03*
X305266Y68123D03*
X301315Y95815D03*
X305315D03*
X293000Y219516D03*
X292949Y246427D03*
X292705Y582970D03*
X301791Y678706D03*
X305685Y687337D03*
X305662Y704658D03*
X295597Y1317379D03*
X291510Y1317805D03*
X310339Y228367D03*
X320966Y699666D03*
X317128Y1335700D03*
X325617Y73879D03*
X333988Y593820D03*
X334561Y698856D03*
X324557Y1317943D03*
X328501Y1317322D03*
X346695Y234071D03*
X342000Y277516D03*
X348157Y571356D03*
X338455Y707487D03*
X338432Y724808D03*
X350032Y1335643D03*
X352608Y276846D03*
X355828Y291906D03*
X354026Y699398D03*
X357310Y1317920D03*
X361301Y1317522D03*
X378184Y468867D03*
X375943Y534212D03*
X367621Y698588D03*
X371515Y707219D03*
X371492Y724540D03*
X386703Y123853D03*
X390859Y123900D03*
X387184Y473011D03*
X382184Y501617D03*
X392184D03*
X380771Y534154D03*
X387066Y699466D03*
X390110Y1318120D03*
X382832Y1335843D03*
X393883Y1336853D03*
X382992Y1674962D03*
X387324Y1675011D03*
X392324D03*
X407299Y206636D03*
X403299D03*
Y214587D03*
X407299D03*
X406184Y501617D03*
X397184D03*
X400673Y570869D03*
X400661Y698656D03*
X404555Y707287D03*
X404532Y724608D03*
X399000Y1624229D03*
X397324Y1675011D03*
X409000Y1677516D03*
X423299Y206636D03*
X415299D03*
X419299D03*
X415299Y214587D03*
X419984Y501540D03*
X410984D03*
X424784Y501463D03*
X420066Y681666D03*
X423926Y1029020D03*
X422692Y1337451D03*
X415414Y1355174D03*
X413000Y1677516D03*
X438673Y77216D03*
X433685Y91173D03*
X429685D03*
X429673Y77216D03*
X433673Y84216D03*
X438673D03*
X437997Y160641D03*
X433997D03*
X439299Y206636D03*
X435299D03*
X427299D03*
X431299D03*
Y214587D03*
X427299D03*
X435299D03*
X439500Y486516D03*
X433661Y680856D03*
X437555Y689487D03*
X437532Y706808D03*
X435146Y1029020D03*
X427666D03*
X431406D03*
X438886D03*
X426561Y1337435D03*
X428500Y1634016D03*
X442673Y84216D03*
X449997Y160641D03*
X445997D03*
X449997Y153641D03*
X445997D03*
X453997Y160641D03*
X443299Y206636D03*
X447299D03*
Y214587D03*
X443299D03*
X452466Y657066D03*
X450107Y1029020D03*
X442626D03*
X453847D03*
X446366D03*
X447576Y1644498D03*
X443594Y1644543D03*
X461997Y160641D03*
X469997D03*
X457931Y215194D03*
X465699Y285576D03*
X468500Y490016D03*
X466061Y656256D03*
X469955Y664887D03*
X469932Y682208D03*
X457587Y1029020D03*
X457000Y1644016D03*
X465000Y1647516D03*
X468500Y1711516D03*
X473997Y160641D03*
X481997D03*
X477997D03*
X484063Y308488D03*
X485066Y630566D03*
X498385Y108215D03*
X498661Y629756D03*
X502555Y638387D03*
X502532Y655708D03*
X528304Y211013D03*
X518500Y429516D03*
X522500D03*
X518366Y596466D03*
X531961Y595656D03*
X539503Y595432D03*
X543371Y595444D03*
X535855Y604287D03*
X535832Y621608D03*
X540106Y659816D03*
X550196Y184772D03*
X552699Y294576D03*
X573911Y214712D03*
X571063Y317488D03*
X568451Y1265034D03*
X564509Y1265030D03*
X586394Y90189D03*
X578454Y83155D03*
X577859Y214712D03*
X586500Y458016D03*
Y464516D03*
X583125Y751881D03*
X579125D03*
X587521Y751949D03*
X590501Y90189D03*
X602280D03*
X602328Y103586D03*
X590512D03*
X593758Y418721D03*
X603456Y751895D03*
X599489Y751881D03*
X595489D03*
X591521Y751949D03*
X618182Y90189D03*
X618256Y103586D03*
X608794Y191277D03*
X615385Y398669D03*
X607456Y751895D03*
X615443Y751907D03*
X611443D03*
X621310Y175625D03*
X630609Y227491D03*
X626705Y299821D03*
X631505Y286871D03*
X630195Y1386973D03*
X626295D03*
X634095D03*
X642301Y150067D03*
X638000Y415516D03*
X634244Y507554D03*
X646236Y1353453D03*
X638436D03*
X642436D03*
X656000Y518016D03*
Y510016D03*
X650036Y1353453D03*
X653836D03*
X657836D03*
X672800Y371878D03*
X676800D03*
X675500Y393378D03*
X666948Y398203D03*
X678071Y1308705D03*
X684643Y108901D03*
X680800Y371878D03*
X684800D03*
X693367Y363420D03*
X683500Y393378D03*
X679500D03*
X691500D03*
X699520Y363420D03*
X708500Y507878D03*
X704666Y507833D03*
X708509Y523861D03*
X704500Y524378D03*
X700500D03*
X708500Y540378D03*
X704500D03*
X696283Y540803D03*
X702645Y618627D03*
X698645D03*
X705657Y1381562D03*
X703799Y1627709D03*
X705688Y1647458D03*
X706623Y1663092D03*
X708953Y128184D03*
X719334Y363378D03*
X711458Y363376D03*
X716300Y376878D03*
X719500Y393378D03*
X723500D03*
X716500Y507878D03*
X720500D03*
X712500D03*
X712484Y523067D03*
X723032Y524331D03*
X719518Y524347D03*
X716016Y524441D03*
X710464Y549489D03*
X711845Y587733D03*
X711907Y603369D03*
X722129Y661183D03*
X718129D03*
X719152Y1627597D03*
X715309Y1677059D03*
X721909Y1681387D03*
X737093Y87993D03*
X737340Y115751D03*
X735449Y372044D03*
X731406Y376847D03*
X731500Y393378D03*
X727500D03*
X724500Y507878D03*
X737324Y524019D03*
X730310Y524299D03*
X733811Y524253D03*
X726793Y524365D03*
X724500Y540378D03*
X734557Y1381917D03*
X738439Y1381662D03*
X727188Y1399693D03*
X724723Y1627036D03*
X729616Y1677277D03*
X725632Y1677276D03*
X737467Y1680623D03*
X741270Y115675D03*
X739500Y376878D03*
X743500D03*
X748500Y540378D03*
X740500D03*
X751770Y1628299D03*
X752187Y1675010D03*
X741326Y1677073D03*
X745537Y1677158D03*
X745382Y1687286D03*
X760193Y93364D03*
X760500Y109516D03*
X759000Y363878D03*
X763500Y376878D03*
X767500Y393378D03*
X763500D03*
X760500Y540378D03*
X756500D03*
X767339Y1382017D03*
X759970Y1399793D03*
X758030Y1663099D03*
X772000Y524378D03*
X771216Y1382017D03*
X806500Y1327016D03*
X812526Y1345269D03*
X808526D03*
X831540Y62859D03*
X834616Y104297D03*
X835114Y117714D03*
X833715Y225084D03*
X831000Y508516D03*
X841900Y542313D03*
X834750Y566238D03*
X856630Y63009D03*
X850016Y90267D03*
X858783Y224499D03*
X863294Y266052D03*
X863571Y293901D03*
X867571D03*
X886503Y271423D03*
X925468Y264163D03*
X920268Y272375D03*
X922447Y1152591D03*
X949263Y274672D03*
X965442Y164901D03*
X969472Y1152591D03*
X985500Y152315D03*
X989605Y179569D03*
X985445Y179599D03*
X988835Y191969D03*
X988460Y363552D03*
X1005735Y157959D03*
X1001395Y218439D03*
X1004460Y363552D03*
X1000460D03*
X996460D03*
X992460D03*
X1009618Y399081D03*
X1020202Y538292D03*
X1007011Y550165D03*
X1034838Y538292D03*
X1030000Y557516D03*
X1035500D03*
X1050104Y1662400D03*
X1069236Y393973D03*
X1075526Y424480D03*
X1069839Y1363534D03*
X1092948Y476371D03*
X1091370Y1381855D03*
X1095489Y1696120D03*
X1094514Y1715932D03*
X1102439Y1363534D03*
X1098648Y1364132D03*
X1108747Y1535896D03*
X1109522Y1551449D03*
X1109000Y1665516D03*
X1098514Y1722932D03*
X1123970Y1381855D03*
X1114117Y1535896D03*
X1121010Y1588914D03*
X1125010D03*
X1115027Y1593267D03*
X1115394Y1622843D03*
X1112500Y1665516D03*
X1135139Y1363534D03*
X1131248Y1364132D03*
X1137846Y1456464D03*
X1133846D03*
X1132168Y1623481D03*
X1136097Y1623484D03*
X1166203Y74293D03*
X1163948Y1364132D03*
X1168039Y1363534D03*
X1156670Y1381855D03*
X1184000Y425941D03*
X1172000Y427516D03*
X1180000D03*
X1176000D03*
X1196848Y1364132D03*
X1189570Y1381855D03*
X1189407Y1712034D03*
X1200839Y1363534D03*
X1214254Y1713952D03*
Y1706952D03*
Y1727952D03*
Y1720952D03*
X1230312Y91151D03*
X1229648Y1364132D03*
X1222370Y1381855D03*
X1238830Y1317388D03*
X1233516Y1364122D03*
X1259472Y87380D03*
X1248859Y1420016D03*
X1252859D03*
X1253000Y1427016D03*
X1273677Y762004D03*
X1271726Y1317360D03*
X1267639Y1317786D03*
X1260361Y1335709D03*
X1275981Y87630D03*
X1284764Y92320D03*
X1280764D03*
X1288677Y759004D03*
X1277677Y762004D03*
X1281677D03*
X1296200Y61427D03*
X1292786Y545339D03*
X1298886Y593571D03*
X1292677Y762504D03*
X1296677D03*
X1300677Y759004D03*
X1300686Y1317924D03*
X1304630Y1317303D03*
X1293257Y1335681D03*
X1308110Y61427D03*
X1307366Y549729D03*
X1320020Y61495D03*
X1333399Y92600D03*
X1332360Y558711D03*
X1333439Y1317901D03*
X1326161Y1335624D03*
X1337399Y92600D03*
X1341399D03*
X1348199D03*
X1337430Y1317503D03*
X1356199Y92566D03*
X1352199D03*
X1360109D03*
X1350772Y674684D03*
X1358961Y1335824D03*
X1366018Y614609D03*
X1366239Y1318101D03*
X1370012Y1336834D03*
X1379613Y613799D03*
X1383507Y622430D03*
X1383484Y639751D03*
X1391543Y1355155D03*
X1398718Y647509D03*
X1403808Y1029019D03*
X1407548D03*
X1400068D03*
X1403690Y1286281D03*
X1398821Y1337432D03*
X1412313Y646699D03*
X1416207Y655330D03*
X1416184Y672651D03*
X1422508Y1029019D03*
X1415028D03*
X1411288D03*
X1418768D03*
X1419622Y1610283D03*
X1415623Y1599175D03*
X1438262Y55408D03*
X1434513Y109916D03*
X1439049Y116959D03*
X1431318Y680089D03*
X1429989Y1029019D03*
X1433729D03*
X1426249D03*
X1446869Y108377D03*
X1443049Y116959D03*
X1444769Y168733D03*
X1439769D03*
X1449769D03*
X1439769Y176733D03*
X1449769D03*
X1441741Y596382D03*
X1444913Y679279D03*
X1448807Y687910D03*
X1448784Y705231D03*
X1440500Y1617516D03*
X1445500D03*
X1449070Y1681238D03*
X1445079Y1681194D03*
X1454549Y116959D03*
X1460508Y136459D03*
X1454769Y168733D03*
X1464236Y699666D03*
X1461702Y1667904D03*
X1483820Y125774D03*
X1477831Y698856D03*
X1481725Y707487D03*
X1481702Y724808D03*
X1491560Y594553D03*
X1497318Y699666D03*
X1513644Y222191D03*
Y213341D03*
X1513348Y256554D03*
X1510913Y698856D03*
X1527853Y562780D03*
X1514807Y707487D03*
X1514784Y724808D03*
X1539693Y538129D03*
X1537853Y562780D03*
X1530118Y699666D03*
X1543713Y698856D03*
X1547607Y707487D03*
X1547584Y724808D03*
X1561345Y574714D03*
X1563248Y677726D03*
X1584079Y561624D03*
X1576843Y676916D03*
X1580737Y685547D03*
X1580714Y702868D03*
X1579177Y1262304D03*
X1596018Y643957D03*
X1605286Y547189D03*
X1609286D03*
X1609613Y643147D03*
X1613507Y651778D03*
X1613484Y669099D03*
X1625000Y386016D03*
X1629018Y624957D03*
X1621000Y1432516D03*
X1638334Y558303D03*
X1646507Y632778D03*
X1646484Y650099D03*
X1641804Y1308077D03*
X1636167Y1438994D03*
X1661928Y224688D03*
X1659610Y397218D03*
X1653790Y428560D03*
X1657545D03*
X1650035D03*
X1649979Y619062D03*
X1654147Y619014D03*
X1651959Y692763D03*
X1653390Y1380851D03*
X1649024Y1406737D03*
X1653024D03*
X1656824D03*
X1660624D03*
X1654513Y1708700D03*
X1658513Y1711850D03*
X1654513Y1715700D03*
Y1723850D03*
Y1730850D03*
X1663610Y397218D03*
X1674921Y1398982D03*
X1668424Y1406737D03*
X1664424D03*
X1689000Y228516D03*
X1688504Y401576D03*
X1690154Y428701D03*
X1682290Y1381206D03*
X1686172Y1380951D03*
X1681000Y1433516D03*
Y1440016D03*
X1684012Y1666257D03*
X1689513Y1708700D03*
Y1715700D03*
X1693000Y228516D03*
X1694314Y428671D03*
X1695529Y1545284D03*
X1716931Y75771D03*
X1711798Y75783D03*
Y62295D03*
X1716558D03*
X1721344Y62472D03*
X1713418Y125183D03*
X1710426Y407679D03*
X1715072Y1381306D03*
X1718949D03*
X1707703Y1399082D03*
X1726608Y105900D03*
X1730202Y1596109D03*
X1726202D03*
X1725423Y1687172D03*
X1735463Y1688981D03*
X1729436Y1687181D03*
X1728633Y1712206D03*
Y1720356D03*
X1732633Y1723506D03*
X1728633Y1727356D03*
X1750918Y125183D03*
X1751983Y258153D03*
X1737914Y1563223D03*
X1747963Y1644881D03*
X1740463Y1688981D03*
X1745463D03*
X1757322Y125187D03*
X1766606Y1563079D03*
X1760051Y1580348D03*
X1757963Y1647981D03*
X1752963Y1644881D03*
X1762963Y1647981D03*
X1767638Y69632D03*
X1767891Y97336D03*
X1771891D03*
X1773657Y1563723D03*
X1790738Y75003D03*
X1793444Y180660D03*
X1797011D03*
X1789811D03*
X1795794Y1580048D03*
X1800511Y180660D03*
X1804111D03*
X1807711D03*
X1811711Y177560D03*
X1802349Y1562779D03*
X1819705Y156888D03*
X1816308Y202045D03*
G54D34*
X53333Y527713D03*
G54D127*
X274301Y115216D03*
X707457Y119341D03*
X1749422Y116340D03*
G54D190*
X474070Y303156D03*
X561070Y312156D03*
G54D136*
X274913Y1019214D03*
X320189Y838505D03*
Y1199923D03*
X561133Y838505D03*
Y1199923D03*
X606409Y1019214D03*
X841240Y1420331D03*
X1016240D03*
X1251055Y1019213D03*
X1296331Y838504D03*
Y1199922D03*
X1537275Y838504D03*
Y1199922D03*
X1582551Y1019213D03*
G54D280*
X989227Y378999D03*
X986668D03*
Y401047D03*
X989227D03*
X1004582Y378999D03*
X1002023D03*
X999464D03*
X996905D03*
X994345D03*
X991786D03*
Y401047D03*
X994345D03*
X996905D03*
X999464D03*
X1002023D03*
X1004582D03*
X1438312Y134818D03*
Y156866D03*
X1453667Y134818D03*
X1451108D03*
X1448549D03*
X1445989D03*
X1443430D03*
X1440871D03*
Y156866D03*
X1443430D03*
X1445989D03*
X1448549D03*
X1451108D03*
X1453667D03*
X1456226Y134818D03*
Y156866D03*
G54D163*
X410379Y1569803D03*
X405379D03*
X400379D03*
Y1590275D03*
X405379D03*
X410379D03*
X415379Y1569803D03*
X425374D03*
X415379Y1590275D03*
X425374D03*
X440374Y1569803D03*
X435374D03*
X430374D03*
Y1590275D03*
X435374D03*
X440374D03*
X649284Y1658333D03*
X644284D03*
X639284D03*
Y1678805D03*
X644284D03*
X649284D03*
X654284Y1658333D03*
X662971Y1658547D03*
X654284Y1678805D03*
X662971Y1679019D03*
X677971Y1658547D03*
X672971D03*
X667971D03*
Y1679019D03*
X672971D03*
X677971D03*
X1169187Y1662159D03*
Y1682631D03*
X1184187Y1662159D03*
X1179187D03*
X1174187D03*
Y1682631D03*
X1179187D03*
X1184187D03*
X1661101Y1675927D03*
X1656101D03*
X1651101D03*
Y1696399D03*
X1656101D03*
X1661101D03*
X1666101Y1675927D03*
Y1696399D03*
G54D208*
X595203Y167856D03*
Y170415D03*
Y172975D03*
Y175534D03*
X612801D03*
Y172975D03*
Y170415D03*
Y167856D03*
G54D235*
X746517Y126419D03*
X757935D03*
G54D172*
X441043Y1698268D03*
X1416437D03*
G54D316*
X1787993Y194161D03*
Y196130D03*
Y198098D03*
X1806497Y194161D03*
Y200067D03*
Y198098D03*
Y196130D03*
Y202035D03*
G54D52*
X66229Y1542339D03*
X57370D03*
X59142D03*
X60914D03*
X62685D03*
X64457D03*
X73315D03*
X71544D03*
X69772D03*
X68000D03*
X94407Y151279D03*
X92438D03*
X90470D03*
X88501D03*
Y162303D03*
X90470D03*
X92438D03*
X94407D03*
X93113Y1542339D03*
X94885D03*
X96657D03*
X110081Y1376461D03*
X104766D03*
X108310D03*
X106538D03*
X111853D03*
X109058Y1542339D03*
X107287D03*
X105515D03*
X103743D03*
X101972D03*
X98428D03*
X100200D03*
X120711Y1376461D03*
X113625D03*
X117168D03*
X118940D03*
X115396D03*
X137366D03*
X140910D03*
X139138D03*
X153311D03*
X142681D03*
X146225D03*
X149768D03*
X144453D03*
X151540D03*
X147996D03*
X170066D03*
X186011D03*
X175381D03*
X178925D03*
X182468D03*
X173610D03*
X171838D03*
X177153D03*
X184240D03*
X180696D03*
X208281D03*
X202966D03*
X211825D03*
X215368D03*
X206510D03*
X204738D03*
X210053D03*
X213596D03*
X218911D03*
X217140D03*
X241081D03*
X235766D03*
X244625D03*
X239310D03*
X237538D03*
X242853D03*
X250345Y653656D03*
X252116D03*
X253888D03*
X255660D03*
X257431D03*
X259203D03*
X251711Y1376461D03*
X248168D03*
X249940D03*
X246396D03*
X266290Y653656D03*
X264518D03*
X262746D03*
X260975D03*
X274681Y1330315D03*
X269366D03*
X272910D03*
X271138D03*
X289206Y149291D03*
X287237D03*
X285269D03*
X283300D03*
Y160315D03*
X285269D03*
X287237D03*
X289206D03*
X283075Y687897D03*
X284846D03*
X286618D03*
X288390D03*
X290161D03*
X285311Y1330315D03*
X278225D03*
X281768D03*
X276453D03*
X283540D03*
X279996D03*
X299020Y687897D03*
X297248D03*
X295476D03*
X293705D03*
X291933D03*
X302262Y1330287D03*
X304034D03*
X315845Y708047D03*
X317616D03*
X319388D03*
X318207Y1330287D03*
X307577D03*
X311121D03*
X314664D03*
X305806D03*
X309349D03*
X316436D03*
X312892D03*
X321160Y708047D03*
X322931D03*
X331790D03*
X330018D03*
X328246D03*
X326475D03*
X324703D03*
X335166Y1330230D03*
X348905Y707779D03*
X340481Y1330230D03*
X344025D03*
X347568D03*
X338710D03*
X336938D03*
X342253D03*
X349340D03*
X345796D03*
X350676Y707779D03*
X352448D03*
X354220D03*
X355991D03*
X364850D03*
X363078D03*
X361306D03*
X359535D03*
X357763D03*
X351111Y1330230D03*
X373281Y1330430D03*
X367966D03*
X376825D03*
X371510D03*
X369738D03*
X375053D03*
X378596D03*
X381945Y707847D03*
X383716D03*
X385488D03*
X387260D03*
X389031D03*
X394346D03*
X392575D03*
X390803D03*
X383911Y1330430D03*
X380368D03*
X382140D03*
X397890Y707847D03*
X396118D03*
X405863Y1349761D03*
X400548D03*
X409407D03*
X404092D03*
X402320D03*
X407635D03*
X414945Y690047D03*
X416716D03*
X418488D03*
X420260D03*
X422031D03*
X423803D03*
X416493Y1349761D03*
X412950D03*
X414722D03*
X411178D03*
X430890Y690047D03*
X429118D03*
X427346D03*
X425575D03*
X447345Y665447D03*
X449116D03*
X450888D03*
X452660D03*
X454431D03*
X463290D03*
X461518D03*
X459746D03*
X457975D03*
X456203D03*
X479945Y638947D03*
X481716D03*
X483488D03*
X485260D03*
X487031D03*
X495890D03*
X494118D03*
X492346D03*
X490575D03*
X488803D03*
X513245Y604847D03*
X515016D03*
X516788D03*
X518560D03*
X520331D03*
X529190D03*
X527418D03*
X525646D03*
X523875D03*
X522103D03*
X613182Y219365D03*
X611213D03*
X609245D03*
X607276D03*
Y230389D03*
X609245D03*
X611213D03*
X613182D03*
X717637Y1394470D03*
X712322D03*
X721181D03*
X715866D03*
X714094D03*
X719409D03*
X722952D03*
X728267D03*
X724724D03*
X726496D03*
X750419Y1394570D03*
X745104D03*
X748648D03*
X746876D03*
X752191D03*
X761049D03*
X753963D03*
X757506D03*
X759278D03*
X755734D03*
X826467Y131386D03*
X824498D03*
X822530D03*
X820561D03*
Y142410D03*
X822530D03*
X824498D03*
X826467D03*
X850432Y208879D03*
X848463D03*
X846495D03*
X844526D03*
Y219903D03*
X846495D03*
X848463D03*
X850432D03*
X1076504Y1376442D03*
X1080048D03*
X1078276D03*
X1092449D03*
X1081819D03*
X1085363D03*
X1088906D03*
X1083591D03*
X1090678D03*
X1087134D03*
X1109104D03*
X1125049D03*
X1114419D03*
X1117963D03*
X1121506D03*
X1112648D03*
X1110876D03*
X1116191D03*
X1123278D03*
X1119734D03*
X1147119D03*
X1141804D03*
X1150663D03*
X1154206D03*
X1145348D03*
X1143576D03*
X1148891D03*
X1152434D03*
X1157749D03*
X1155978D03*
X1180019D03*
X1174704D03*
X1183563D03*
X1178248D03*
X1176476D03*
X1181791D03*
X1190649D03*
X1187106D03*
X1188878D03*
X1185334D03*
X1212819D03*
X1207504D03*
X1211048D03*
X1209276D03*
X1214591D03*
X1223449D03*
X1216363D03*
X1219906D03*
X1221678D03*
X1218134D03*
X1250810Y1330296D03*
X1245495D03*
X1254354D03*
X1257897D03*
X1249039D03*
X1247267D03*
X1252582D03*
X1259669D03*
X1256125D03*
X1261440D03*
X1282855Y401213D03*
X1280886D03*
X1278918D03*
X1276949D03*
Y412237D03*
X1278918D03*
X1280886D03*
X1282855D03*
X1283706Y1330268D03*
X1278391D03*
X1287250D03*
X1281935D03*
X1280163D03*
X1285478D03*
X1289021D03*
X1294336D03*
X1290793D03*
X1292565D03*
X1316610Y1330211D03*
X1311295D03*
X1314839D03*
X1313067D03*
X1318382D03*
X1327240D03*
X1320154D03*
X1323697D03*
X1325469D03*
X1321925D03*
X1344095Y1330411D03*
X1347639D03*
X1345867D03*
X1360897Y622990D03*
X1362668D03*
X1360040Y1330411D03*
X1349410D03*
X1352954D03*
X1356497D03*
X1351182D03*
X1358269D03*
X1354725D03*
X1364440Y622990D03*
X1366212D03*
X1367983D03*
X1376842D03*
X1375070D03*
X1373298D03*
X1371527D03*
X1369755D03*
X1376677Y1349742D03*
X1378449D03*
X1393597Y655890D03*
X1392622Y1349742D03*
X1381992D03*
X1385536D03*
X1389079D03*
X1380221D03*
X1383764D03*
X1390851D03*
X1387307D03*
X1395368Y655890D03*
X1397140D03*
X1398912D03*
X1400683D03*
X1407770D03*
X1405998D03*
X1404227D03*
X1402455D03*
X1409542D03*
X1426197Y688470D03*
X1427968D03*
X1429740D03*
X1431512D03*
X1433283D03*
X1438598D03*
X1436827D03*
X1435055D03*
X1442142D03*
X1440370D03*
X1459115Y708047D03*
X1460886D03*
X1462658D03*
X1464430D03*
X1466201D03*
X1467973D03*
X1475060D03*
X1473288D03*
X1471516D03*
X1469745D03*
X1492197Y708215D03*
X1493968D03*
X1495740D03*
X1497512D03*
X1499283D03*
X1508142D03*
X1506370D03*
X1504598D03*
X1502827D03*
X1501055D03*
X1524997Y708047D03*
X1526768D03*
X1528540D03*
X1530312D03*
X1532083D03*
X1540942D03*
X1539170D03*
X1537398D03*
X1535627D03*
X1533855D03*
X1557201Y294904D03*
X1555233D03*
X1553264D03*
Y305928D03*
X1555233D03*
X1557201D03*
X1559170Y294904D03*
Y305928D03*
X1558127Y686107D03*
X1559898D03*
X1561670D03*
X1563442D03*
X1565213D03*
X1572300D03*
X1570528D03*
X1568757D03*
X1566985D03*
X1574072D03*
X1590897Y652338D03*
X1592668D03*
X1594440D03*
X1596212D03*
X1597983D03*
X1601527D03*
X1599755D03*
X1606842D03*
X1605070D03*
X1603298D03*
X1623897Y633338D03*
X1625668D03*
X1627440D03*
X1629212D03*
X1630983D03*
X1639842D03*
X1638070D03*
X1636298D03*
X1634527D03*
X1632755D03*
X1660055Y1393759D03*
X1661827D03*
X1676000D03*
X1665370D03*
X1668914D03*
X1672457D03*
X1663599D03*
X1667142D03*
X1674229D03*
X1670685D03*
X1692026Y1680733D03*
X1690057D03*
X1686120D03*
X1688089D03*
X1686120Y1691757D03*
X1692026D03*
X1688089D03*
X1690057D03*
X1698152Y1393859D03*
X1692837D03*
X1701696D03*
X1705239D03*
X1696381D03*
X1694609D03*
X1699924D03*
X1707011D03*
X1703467D03*
X1708782D03*
X1735976Y364872D03*
X1734008D03*
X1732039D03*
Y375896D03*
X1734008D03*
X1735976D03*
X1737945Y364872D03*
Y375896D03*
X1744653Y1575375D03*
X1746425D03*
X1748197D03*
X1749968D03*
X1751740D03*
X1760598D03*
X1758827D03*
X1757055D03*
X1755283D03*
X1753512D03*
X1780396D03*
X1796341D03*
X1794570D03*
X1792798D03*
X1791026D03*
X1789255D03*
X1782168D03*
X1783940D03*
X1785711D03*
X1787483D03*
G54D109*
X190861Y120502D03*
X195979D03*
Y113022D03*
X193420D03*
X190861D03*
X203061Y120502D03*
X208179D03*
Y113022D03*
X205620D03*
X203061D03*
X409000Y1662260D03*
Y1669740D03*
X406441Y1662260D03*
Y1669740D03*
X411559Y1662260D03*
Y1669740D03*
X469975Y1720053D03*
Y1727533D03*
X467416Y1720053D03*
Y1727533D03*
X472534Y1720053D03*
Y1727533D03*
X1095489Y1703764D03*
Y1711244D03*
X1092930Y1703764D03*
Y1711244D03*
X1098048Y1703764D03*
Y1711244D03*
X1413622Y1625627D03*
X1418740D03*
X1416181D03*
X1418740Y1633107D03*
X1413622D03*
G54D244*
X776718Y1575473D03*
Y1589253D03*
X794436Y1575473D03*
Y1589253D03*
X818718Y1575473D03*
Y1589253D03*
X836436Y1575473D03*
Y1589253D03*
X860718Y1575473D03*
Y1589253D03*
X878436Y1575473D03*
Y1589253D03*
X902718Y1575473D03*
Y1589253D03*
X920436Y1575473D03*
Y1589253D03*
G54D226*
X721113Y651187D03*
Y646147D03*
X719145Y651187D03*
Y646147D03*
X1146221Y1558549D03*
Y1553509D03*
X1144253Y1558549D03*
Y1553509D03*
X1471975Y1676881D03*
Y1681921D03*
X1473943Y1676881D03*
Y1681921D03*
G54D145*
X313500Y247472D03*
X309760Y256528D03*
X317240D03*
X881000Y310972D03*
X877260Y320028D03*
X884740D03*
X1638500Y386972D03*
X1634760Y396028D03*
X1642240D03*
G54D271*
X928740Y321654D03*
G54D181*
X481156Y297251D03*
Y299219D03*
X474464Y297251D03*
X481156Y301187D03*
X474464D03*
X568156Y310187D03*
Y306251D03*
Y308219D03*
X561464Y306251D03*
Y310187D03*
G54D307*
X1653051Y414202D03*
G54D25*
X36882Y282916D03*
Y277798D03*
X35017Y288500D03*
X36882Y312916D03*
Y307798D03*
X31329Y517025D03*
X31613Y1497914D03*
Y1502214D03*
X35444Y1668587D03*
Y1663587D03*
X51017Y303500D03*
X44017D03*
X38150Y1622896D03*
Y1626896D03*
X59742Y268223D03*
X59872Y280357D03*
Y276357D03*
Y272357D03*
X64517Y290000D03*
X59872Y310357D03*
X65625Y423746D03*
X61713Y1552869D03*
X82118Y140950D03*
X74271Y157191D03*
Y161191D03*
Y165191D03*
X81891Y386502D03*
X81908Y376026D03*
X72150Y521613D03*
Y525513D03*
Y543213D03*
Y539313D03*
X78713Y1549369D03*
X87072Y1307499D03*
X87092Y1311619D03*
X96017Y1412500D03*
Y1408000D03*
Y1417000D03*
Y1421500D03*
Y1444500D03*
X87017Y1440000D03*
Y1444500D03*
X96017Y1448500D03*
X87017D03*
X95528Y1552796D03*
X84000Y1663138D03*
X83959Y1667127D03*
X85437Y1698511D03*
Y1702511D03*
X85274Y1724331D03*
Y1720331D03*
X101771Y153691D03*
Y158191D03*
X105982Y1385562D03*
X107017Y1414500D03*
X104610Y1597797D03*
X112870Y1670313D03*
Y1674313D03*
X114517Y1712450D03*
X141509Y526997D03*
X134994Y679290D03*
Y675290D03*
X127434Y1382305D03*
X138582Y1385562D03*
X129585Y1709346D03*
X136835Y1709166D03*
X139784Y1718241D03*
X145017Y1433500D03*
Y1429500D03*
Y1437500D03*
X149870Y1670087D03*
X143870Y1682587D03*
X168377Y400560D03*
X160134Y1382305D03*
X171282Y1385562D03*
X172017Y1715000D03*
X162832Y1726500D03*
X172017Y1721000D03*
X174617Y412350D03*
X192937Y144962D03*
X194017Y149000D03*
X194517Y156500D03*
X193034Y1382305D03*
X204182Y1385562D03*
X210590Y1419187D03*
X206017Y1707000D03*
X206332Y1723000D03*
X220997Y120662D03*
Y124662D03*
X222369Y148750D03*
X218017Y156500D03*
X224537Y206820D03*
X229150Y571129D03*
X225834Y1382305D03*
X242237Y71862D03*
X232803Y711602D03*
X236982Y1385562D03*
X247314Y111743D03*
X256678Y140882D03*
X259828Y144882D03*
X260227Y207660D03*
X247557Y224370D03*
X248144Y640909D03*
X271973Y74536D03*
X273784Y99183D03*
X267067Y142892D03*
X267070Y159203D03*
Y155203D03*
X270017Y215000D03*
X262017Y221500D03*
X267936Y611172D03*
X262108Y644555D03*
X271515Y676901D03*
X270582Y1339416D03*
X276917Y136962D03*
X277017Y207000D03*
Y211000D03*
X283808Y570398D03*
X276918Y585178D03*
X282374Y674150D03*
X295464Y75673D03*
X298183Y71128D03*
X296570Y156203D03*
Y151703D03*
X294838Y678796D03*
X304245Y711142D03*
X292330Y1336131D03*
X303478Y1339388D03*
X317074Y91803D03*
X316017Y263000D03*
X314160Y694525D03*
X322559Y69863D03*
X334431Y165170D03*
X325908Y545521D03*
X328746Y566086D03*
X327608Y698946D03*
X325234Y1336074D03*
X343233Y225070D03*
X339017Y285000D03*
X337015Y731292D03*
X336382Y1339331D03*
X363713Y130165D03*
X352432Y215325D03*
X365832Y211361D03*
Y219361D03*
X352450Y211407D03*
X365832Y215361D03*
X358017Y307500D03*
X356124Y550415D03*
X353674Y562415D03*
Y566415D03*
Y570415D03*
Y574415D03*
X364649Y617438D03*
X360668Y698678D03*
X358034Y1336274D03*
X370980Y158028D03*
X373562Y225145D03*
Y228645D03*
X374072Y243615D03*
X370075Y731024D03*
X369182Y1339531D03*
X371279Y1387697D03*
X386510Y142937D03*
X392813Y138980D03*
X381105Y280370D03*
Y294370D03*
X391517Y311500D03*
X394017Y304000D03*
X393708Y698746D03*
X395923Y134980D03*
X405658Y148300D03*
X399888Y551915D03*
X403115Y731092D03*
X401764Y1358862D03*
X404523Y1631219D03*
X409017Y1637000D03*
X406017Y1645500D03*
Y1653500D03*
X419510Y59935D03*
X419354Y71665D03*
Y66865D03*
X420318Y99148D03*
X416768Y104148D03*
X412658Y144300D03*
Y148300D03*
X414457Y235442D03*
X415232Y250165D03*
Y258165D03*
Y266165D03*
X415683Y1006123D03*
Y1009864D03*
X425133Y1014766D03*
X415683Y1013604D03*
Y1028564D03*
X425115Y1018879D03*
X415683Y1021084D03*
Y1024824D03*
Y1017344D03*
X425115Y1023013D03*
X414017Y1657500D03*
X426708Y680946D03*
X436115Y713292D03*
X434962Y1014745D03*
X434958Y1018879D03*
Y1023013D03*
X438517Y1604200D03*
Y1600200D03*
X449422Y270911D03*
X443816Y1014745D03*
X454052D03*
X443816Y1018879D03*
X454052D03*
X443816Y1023013D03*
X454052D03*
X442017Y1622700D03*
Y1618700D03*
X462745Y70016D03*
X465913Y239764D03*
Y227764D03*
Y231764D03*
Y247764D03*
X459108Y656346D03*
X468515Y688692D03*
X465017Y1668000D03*
Y1659500D03*
X470017Y1680000D03*
X465017Y1676000D03*
X465517Y1697000D03*
X472370Y60029D03*
X472300Y55135D03*
X472370Y64975D03*
X473642Y90574D03*
Y105574D03*
Y100574D03*
Y95574D03*
X473707Y119644D03*
Y115644D03*
X473642Y110574D03*
X473707Y123644D03*
X483270Y206827D03*
X473445Y284738D03*
Y280858D03*
X481982Y578572D03*
X472517Y1655500D03*
Y1672000D03*
Y1701000D03*
Y1706500D03*
Y1714500D03*
X490014Y171625D03*
X489199Y193516D03*
Y189516D03*
X497749Y193516D03*
Y185516D03*
Y189516D03*
X486201Y233000D03*
X494551Y238119D03*
X491708Y629846D03*
X506024Y185516D03*
X501293Y205285D03*
X508293Y202404D03*
X501115Y662192D03*
X526517Y432500D03*
X525008Y595746D03*
X541713Y195256D03*
X543505Y218441D03*
Y230441D03*
Y239566D03*
X536517Y445500D03*
X534415Y628092D03*
X544254Y663689D03*
X551353Y152742D03*
X556095Y193541D03*
X553190Y399586D03*
Y414274D03*
Y423949D03*
X550517Y451000D03*
X559017Y477500D03*
X571253Y235821D03*
X560445Y293738D03*
Y289858D03*
X560517Y451000D03*
X572017Y462000D03*
Y466000D03*
X570017Y471500D03*
Y475500D03*
X583720Y164356D03*
Y169415D03*
X575554Y193516D03*
X575569Y197481D03*
X578041Y261171D03*
X583140Y411846D03*
Y423949D03*
Y435949D03*
X583723Y454242D03*
X577017Y475500D03*
Y479500D03*
X600284Y136408D03*
X600287Y132270D03*
X600286Y141640D03*
X591040Y208991D03*
X591046Y221277D03*
Y217277D03*
Y225277D03*
Y229277D03*
X590327Y400287D03*
Y404287D03*
X603017Y412000D03*
X590644Y458461D03*
X590723Y454242D03*
X590520Y468893D03*
X590538Y479631D03*
X594017Y493500D03*
X600288Y1266598D03*
Y1262598D03*
X612017Y440000D03*
X620546Y221777D03*
Y226277D03*
X629938Y474020D03*
X627419Y1357114D03*
X619376Y1367166D03*
X619294Y1386732D03*
X646331Y166053D03*
Y161862D03*
X646383Y174201D03*
X646331Y170053D03*
X643178Y473905D03*
X648917Y1728000D03*
Y1717138D03*
X641917Y1728000D03*
Y1722138D03*
Y1717138D03*
X648917Y1722138D03*
X641917Y1733000D03*
X648917D03*
X652517Y390000D03*
X656457Y461818D03*
X656440Y457755D03*
X661472Y486941D03*
X650582D03*
X661334Y495126D03*
X655753Y1371199D03*
X655685Y1378931D03*
X655719Y1375061D03*
X653317Y1698400D03*
X662517Y1708184D03*
X653317Y1712084D03*
X672562Y401567D03*
Y409320D03*
Y405488D03*
X672517Y457862D03*
Y453862D03*
Y461862D03*
Y477862D03*
Y465862D03*
X672433Y474268D03*
X672517Y482862D03*
X666803Y504895D03*
X674803D03*
X665517Y529500D03*
X671117Y1308002D03*
X677810Y1639704D03*
Y1643904D03*
X680470Y115868D03*
X680294Y1530526D03*
Y1526526D03*
X706940Y103308D03*
X702157Y1560573D03*
X702127Y1580523D03*
X702017Y1608500D03*
Y1600500D03*
X702658Y1616656D03*
X696934Y1670408D03*
X696972Y1674429D03*
X696856Y1678474D03*
X710217Y157762D03*
X730010Y90998D03*
X730040Y95158D03*
X735172Y1400414D03*
X725378Y1614743D03*
X751650Y111288D03*
X745752Y142050D03*
X748217Y167537D03*
X752127Y1576023D03*
Y1589023D03*
Y1584023D03*
X757135Y89348D03*
X756784Y276322D03*
X763760Y299279D03*
X763167Y1591733D03*
X757179Y1693369D03*
X774806Y158026D03*
X774820Y153728D03*
X777560Y299279D03*
X779017Y371000D03*
Y364000D03*
X772017D03*
X775186Y419464D03*
X775169Y455344D03*
Y463344D03*
Y459344D03*
Y476344D03*
Y472344D03*
Y487344D03*
Y491344D03*
Y499344D03*
Y495344D03*
X788283Y267822D03*
Y281822D03*
X789619Y415344D03*
X789517Y407500D03*
X789669Y439344D03*
Y451344D03*
Y463344D03*
Y459344D03*
Y455344D03*
Y471344D03*
X789838Y467646D03*
X790179Y483458D03*
X790396Y479511D03*
X790017Y507000D03*
X792363Y1328662D03*
X805576Y386791D03*
X805583Y381020D03*
Y376753D03*
X798517Y392500D03*
X806592Y422687D03*
X806403Y431344D03*
X806319Y463578D03*
X806231Y449802D03*
X806450Y471344D03*
X806563Y476159D03*
X806450Y487344D03*
X806519Y491344D03*
X806563Y480159D03*
X806517Y504000D03*
X806636Y495344D03*
X806517Y512000D03*
Y516000D03*
X808517Y534500D03*
X808225Y541448D03*
X804381Y1340762D03*
Y1336334D03*
X799517Y1330000D03*
X804788Y1351988D03*
X807928Y1364193D03*
X804667Y1574633D03*
Y1590633D03*
Y1598633D03*
Y1606633D03*
X820936Y415344D03*
Y419344D03*
X827200Y405347D03*
X820928Y423099D03*
X820936Y455344D03*
X820875Y463578D03*
Y471344D03*
Y467568D03*
X827685Y497912D03*
X831479Y58632D03*
X828237Y166862D03*
Y176362D03*
X836017Y393000D03*
X832017Y471000D03*
X840718Y490567D03*
X840754Y486478D03*
X840717Y482128D03*
X840603Y494661D03*
X848837Y162762D03*
X856320Y269057D03*
X856350Y273217D03*
X856238Y384030D03*
X846274Y507106D03*
X853036Y494585D03*
X852842Y503154D03*
X853108Y498861D03*
X846667Y1574633D03*
Y1590633D03*
Y1598633D03*
Y1606633D03*
X871237Y166362D03*
X859017Y395500D03*
X868537Y418720D03*
X879237Y171362D03*
Y176862D03*
X881242Y187449D03*
X881232Y183169D03*
X883945Y267407D03*
X877932Y289439D03*
X885017Y326000D03*
X885999Y1056033D03*
X902298Y606915D03*
X888667Y1574633D03*
Y1590633D03*
Y1598633D03*
Y1606633D03*
X916973Y570706D03*
X930667Y1582233D03*
Y1578233D03*
Y1586233D03*
X945060Y585200D03*
X945748Y614150D03*
X944573Y628662D03*
X958142Y198171D03*
X958994Y1498695D03*
X981641Y189347D03*
X984972Y260781D03*
Y271443D03*
X984601Y295641D03*
X988573Y516014D03*
Y521014D03*
Y526074D03*
Y531074D03*
X982360Y1498695D03*
X994429Y221233D03*
Y225233D03*
X1000851Y446175D03*
Y457175D03*
Y451675D03*
Y462675D03*
Y468175D03*
Y479175D03*
Y473675D03*
Y494175D03*
Y490175D03*
Y484675D03*
Y499675D03*
X1005726Y1498695D03*
X1009827Y153868D03*
X1013737Y198999D03*
X1013712Y207423D03*
X1013637Y203099D03*
X1013712Y214423D03*
Y222423D03*
Y218423D03*
Y226423D03*
X1015351Y287311D03*
Y298311D03*
X1021476Y397726D03*
X1007219Y433426D03*
X1014074Y420902D03*
X1011281Y484155D03*
X1008723Y510304D03*
X1013017Y560500D03*
X1021517Y566000D03*
X1029092Y1498695D03*
X1042619Y1646205D03*
X1042487Y1652082D03*
X1055034Y406560D03*
X1065763Y445499D03*
X1065813Y457959D03*
X1065781Y453655D03*
Y449655D03*
X1065811Y462525D03*
Y467000D03*
Y471500D03*
X1055997Y490037D03*
X1065781Y479655D03*
X1057663Y1311203D03*
Y1307203D03*
X1052458Y1498695D03*
X1074727Y457959D03*
X1077720Y1385543D03*
X1075824Y1498695D03*
X1090455Y446105D03*
Y440605D03*
Y462605D03*
Y457105D03*
Y451605D03*
Y468105D03*
X1083455Y472105D03*
X1090455Y489641D03*
Y484605D03*
Y494641D03*
X1091356Y1633726D03*
X1091398Y1629945D03*
X1098965Y479355D03*
X1099172Y1382286D03*
X1110320Y1385543D03*
X1099190Y1498695D03*
X1099540Y1634400D03*
X1099733Y1630123D03*
X1099017Y1639000D03*
X1124426Y398020D03*
X1126750Y52651D03*
X1133923Y52599D03*
X1133155Y56512D03*
X1133422Y380533D03*
Y385698D03*
X1131872Y1382286D03*
X1147335Y74738D03*
X1152210Y204835D03*
Y209835D03*
X1144755Y489819D03*
X1143020Y1385543D03*
X1147400Y1436579D03*
X1157655Y461691D03*
Y457691D03*
Y449691D03*
Y453691D03*
Y465691D03*
Y469691D03*
Y481691D03*
X1169049Y580602D03*
X1169109Y584622D03*
X1164772Y1382286D03*
X1171946Y89556D03*
Y93556D03*
X1179708Y95864D03*
X1175920Y1385543D03*
X1181117Y1433000D03*
X1192804Y61515D03*
X1192904Y57015D03*
X1192824Y52815D03*
X1186005Y87125D03*
Y91125D03*
X1192219Y164987D03*
Y160987D03*
X1188444Y436202D03*
Y444202D03*
X1199944Y460202D03*
X1188444Y452202D03*
X1200004Y465272D03*
X1200080Y470376D03*
X1197632Y1382088D03*
X1197017Y1396500D03*
Y1401000D03*
Y1410000D03*
Y1405500D03*
Y1424000D03*
X1188117Y1428500D03*
Y1433000D03*
X1197017Y1437500D03*
Y1447500D03*
Y1442500D03*
X1189872Y1673050D03*
X1189554Y1697850D03*
X1196554D03*
X1210098Y94846D03*
X1202273Y133866D03*
Y128748D03*
X1202529Y177187D03*
Y181187D03*
X1202560Y188942D03*
X1208720Y1385543D03*
X1208017Y1401000D03*
X1205214Y1673059D03*
X1204896Y1697859D03*
X1211896D03*
X1241710Y145239D03*
X1236971Y447255D03*
Y443255D03*
X1241834Y1418462D03*
X1241876Y1422362D03*
X1258124Y155730D03*
Y164051D03*
Y160051D03*
Y176051D03*
Y180551D03*
Y168051D03*
Y172051D03*
Y185051D03*
X1254964Y464372D03*
X1245844Y468152D03*
X1256017Y765000D03*
X1246711Y1339397D03*
X1272628Y150030D03*
X1270566Y390884D03*
X1262517Y390500D03*
X1262719Y411125D03*
Y407125D03*
Y415125D03*
X1268459Y1336112D03*
X1286624Y162051D03*
Y166051D03*
Y171551D03*
Y184051D03*
X1279607Y1339369D03*
X1281617Y1430000D03*
Y1434000D03*
X1295210Y133739D03*
Y125739D03*
Y129739D03*
Y145739D03*
X1290219Y403625D03*
Y408125D03*
X1304159Y537299D03*
X1293273Y552147D03*
X1304275Y556545D03*
X1291883Y597013D03*
X1301363Y1336055D03*
X1312511Y1339312D03*
X1334163Y1336255D03*
X1343277Y674443D03*
X1345311Y1339512D03*
X1368201Y100509D03*
X1372660Y613889D03*
X1366923Y1355715D03*
X1377893Y1358843D03*
X1382067Y646235D03*
X1391825Y1009863D03*
Y1013603D03*
Y1006122D03*
Y1017343D03*
Y1028563D03*
Y1024823D03*
Y1021083D03*
X1389010Y1670391D03*
X1382010Y1674391D03*
X1384562Y1704038D03*
X1382321Y1733118D03*
X1396774Y642765D03*
X1405360Y646789D03*
X1401257Y1014744D03*
Y1018878D03*
Y1023012D03*
X1405150Y1622167D03*
X1398150Y1626167D03*
X1402000Y1630167D03*
X1414767Y679135D03*
X1419958Y1014744D03*
X1411104D03*
X1419958Y1023012D03*
X1411100Y1018878D03*
X1419958D03*
X1411100Y1023012D03*
X1423814Y1619504D03*
Y1613966D03*
X1418832Y1642967D03*
X1432136Y244450D03*
X1430774Y675765D03*
X1437960Y679369D03*
X1430194Y1014744D03*
Y1023012D03*
Y1018878D03*
X1432826Y1609966D03*
X1433014Y1619566D03*
X1445136Y244450D03*
X1447367Y711715D03*
X1464922Y61563D03*
X1455759Y128242D03*
X1466774Y548977D03*
Y552977D03*
Y544977D03*
X1458774Y564977D03*
X1466774Y556977D03*
Y560977D03*
Y564977D03*
X1462274Y695265D03*
X1471922Y61563D03*
X1470878Y698946D03*
X1480285Y731292D03*
X1510774Y543977D03*
X1503960Y698946D03*
X1513367Y731292D03*
X1523836Y201250D03*
X1539034Y300816D03*
Y308816D03*
Y304816D03*
X1536760Y698946D03*
X1546881Y284575D03*
X1546167Y731292D03*
X1547191Y1266271D03*
X1547194Y1282188D03*
Y1278188D03*
Y1286188D03*
X1566534Y297316D03*
Y301816D03*
X1570160Y531220D03*
X1569890Y677006D03*
X1562005Y1273445D03*
X1579297Y709352D03*
X1581789Y1302278D03*
X1595970Y225250D03*
X1602660Y643237D03*
X1615826Y530739D03*
X1610636Y542733D03*
X1612067Y675583D03*
X1622459Y282728D03*
Y278520D03*
X1622426Y286742D03*
X1629766Y1420450D03*
X1629684Y1444016D03*
Y1440016D03*
X1642705Y627206D03*
X1635660Y624237D03*
X1645067Y656583D03*
X1634850Y1306874D03*
X1638007Y1410398D03*
X1639684Y1442228D03*
X1655042Y141762D03*
Y146762D03*
Y151762D03*
Y161762D03*
X1656683Y696318D03*
X1666273Y1432215D03*
X1666307Y1428345D03*
X1666341Y1424483D03*
X1666359Y1420567D03*
X1682905Y1399703D03*
X1688168Y1559526D03*
Y1563526D03*
X1692044Y1696422D03*
X1701811Y373773D03*
Y369773D03*
X1699901Y401485D03*
X1722435Y112867D03*
X1714707Y364962D03*
X1709851Y666238D03*
Y662238D03*
X1736826Y85339D03*
X1730096Y1530950D03*
Y1535250D03*
X1735446Y1649456D03*
X1726980Y1663465D03*
Y1667965D03*
Y1658965D03*
Y1672465D03*
X1748905Y100307D03*
X1746127Y305106D03*
X1751237Y372452D03*
X1740014Y1435005D03*
X1748996Y1585905D03*
X1738980Y1653965D03*
X1760585Y76797D03*
X1760555Y72637D03*
X1753453Y85407D03*
X1765996Y1582405D03*
X1778592Y190799D03*
X1768445Y1666984D03*
X1768406Y1670514D03*
X1767980Y1685465D03*
X1768325Y1674057D03*
X1767980Y1681702D03*
Y1678172D03*
Y1689965D03*
X1787680Y70987D03*
X1782195Y92927D03*
X1789907Y146834D03*
Y151834D03*
Y165834D03*
X1792288Y367866D03*
X1784816Y403932D03*
X1792288Y390411D03*
X1784816Y410432D03*
Y418932D03*
Y425432D03*
X1782811Y1585832D03*
X1822097Y147834D03*
X1815097Y151834D03*
X1817249Y371329D03*
X1824249D03*
Y367359D03*
X1823186Y383952D03*
Y379552D03*
X1817086Y395552D03*
X1816316Y407932D03*
X1815816Y421432D03*
Y427432D03*
X1815809Y431678D03*
X1844808Y161834D03*
G54D118*
X230905Y1734212D03*
X297835D03*
X495078D03*
X562008D03*
X1238778D03*
X1305708D03*
X1502952D03*
X1569882D03*
G54D70*
X113065Y1311630D03*
Y1345094D03*
X145665Y1311630D03*
Y1345094D03*
X178165Y1311630D03*
Y1345094D03*
X210765Y1311630D03*
Y1345094D03*
X243365Y1311630D03*
Y1345094D03*
X257991Y685023D03*
Y718487D03*
X277665Y1265484D03*
Y1298948D03*
X290721Y719264D03*
Y752728D03*
X310561Y1265399D03*
Y1298863D03*
X323491Y739414D03*
Y772878D03*
X343465Y1265399D03*
Y1298863D03*
X356551Y739326D03*
Y772790D03*
X375961Y1265456D03*
Y1298920D03*
X389591Y739214D03*
Y772678D03*
X408847Y1284930D03*
Y1318394D03*
X425562Y721429D03*
Y754893D03*
X457090Y696814D03*
Y730278D03*
X489462Y670314D03*
Y703778D03*
X522062Y636214D03*
Y669678D03*
X1084803Y1311611D03*
Y1345075D03*
X1117403Y1311611D03*
Y1345075D03*
X1150103Y1311611D03*
Y1345075D03*
X1183003Y1311611D03*
Y1345075D03*
X1215803Y1311611D03*
Y1345075D03*
X1253794Y1265465D03*
Y1298929D03*
X1286690Y1265380D03*
Y1298844D03*
X1319594Y1265380D03*
Y1298844D03*
X1352090Y1265437D03*
Y1298901D03*
X1368861Y654359D03*
Y687823D03*
X1384976Y1284911D03*
Y1318375D03*
X1401243Y687257D03*
Y720721D03*
X1433843Y719837D03*
Y753301D03*
X1466761Y739414D03*
Y772878D03*
X1499843Y739414D03*
Y772878D03*
X1532643Y739414D03*
Y772878D03*
X1567114Y717474D03*
Y750938D03*
X1600244Y683705D03*
Y717169D03*
X1633043Y664705D03*
Y698169D03*
G54D217*
X676509Y145866D03*
X1859986Y1403418D03*
X1859706Y1709011D03*
X1866790Y463389D03*
X1871790Y476573D03*
X1861790D03*
X1870648Y783729D03*
X1860648D03*
X1865648Y796913D03*
X1867295Y837583D03*
X1862295Y850767D03*
X1872295D03*
X1871790Y1158071D03*
X1861790D03*
X1866790Y1171255D03*
X1864986Y1390234D03*
X1869986Y1403418D03*
X1869706Y1709011D03*
X1864706Y1722195D03*
X1886862Y94107D03*
X1881862Y107291D03*
X1882340Y410829D03*
X1887340Y424013D03*
X1887711Y463680D03*
X1882711Y476864D03*
X1882240Y783474D03*
X1887240Y796658D03*
X1888273Y837632D03*
X1883273Y850816D03*
X1882579Y1158348D03*
X1887579Y1171532D03*
X1886223Y1391283D03*
X1881223Y1404467D03*
X1881177Y1709323D03*
X1886177Y1722507D03*
X1891862Y107291D03*
X1892340Y410829D03*
X1892711Y476864D03*
X1892240Y783474D03*
X1893273Y850816D03*
X1892579Y1158348D03*
X1891223Y1404467D03*
X1891177Y1709323D03*
X2077012Y95128D03*
X2082012Y108312D03*
X2072012D03*
X2071128Y410829D03*
X2081128D03*
X2076128Y424013D03*
G54D43*
X60303Y20354D03*
X312921Y24291D03*
X326731Y663237D03*
X363731D03*
X443467Y594259D03*
X505185Y41141D03*
X754645Y1436735D03*
X757803Y45078D03*
X929331Y160413D03*
X922441Y237697D03*
X1077638Y133866D03*
X1166535Y1422322D03*
X1291146Y1385558D03*
X1320516D03*
X1425533Y601230D03*
X1487677Y649988D03*
X1524437Y650208D03*
X1534712Y20354D03*
X1701285Y208455D03*
X1700840Y1434362D03*
X1731660Y208455D03*
X1770442Y294777D03*
X1787330Y24291D03*
X1800002Y294777D03*
G54D262*
X876098Y1092807D03*
X897358D03*
X966577Y1092258D03*
X987837D03*
G54D154*
X366588Y283311D03*
X773766Y270763D03*
G54D61*
X77394Y734588D03*
Y1021399D03*
Y1277698D03*
X107095Y734588D03*
Y1021399D03*
Y1277698D03*
X136795Y734588D03*
Y1021399D03*
Y1277698D03*
X166496Y734588D03*
Y1021399D03*
Y1277698D03*
X196197Y734588D03*
Y1021399D03*
Y1277698D03*
X225898Y734588D03*
Y1021399D03*
Y1277698D03*
X655425Y734588D03*
Y1021399D03*
Y1277698D03*
X685126Y734588D03*
Y1021399D03*
Y1277698D03*
X714827Y734588D03*
Y1021399D03*
Y1277698D03*
X744528Y734588D03*
Y1021399D03*
Y1277698D03*
X774229Y734588D03*
Y1021399D03*
Y1277698D03*
X803929Y734588D03*
Y1021399D03*
Y1277698D03*
X1053536Y734587D03*
Y1021398D03*
Y1277697D03*
X1083237Y734587D03*
Y1021398D03*
Y1277697D03*
X1112937Y734587D03*
Y1021398D03*
Y1277697D03*
X1142638Y734587D03*
Y1021398D03*
Y1277697D03*
X1172339Y734587D03*
Y1021398D03*
Y1277697D03*
X1202040Y734587D03*
Y1021398D03*
Y1277697D03*
X1631567Y734587D03*
Y1021398D03*
Y1277697D03*
X1661268Y734587D03*
Y1021398D03*
Y1277697D03*
X1690969Y734587D03*
Y1021398D03*
Y1277697D03*
X1720670Y734587D03*
Y1021398D03*
Y1277697D03*
X1750371Y734587D03*
Y1021398D03*
Y1277697D03*
X1780071Y734587D03*
Y1021398D03*
Y1277697D03*
G54D253*
X804457Y1348236D03*
G54D17*
X17363Y233231D03*
X10543Y233275D03*
X36595Y388035D03*
X32774Y528853D03*
X46834Y366395D03*
X50631Y1533154D03*
X42150Y1553563D03*
X46150D03*
X45633Y1598379D03*
X50133D03*
X55190Y366395D03*
X64442Y507448D03*
X53299Y549778D03*
X63148Y549743D03*
X58365D03*
X59427Y1649870D03*
X66127Y1684870D03*
X76378Y1412138D03*
X72378D03*
X79323Y1533010D03*
X72768Y1550279D03*
X76806Y1599390D03*
X78406Y1607690D03*
X73427Y1649870D03*
X68427D03*
X82127Y1684870D03*
X86374Y1533654D03*
X90127Y1684870D03*
X92257Y1724314D03*
X98101Y1366520D03*
X108511Y1549979D03*
X115016Y297680D03*
Y318114D03*
X118407Y524274D03*
X126910Y1367118D03*
X119632Y1384841D03*
X115066Y1532710D03*
X120353Y1652070D03*
X124353D03*
X116353D03*
X123353Y1693449D03*
X140360Y427063D03*
X130701Y1366520D03*
X140353Y1652070D03*
X128353D03*
X127353Y1693570D03*
X132767Y1726224D03*
X150318Y213441D03*
Y221441D03*
X152232Y1384841D03*
X143500Y1445483D03*
X147000D03*
X148353Y1652070D03*
X144253D03*
X147253Y1693570D03*
X154740Y1710483D03*
X149900Y1715849D03*
Y1722849D03*
X159510Y1366891D03*
X163401Y1366520D03*
X159427Y1693570D03*
X162740Y1710483D03*
X167500Y1718483D03*
X184932Y1384841D03*
X181760Y1710371D03*
X185760Y1728859D03*
X189410Y393643D03*
X192210Y1367118D03*
X196301Y1366520D03*
X189760Y1710371D03*
X194000Y1717983D03*
X211000Y1714983D03*
X228675Y567092D03*
X225110Y1367118D03*
X229101Y1366520D03*
X217832Y1384841D03*
X236266Y65345D03*
X240266D03*
X244266D03*
X232817Y567060D03*
X239843Y715231D03*
X248266Y65345D03*
X251487Y107743D03*
X255270Y214953D03*
X255466Y648242D03*
X257910Y1367118D03*
X250632Y1384841D03*
X275797Y127026D03*
X262466Y598136D03*
X269405Y585018D03*
X263866Y590937D03*
X269061Y647432D03*
X272955Y656063D03*
X272932Y673384D03*
X262701Y1320374D03*
X261778Y1367108D03*
X279783Y127051D03*
X288597Y218502D03*
X288949Y249394D03*
X276801Y581561D03*
X288196Y682483D03*
X284232Y1338695D03*
X305266Y71090D03*
X301315Y98782D03*
X305315D03*
X293000Y222483D03*
X292949Y249394D03*
X292705Y585937D03*
X301791Y681673D03*
X305685Y690304D03*
X305662Y707625D03*
X295597Y1320346D03*
X291510Y1320772D03*
X310339Y231334D03*
X320966Y702633D03*
X317128Y1338667D03*
X325617Y76846D03*
X333988Y596787D03*
X334561Y701823D03*
X324557Y1320910D03*
X328501Y1320289D03*
X346695Y237038D03*
X342000Y280483D03*
X348157Y574323D03*
X338455Y710454D03*
X338432Y727775D03*
X350032Y1338610D03*
X352608Y279813D03*
X355828Y294873D03*
X354026Y702365D03*
X357310Y1320887D03*
X361301Y1320489D03*
X378184Y471834D03*
X375943Y537179D03*
X367621Y701555D03*
X371515Y710186D03*
X371492Y727507D03*
X386703Y126820D03*
X390859Y126867D03*
X387184Y475978D03*
X382184Y504584D03*
X392184D03*
X380771Y537121D03*
X387066Y702433D03*
X390110Y1321087D03*
X382832Y1338810D03*
X393883Y1339820D03*
X382992Y1677929D03*
X387324Y1677978D03*
X392324D03*
X407299Y209603D03*
X403299D03*
Y217554D03*
X407299D03*
X406184Y504584D03*
X397184D03*
X400673Y573836D03*
X400661Y701623D03*
X404555Y710254D03*
X404532Y727575D03*
X399000Y1627196D03*
X397324Y1677978D03*
X409000Y1680483D03*
X423299Y209603D03*
X415299D03*
X419299D03*
X415299Y217554D03*
X419984Y504507D03*
X410984D03*
X424784Y504430D03*
X420066Y684633D03*
X423926Y1031987D03*
X422692Y1340418D03*
X415414Y1358141D03*
X413000Y1680483D03*
X438673Y80183D03*
X429673D03*
X433673Y87183D03*
X438673D03*
X433685Y94140D03*
X429685D03*
X437997Y163608D03*
X433997D03*
X439299Y209603D03*
X435299D03*
X427299D03*
X431299D03*
Y217554D03*
X427299D03*
X435299D03*
X439500Y489483D03*
X433661Y683823D03*
X437555Y692454D03*
X437532Y709775D03*
X435146Y1031987D03*
X427666D03*
X431406D03*
X438886D03*
X426561Y1340402D03*
X428500Y1636983D03*
X442673Y87183D03*
X449997Y163608D03*
X445997D03*
X449997Y156608D03*
X445997D03*
X453997Y163608D03*
X443299Y209603D03*
X447299D03*
Y217554D03*
X443299D03*
X452466Y660033D03*
X450107Y1031987D03*
X442626D03*
X453847D03*
X446366D03*
X447576Y1647465D03*
X443594Y1647510D03*
X461997Y163608D03*
X469997D03*
X457931Y218161D03*
X465699Y288543D03*
X468500Y492983D03*
X466061Y659223D03*
X469955Y667854D03*
X469932Y685175D03*
X457587Y1031987D03*
X457000Y1646983D03*
X465000Y1650483D03*
X468500Y1714483D03*
X473997Y163608D03*
X481997D03*
X477997D03*
X484063Y311455D03*
X485066Y633533D03*
X498385Y111182D03*
X498661Y632723D03*
X502555Y641354D03*
X502532Y658675D03*
X528304Y213980D03*
X518500Y432483D03*
X522500D03*
X518366Y599433D03*
X531961Y598623D03*
X539503Y598399D03*
X543371Y598411D03*
X535855Y607254D03*
X535832Y624575D03*
X540106Y662783D03*
X550196Y187739D03*
X552699Y297543D03*
X573911Y217679D03*
X571063Y320455D03*
X568451Y1268001D03*
X564509Y1267997D03*
X578454Y86122D03*
X586394Y93156D03*
X577859Y217679D03*
X586500Y460983D03*
Y467483D03*
X583125Y754848D03*
X579125D03*
X587521Y754916D03*
X602328Y106553D03*
X590512D03*
X590501Y93156D03*
X602280D03*
X593758Y421688D03*
X603456Y754862D03*
X599489Y754848D03*
X595489D03*
X591521Y754916D03*
X618256Y106553D03*
X618182Y93156D03*
X608794Y194244D03*
X615385Y401636D03*
X607456Y754862D03*
X615443Y754874D03*
X611443D03*
X621310Y178592D03*
X630609Y230458D03*
X631505Y289838D03*
X626705Y302788D03*
X630195Y1389940D03*
X626295D03*
X634095D03*
X642301Y153034D03*
X638000Y418483D03*
X634244Y510521D03*
X646236Y1356420D03*
X638436D03*
X642436D03*
X656000Y520983D03*
Y512983D03*
X650036Y1356420D03*
X653836D03*
X657836D03*
X672800Y374845D03*
X676800D03*
X675500Y396345D03*
X666948Y401170D03*
X678071Y1311672D03*
X684643Y111868D03*
X680800Y374845D03*
X684800D03*
X693367Y366387D03*
X683500Y396345D03*
X679500D03*
X691500D03*
X699520Y366387D03*
X708500Y510845D03*
X704666Y510800D03*
X704500Y527345D03*
X700500D03*
X708509Y526828D03*
X708500Y543345D03*
X704500D03*
X696283Y543770D03*
X702645Y621594D03*
X698645D03*
X705657Y1384529D03*
X703799Y1630676D03*
X705688Y1650425D03*
X706623Y1666059D03*
X708953Y131151D03*
X719334Y366345D03*
X711458Y366343D03*
X716300Y379845D03*
X719500Y396345D03*
X723500D03*
X716500Y510845D03*
X720500D03*
X712500D03*
X723032Y527298D03*
X719518Y527314D03*
X712484Y526034D03*
X716016Y527408D03*
X710464Y552456D03*
X711845Y590700D03*
X711907Y606336D03*
X722129Y664150D03*
X718129D03*
X719152Y1630564D03*
X715309Y1680026D03*
X721909Y1684354D03*
X737093Y90960D03*
X737340Y118718D03*
X735449Y375011D03*
X731406Y379814D03*
X731500Y396345D03*
X727500D03*
X724500Y510845D03*
X730310Y527266D03*
X733811Y527220D03*
X726793Y527332D03*
X737324Y526986D03*
X724500Y543345D03*
X734557Y1384884D03*
X738439Y1384629D03*
X727188Y1402660D03*
X724723Y1630003D03*
X729616Y1680244D03*
X725632Y1680243D03*
X737467Y1683590D03*
X741270Y118642D03*
X739500Y379845D03*
X743500D03*
X748500Y543345D03*
X740500D03*
X751770Y1631266D03*
X752187Y1677977D03*
X741326Y1680040D03*
X745537Y1680125D03*
X745382Y1690253D03*
X760193Y96331D03*
X760500Y112483D03*
X759000Y366845D03*
X763500Y379845D03*
X767500Y396345D03*
X763500D03*
X760500Y543345D03*
X756500D03*
X767339Y1384984D03*
X759970Y1402760D03*
X758030Y1666066D03*
X772000Y527345D03*
X771216Y1384984D03*
X806500Y1329983D03*
X812526Y1348236D03*
X808526D03*
X831540Y65826D03*
X834616Y107264D03*
X835114Y120681D03*
X833715Y228051D03*
X831000Y511483D03*
X841900Y545280D03*
X834750Y569205D03*
X856630Y65976D03*
X850016Y93234D03*
X858783Y227466D03*
X863294Y269019D03*
X863571Y296868D03*
X867571D03*
X886503Y274390D03*
X925468Y267130D03*
X920268Y275342D03*
X922447Y1155558D03*
X949263Y277639D03*
X965442Y167868D03*
X969472Y1155558D03*
X985500Y155282D03*
X989605Y182536D03*
X988835Y194936D03*
X985445Y182566D03*
X988460Y366519D03*
X1005735Y160926D03*
X1001395Y221406D03*
X1004460Y366519D03*
X1000460D03*
X996460D03*
X992460D03*
X1009618Y402048D03*
X1020202Y541259D03*
X1007011Y553132D03*
X1034838Y541259D03*
X1030000Y560483D03*
X1035500D03*
X1050104Y1665367D03*
X1069236Y396940D03*
X1075526Y427447D03*
X1069839Y1366501D03*
X1092948Y479338D03*
X1091370Y1384822D03*
X1095489Y1699087D03*
X1094514Y1718899D03*
X1102439Y1366501D03*
X1098648Y1367099D03*
X1108747Y1538863D03*
X1109522Y1554416D03*
X1109000Y1668483D03*
X1098514Y1725899D03*
X1123970Y1384822D03*
X1114117Y1538863D03*
X1121010Y1591881D03*
X1125010D03*
X1115027Y1596234D03*
X1115394Y1625810D03*
X1112500Y1668483D03*
X1135139Y1366501D03*
X1131248Y1367099D03*
X1137846Y1459431D03*
X1133846D03*
X1132168Y1626448D03*
X1136097Y1626451D03*
X1166203Y77260D03*
X1163948Y1367099D03*
X1168039Y1366501D03*
X1156670Y1384822D03*
X1184000Y428908D03*
X1172000Y430483D03*
X1180000D03*
X1176000D03*
X1196848Y1367099D03*
X1189570Y1384822D03*
X1189407Y1715001D03*
X1200839Y1366501D03*
X1214254Y1709919D03*
Y1730919D03*
Y1723919D03*
Y1716919D03*
X1230312Y94118D03*
X1229648Y1367099D03*
X1222370Y1384822D03*
X1238830Y1320355D03*
X1233516Y1367089D03*
X1259472Y90347D03*
X1248859Y1422983D03*
X1252859D03*
X1253000Y1429983D03*
X1273677Y764971D03*
X1271726Y1320327D03*
X1267639Y1320753D03*
X1260361Y1338676D03*
X1275981Y90597D03*
X1284764Y95287D03*
X1280764D03*
X1288677Y761971D03*
X1277677Y764971D03*
X1281677D03*
X1296200Y64394D03*
X1292786Y548306D03*
X1298886Y596538D03*
X1300677Y761971D03*
X1292677Y765471D03*
X1296677D03*
X1300686Y1320891D03*
X1304630Y1320270D03*
X1293257Y1338648D03*
X1308110Y64394D03*
X1307366Y552696D03*
X1320020Y64462D03*
X1333399Y95567D03*
X1332360Y561678D03*
X1333439Y1320868D03*
X1326161Y1338591D03*
X1337399Y95567D03*
X1341399D03*
X1348199D03*
X1337430Y1320470D03*
X1356199Y95533D03*
X1352199D03*
X1360109D03*
X1350772Y677651D03*
X1358961Y1338791D03*
X1366018Y617576D03*
X1366239Y1321068D03*
X1370012Y1339801D03*
X1379613Y616766D03*
X1383507Y625397D03*
X1383484Y642718D03*
X1391543Y1358122D03*
X1398718Y650476D03*
X1403808Y1031986D03*
X1407548D03*
X1400068D03*
X1403690Y1289248D03*
X1398821Y1340399D03*
X1412313Y649666D03*
X1416207Y658297D03*
X1416184Y675618D03*
X1422508Y1031986D03*
X1415028D03*
X1411288D03*
X1418768D03*
X1415623Y1602142D03*
X1419622Y1613250D03*
X1438262Y58375D03*
X1434513Y112883D03*
X1439049Y119926D03*
X1431318Y683056D03*
X1429989Y1031986D03*
X1433729D03*
X1426249D03*
X1446869Y111344D03*
X1443049Y119926D03*
X1444769Y171700D03*
X1439769D03*
X1449769D03*
X1439769Y179700D03*
X1449769D03*
X1441741Y599349D03*
X1444913Y682246D03*
X1448807Y690877D03*
X1448784Y708198D03*
X1440500Y1620483D03*
X1445500D03*
X1449070Y1684205D03*
X1445079Y1684161D03*
X1454549Y119926D03*
X1460508Y139426D03*
X1454769Y171700D03*
X1464236Y702633D03*
X1461702Y1670871D03*
X1483820Y128741D03*
X1477831Y701823D03*
X1481725Y710454D03*
X1481702Y727775D03*
X1491560Y597520D03*
X1497318Y702633D03*
X1513644Y225158D03*
Y216308D03*
X1513348Y259521D03*
X1510913Y701823D03*
X1527853Y565747D03*
X1514807Y710454D03*
X1514784Y727775D03*
X1539693Y541096D03*
X1537853Y565747D03*
X1530118Y702633D03*
X1543713Y701823D03*
X1547607Y710454D03*
X1547584Y727775D03*
X1561345Y577681D03*
X1563248Y680693D03*
X1584079Y564591D03*
X1576843Y679883D03*
X1580737Y688514D03*
X1580714Y705835D03*
X1579177Y1265271D03*
X1596018Y646924D03*
X1605286Y550156D03*
X1609286D03*
X1609613Y646114D03*
X1613507Y654745D03*
X1613484Y672066D03*
X1625000Y388983D03*
X1629018Y627924D03*
X1621000Y1435483D03*
X1638334Y561270D03*
X1646507Y635745D03*
X1646484Y653066D03*
X1641804Y1311044D03*
X1636167Y1441961D03*
X1661928Y227655D03*
X1659610Y400185D03*
X1653790Y431527D03*
X1657545D03*
X1650035D03*
X1649979Y622029D03*
X1654147Y621981D03*
X1651959Y695730D03*
X1653390Y1383818D03*
X1649024Y1409704D03*
X1653024D03*
X1656824D03*
X1660624D03*
X1654513Y1711667D03*
X1658513Y1714817D03*
X1654513Y1726817D03*
Y1718667D03*
Y1733817D03*
X1663610Y400185D03*
X1674921Y1401949D03*
X1668424Y1409704D03*
X1664424D03*
X1689000Y231483D03*
X1688504Y404543D03*
X1690154Y431668D03*
X1682290Y1384173D03*
X1686172Y1383918D03*
X1681000Y1442983D03*
Y1436483D03*
X1684012Y1669224D03*
X1689513Y1711667D03*
Y1718667D03*
X1693000Y231483D03*
X1694314Y431638D03*
X1695529Y1548251D03*
X1711798Y65262D03*
X1716558D03*
X1721344Y65439D03*
X1716931Y78738D03*
X1711798Y78750D03*
X1713418Y128150D03*
X1710426Y410646D03*
X1715072Y1384273D03*
X1718949D03*
X1707703Y1402049D03*
X1726608Y108867D03*
X1730202Y1599076D03*
X1726202D03*
X1725423Y1690139D03*
X1735463Y1691948D03*
X1729436Y1690148D03*
X1728633Y1715173D03*
Y1723323D03*
X1732633Y1726473D03*
X1728633Y1730323D03*
X1750918Y128150D03*
X1751983Y261120D03*
X1737914Y1566190D03*
X1747963Y1647848D03*
X1740463Y1691948D03*
X1745463D03*
X1757322Y128154D03*
X1766606Y1566046D03*
X1760051Y1583315D03*
X1757963Y1650948D03*
X1752963Y1647848D03*
X1762963Y1650948D03*
X1767638Y72599D03*
X1767891Y100303D03*
X1771891D03*
X1773657Y1566690D03*
X1790738Y77970D03*
X1793444Y183627D03*
X1797011D03*
X1789811D03*
X1795794Y1583015D03*
X1811711Y180527D03*
X1800511Y183627D03*
X1804111D03*
X1807711D03*
X1802349Y1565746D03*
X1819705Y159855D03*
X1816308Y205012D03*
G54D164*
X418293Y1612725D03*
X1125516Y1646941D03*
G54D245*
X791280Y1704890D03*
X1066280D03*
G54D263*
X887519Y1528191D03*
G54D128*
X277098Y185236D03*
X395208D03*
G54D272*
X916889Y582573D03*
Y597073D03*
Y585132D03*
Y587692D03*
Y590251D03*
Y611573D03*
Y599632D03*
Y602192D03*
Y604751D03*
Y626073D03*
Y614132D03*
Y616692D03*
Y619251D03*
Y628632D03*
Y631192D03*
Y633751D03*
X931455Y582573D03*
Y597073D03*
Y590251D03*
Y587692D03*
Y585132D03*
Y611573D03*
Y604751D03*
Y602192D03*
Y599632D03*
Y626073D03*
Y619251D03*
Y616692D03*
Y614132D03*
Y633751D03*
Y631192D03*
Y628632D03*
G54D218*
X667552Y149803D03*
Y151771D03*
Y153740D03*
Y155708D03*
Y165551D03*
Y167519D03*
Y169488D03*
Y171456D03*
Y173425D03*
Y175393D03*
Y177362D03*
Y179330D03*
Y181299D03*
Y183268D03*
Y185236D03*
Y187204D03*
Y189173D03*
Y191142D03*
Y193110D03*
Y195079D03*
Y197047D03*
Y199016D03*
Y200984D03*
Y202953D03*
Y204921D03*
Y206890D03*
Y208858D03*
Y210827D03*
Y212795D03*
Y214764D03*
Y216732D03*
Y218701D03*
Y220669D03*
X697277Y148819D03*
Y150787D03*
Y152756D03*
Y154724D03*
Y156693D03*
Y166535D03*
Y168504D03*
Y170472D03*
Y172441D03*
Y174409D03*
Y176378D03*
Y178346D03*
Y180315D03*
Y182283D03*
Y184252D03*
Y186220D03*
Y188189D03*
Y190157D03*
Y192126D03*
Y194094D03*
Y196063D03*
Y198031D03*
Y200000D03*
Y201968D03*
Y203937D03*
Y205905D03*
Y207874D03*
Y209842D03*
Y211811D03*
Y213779D03*
Y215748D03*
Y217716D03*
Y219685D03*
Y221653D03*
G54D53*
X67668Y1559357D03*
X74668D03*
X125298Y1564553D03*
X118298D03*
X125348Y1557644D03*
X118348D03*
X165360Y414250D03*
X158360D03*
X185140Y413710D03*
X184959Y1559098D03*
X184933Y1565952D03*
X192140Y413710D03*
X201789Y591145D03*
Y599245D03*
X191959Y1559098D03*
X191933Y1565952D03*
X208789Y591145D03*
Y599245D03*
X253166Y67826D03*
X260166D03*
X251969Y78930D03*
X258969D03*
X359408Y274970D03*
X366408D03*
X554078Y199041D03*
X561078D03*
X673700Y1521200D03*
X666700D03*
X673633Y1536745D03*
X666633D03*
X673633Y1543599D03*
X666633D03*
X685720Y83362D03*
X692720D03*
X783673Y1355396D03*
Y1362296D03*
X781494Y1409557D03*
X774494D03*
X797969Y1357980D03*
X790673Y1355396D03*
Y1362296D03*
X804969Y1357980D03*
X855576Y234068D03*
X862576D03*
X901500Y1117787D03*
Y1110979D03*
Y1124595D03*
Y1131403D03*
X914700Y1116200D03*
Y1109200D03*
X908500Y1117787D03*
Y1110979D03*
X914700Y1123200D03*
X908500Y1124595D03*
Y1131403D03*
X914700Y1130200D03*
X921700Y1116200D03*
Y1109200D03*
Y1123200D03*
Y1130200D03*
X944500Y1116200D03*
Y1109200D03*
Y1130200D03*
Y1123200D03*
X960442Y175917D03*
X953442D03*
X958419Y1117534D03*
Y1110534D03*
X951500Y1116200D03*
Y1109200D03*
X958419Y1124534D03*
X958300Y1131403D03*
X951500Y1130200D03*
Y1123200D03*
X965419Y1117534D03*
Y1110534D03*
Y1124534D03*
X965300Y1131403D03*
X1037394Y1658146D03*
X1044394D03*
X1126250Y1606927D03*
X1122250Y1615727D03*
X1130250D03*
X1199806Y1598952D03*
X1192806D03*
X1199832Y1592098D03*
X1192832D03*
X1217193Y145739D03*
X1224193D03*
X1302077Y151217D03*
X1295077D03*
X1320014Y519675D03*
X1306766Y532113D03*
X1313766D03*
X1320014Y540375D03*
Y533475D03*
Y526575D03*
X1327014Y519675D03*
Y540375D03*
Y533475D03*
Y526575D03*
X1633139Y533130D03*
X1626139D03*
X1633139Y526230D03*
X1626139D03*
X1633139Y540030D03*
X1626139D03*
X1673258Y1411694D03*
X1674574Y1554200D03*
X1674507Y1576599D03*
Y1569745D03*
X1680258Y1411694D03*
X1681574Y1554200D03*
X1681507Y1576599D03*
Y1569745D03*
X1730096Y63051D03*
X1737096D03*
X1750642Y93075D03*
X1752067Y299637D03*
X1745067D03*
X1757642Y93075D03*
X1757279Y1597550D03*
X1764279D03*
X1757279Y1604950D03*
X1764279D03*
X1808013Y1598316D03*
X1801013D03*
X1808013Y1605816D03*
X1801013D03*
G54D137*
X285260Y227776D03*
Y237224D03*
X289000D03*
X292740Y227776D03*
Y237224D03*
X642394Y128047D03*
X638654D03*
X634914D03*
Y137495D03*
X642394D03*
X761510Y1641559D03*
X757770D03*
X754030D03*
X761510Y1651007D03*
X754030D03*
X844760Y476724D03*
X852240D03*
Y467276D03*
X848500D03*
X844760D03*
G54D146*
X334339Y171170D03*
X329221D03*
Y178610D03*
X331780D03*
X334339D03*
G54D44*
X61057Y64434D03*
Y62334D03*
X64657Y64434D03*
Y62334D03*
X72057Y70434D03*
Y68334D03*
X75657Y70434D03*
Y68334D03*
X86657Y64434D03*
Y62334D03*
X94057Y70434D03*
Y68334D03*
X83057Y64434D03*
Y62334D03*
X105057Y64434D03*
Y62334D03*
X108657Y64434D03*
Y62334D03*
X97657Y70434D03*
Y68334D03*
X127057Y64434D03*
Y62334D03*
X119657Y70434D03*
Y68334D03*
X116057Y70434D03*
Y68334D03*
X138057Y70434D03*
Y68334D03*
X130657Y64434D03*
Y62334D03*
X141657Y70434D03*
Y68334D03*
X152657Y64434D03*
Y62334D03*
X149057Y64434D03*
Y62334D03*
X164861Y70434D03*
Y68334D03*
X161261Y70434D03*
Y68334D03*
X169251Y1467595D03*
Y1469695D03*
X171433Y1521331D03*
Y1526631D03*
Y1528731D03*
Y1523431D03*
X159000Y1535950D03*
Y1532650D03*
Y1530550D03*
Y1538050D03*
Y1543450D03*
Y1541350D03*
X183261Y70434D03*
Y68334D03*
X175861Y64434D03*
Y62334D03*
X172261Y64434D03*
Y62334D03*
X175951Y1457895D03*
Y1459995D03*
X179551Y1457895D03*
Y1459995D03*
X172851Y1467595D03*
Y1469695D03*
X194261Y64434D03*
Y62334D03*
X197861Y64434D03*
Y62334D03*
X186861Y70434D03*
Y68334D03*
X189351Y1477295D03*
X192951D03*
X199651Y1467595D03*
Y1469695D03*
X196051Y1467595D03*
Y1469695D03*
X189351Y1479395D03*
X192951D03*
X200126Y1607286D03*
Y1609386D03*
X188066Y1607286D03*
Y1609386D03*
X191666Y1607286D03*
Y1609386D03*
X205395Y70434D03*
Y68334D03*
X216395Y64434D03*
Y62334D03*
X208995Y70434D03*
Y68334D03*
X206351Y1457895D03*
Y1459995D03*
X202751Y1457895D03*
Y1459995D03*
X216151Y1477295D03*
Y1479395D03*
X212186Y1607286D03*
Y1609386D03*
X215786Y1607286D03*
Y1609386D03*
X203726Y1607286D03*
Y1609386D03*
X230995Y70434D03*
Y68334D03*
X227395Y70434D03*
Y68334D03*
X219995Y64434D03*
Y62334D03*
X229551Y1457895D03*
Y1459995D03*
X219751Y1477295D03*
X222851Y1467595D03*
Y1469695D03*
X226451Y1467595D03*
Y1469695D03*
X219751Y1479395D03*
X224246Y1607286D03*
Y1609386D03*
X227846Y1607286D03*
Y1609386D03*
X233151Y1457895D03*
Y1459995D03*
X242951Y1477295D03*
Y1479395D03*
X236306Y1607286D03*
Y1609386D03*
X239906Y1607286D03*
Y1609386D03*
X256351Y1457895D03*
Y1459995D03*
X259951Y1457895D03*
Y1459995D03*
X249651Y1467595D03*
Y1469695D03*
X246551Y1477295D03*
X253251Y1467595D03*
Y1469695D03*
X246551Y1479395D03*
X254470Y1555340D03*
Y1553240D03*
X260426Y1607286D03*
Y1609386D03*
X248366Y1607286D03*
Y1609386D03*
X251966Y1607286D03*
Y1609386D03*
X273351Y1457895D03*
Y1459995D03*
X269751Y1457895D03*
Y1459995D03*
X271580Y1552250D03*
X268380Y1551550D03*
X271580Y1554350D03*
X261530Y1553220D03*
Y1555320D03*
X268380Y1558650D03*
Y1556550D03*
Y1553650D03*
X276086Y1607286D03*
Y1609386D03*
X272486Y1607286D03*
Y1609386D03*
X264026Y1607286D03*
Y1609386D03*
X283000Y1516750D03*
Y1518850D03*
X286200Y1516750D03*
Y1518850D03*
X283000Y1521750D03*
X286200D03*
X283000Y1523850D03*
X286200D03*
X284546Y1607286D03*
Y1609386D03*
X288146Y1607286D03*
Y1609386D03*
X304013Y1457895D03*
Y1459995D03*
X297313Y1467595D03*
Y1469695D03*
X300913Y1467595D03*
Y1469695D03*
X299495Y1521331D03*
Y1526631D03*
Y1528731D03*
Y1523431D03*
X303999Y1550788D03*
X300199Y1553688D03*
Y1555788D03*
X303999Y1552888D03*
Y1557888D03*
Y1555788D03*
X296606Y1607286D03*
Y1609386D03*
X300206Y1607286D03*
Y1609386D03*
X307613Y1457895D03*
Y1459995D03*
X317413Y1477295D03*
Y1479395D03*
X307199Y1550788D03*
X311476Y1557039D03*
Y1554939D03*
Y1562039D03*
Y1559939D03*
X307199Y1552888D03*
Y1557888D03*
Y1555788D03*
X320726Y1607286D03*
Y1609386D03*
X308666Y1607286D03*
Y1609386D03*
X312266Y1607286D03*
Y1609386D03*
X330813Y1457895D03*
Y1459995D03*
X334413Y1457895D03*
Y1459995D03*
X324113Y1467595D03*
Y1469695D03*
X321013Y1477295D03*
X327713Y1467595D03*
Y1469695D03*
X321013Y1479395D03*
X332786Y1607286D03*
Y1609386D03*
X324326Y1607286D03*
Y1609386D03*
X347813Y1477295D03*
X344213D03*
X347813Y1479395D03*
X344213D03*
X344846Y1607286D03*
Y1609386D03*
X348446Y1607286D03*
Y1609386D03*
X336386Y1607286D03*
Y1609386D03*
X361213Y1457895D03*
Y1459995D03*
X357613Y1457895D03*
Y1459995D03*
X350913Y1467595D03*
Y1469695D03*
X354513Y1467595D03*
Y1469695D03*
X356906Y1607286D03*
Y1609386D03*
X360506Y1607286D03*
Y1609386D03*
X377713Y1467595D03*
Y1469695D03*
X374613Y1477295D03*
X371013D03*
X374613Y1479395D03*
X371013D03*
X368966Y1607286D03*
Y1609386D03*
X372566Y1607286D03*
Y1609386D03*
X388013Y1457895D03*
Y1459995D03*
X384413Y1457895D03*
Y1459995D03*
X381313Y1467595D03*
Y1469695D03*
X390082Y1551550D03*
Y1553650D03*
Y1558650D03*
Y1556550D03*
X395009Y1587339D03*
Y1585239D03*
X384457Y1593936D03*
Y1591836D03*
X406243Y112951D03*
Y110851D03*
Y116351D03*
Y118451D03*
X409443Y126201D03*
Y124101D03*
Y129601D03*
Y131701D03*
X401413Y1457895D03*
Y1459995D03*
X397813Y1457895D03*
Y1459995D03*
X399642Y1551550D03*
X396442D03*
X404200Y1560750D03*
Y1562850D03*
X407600Y1560750D03*
Y1562850D03*
X399642Y1553650D03*
X396442Y1558650D03*
Y1556550D03*
Y1553650D03*
X402983Y1552879D03*
Y1554979D03*
X406086Y1552840D03*
Y1554940D03*
X411062Y1521750D03*
X414262D03*
X411062Y1516750D03*
Y1518850D03*
X414262Y1516750D03*
Y1518850D03*
X411062Y1523850D03*
X414262D03*
X411320Y1555250D03*
Y1553150D03*
X440124Y1457895D03*
Y1459995D03*
X433424Y1467595D03*
Y1469695D03*
X437024Y1467595D03*
Y1469695D03*
X435606Y1521331D03*
Y1526631D03*
Y1528731D03*
Y1523431D03*
X435513Y1531694D03*
Y1533794D03*
X426600Y1562070D03*
Y1564170D03*
X430000Y1562070D03*
Y1564170D03*
X429963Y1557147D03*
Y1559247D03*
X426850Y1557096D03*
Y1559196D03*
X443724Y1457895D03*
Y1459995D03*
X453524Y1477295D03*
Y1479395D03*
X443810Y1550788D03*
X440610D03*
X449597Y1557039D03*
Y1554939D03*
X443810Y1552888D03*
X446240Y1557908D03*
Y1555808D03*
X440610Y1552888D03*
X443040Y1557908D03*
Y1555808D03*
X450749Y1571104D03*
Y1573204D03*
X446218Y1590517D03*
Y1588417D03*
X452239Y1607286D03*
Y1609386D03*
X466924Y1457895D03*
Y1459995D03*
X463824Y1467595D03*
Y1469695D03*
X460224Y1467595D03*
Y1469695D03*
X457124Y1477295D03*
Y1479395D03*
X457317Y1557509D03*
Y1555409D03*
X464299Y1607286D03*
Y1609386D03*
X467899Y1607286D03*
Y1609386D03*
X455839Y1607286D03*
Y1609386D03*
X470524Y1457895D03*
Y1459995D03*
X483924Y1477295D03*
X480324D03*
X483924Y1479395D03*
X480324D03*
X476359Y1607286D03*
Y1609386D03*
X479959Y1607286D03*
Y1609386D03*
X493724Y1457895D03*
Y1459995D03*
X497324Y1457895D03*
Y1459995D03*
X487024Y1467595D03*
Y1469695D03*
X490624Y1467595D03*
Y1469695D03*
X488419Y1607286D03*
Y1609386D03*
X492019Y1607286D03*
Y1609386D03*
X513770Y105220D03*
Y107320D03*
D03*
Y109420D03*
X513824Y1467595D03*
Y1469695D03*
X510724Y1477295D03*
X507124D03*
X510724Y1479395D03*
X507124D03*
X512539Y1607286D03*
Y1609386D03*
X504079Y1607286D03*
Y1609386D03*
X500479Y1607286D03*
Y1609386D03*
X518270Y105220D03*
Y107320D03*
D03*
Y109420D03*
X520524Y1457895D03*
Y1459995D03*
X524124Y1457895D03*
Y1459995D03*
X517424Y1467595D03*
Y1469695D03*
X528470Y1551500D03*
X526193Y1558650D03*
Y1556550D03*
X528470Y1553600D03*
X528199Y1607286D03*
Y1609386D03*
X524599Y1607286D03*
Y1609386D03*
X516139Y1607286D03*
Y1609386D03*
X532920Y115280D03*
Y113180D03*
X537420Y115280D03*
Y113180D03*
Y111080D03*
Y113180D03*
X532920Y111080D03*
Y113180D03*
X537524Y1457895D03*
Y1459995D03*
X533924Y1457895D03*
Y1459995D03*
X544100Y1531540D03*
Y1533640D03*
X531580Y1551520D03*
X532553Y1558650D03*
Y1556550D03*
X531580Y1553620D03*
X540259Y1607286D03*
Y1609386D03*
X536659Y1607286D03*
Y1609386D03*
X547173Y1521750D03*
Y1516750D03*
Y1518850D03*
X550373Y1521750D03*
Y1516750D03*
Y1518850D03*
X547173Y1523850D03*
X550373D03*
X552319Y1607286D03*
Y1609386D03*
X548719Y1607286D03*
Y1609386D03*
X571786Y1457895D03*
Y1459995D03*
X568186Y1457895D03*
Y1459995D03*
X561486Y1467595D03*
Y1469695D03*
X565086Y1467595D03*
Y1469695D03*
X563668Y1521331D03*
Y1526631D03*
Y1528731D03*
Y1523431D03*
X571372Y1550788D03*
X568172D03*
X571372Y1552888D03*
Y1557888D03*
Y1555788D03*
X564372Y1553688D03*
Y1555788D03*
X568172Y1552888D03*
Y1557888D03*
Y1555788D03*
X572839Y1607286D03*
Y1609386D03*
X564379Y1607286D03*
Y1609386D03*
X560779Y1607286D03*
Y1609386D03*
X588286Y1467595D03*
Y1469695D03*
X585186Y1477295D03*
X581586D03*
X585186Y1479395D03*
X581586D03*
X575649Y1557039D03*
Y1554939D03*
Y1562039D03*
Y1559939D03*
X588499Y1607286D03*
Y1609386D03*
X584899Y1607286D03*
Y1609386D03*
X576439Y1607286D03*
Y1609386D03*
X594986Y1457895D03*
Y1459995D03*
X598586Y1457895D03*
Y1459995D03*
X591886Y1467595D03*
Y1469695D03*
X600559Y1607286D03*
Y1609386D03*
X596959Y1607286D03*
Y1609386D03*
X608386Y1477295D03*
X611986D03*
X618686Y1467595D03*
Y1469695D03*
X615086Y1467595D03*
Y1469695D03*
X608386Y1479395D03*
X611986D03*
X612619Y1607286D03*
Y1609386D03*
X609019Y1607286D03*
Y1609386D03*
X630147Y77961D03*
Y80061D03*
X633293Y77961D03*
Y80061D03*
X625386Y1457895D03*
Y1459995D03*
X621786Y1457895D03*
Y1459995D03*
X633139Y1607286D03*
Y1609386D03*
X624679Y1607286D03*
Y1609386D03*
X621079Y1607286D03*
Y1609386D03*
X648586Y1457895D03*
Y1459995D03*
X638786Y1477295D03*
X635186D03*
X645486Y1467595D03*
Y1469695D03*
X641886Y1467595D03*
Y1469695D03*
X638786Y1479395D03*
X635186D03*
X636739Y1607286D03*
Y1609386D03*
X639800Y1648750D03*
Y1650850D03*
X644549Y1648750D03*
Y1650850D03*
X661986Y1457895D03*
Y1459995D03*
X652186Y1457895D03*
Y1459995D03*
X660615Y1551550D03*
X654255D03*
X660615Y1558650D03*
Y1556550D03*
Y1553650D03*
X654255Y1558650D03*
Y1556550D03*
Y1553650D03*
X663439Y1640404D03*
X663003Y1649150D03*
Y1651250D03*
X663439Y1642504D03*
X665586Y1457895D03*
Y1459995D03*
X668206Y1505139D03*
Y1503039D03*
X663815Y1551550D03*
Y1553650D03*
X666729Y1640404D03*
X667985Y1649014D03*
Y1651114D03*
X666729Y1642504D03*
X1138331Y1565295D03*
X1137320Y1554012D03*
Y1556112D03*
X1138480Y1574096D03*
Y1571996D03*
X1138331Y1567395D03*
X1152186Y1565424D03*
X1146689Y1568275D03*
Y1570375D03*
X1142959Y1568294D03*
Y1570394D03*
X1152186Y1567524D03*
X1166873Y1565650D03*
Y1563550D03*
Y1576450D03*
Y1574350D03*
Y1568950D03*
Y1571050D03*
X1162615Y1591163D03*
Y1593263D03*
X1163688Y1661052D03*
Y1663152D03*
X1159688Y1661052D03*
Y1663152D03*
X1183824Y1490895D03*
X1177124Y1500595D03*
Y1502695D03*
X1180724Y1500595D03*
Y1502695D03*
X1183824Y1492995D03*
X1179306Y1559631D03*
Y1561731D03*
Y1556431D03*
Y1554331D03*
X1187424Y1490895D03*
Y1492995D03*
X1197224Y1510295D03*
Y1512395D03*
X1199539Y1640286D03*
X1195939D03*
X1199539Y1642386D03*
X1195939D03*
X1190334Y1666276D03*
Y1664176D03*
X1185676Y1692980D03*
Y1695080D03*
X1210624Y1490895D03*
X1214224D03*
X1203924Y1500595D03*
Y1502695D03*
X1210624Y1492995D03*
X1214224D03*
X1207524Y1500595D03*
Y1502695D03*
X1200824Y1510295D03*
Y1512395D03*
X1211599Y1640286D03*
X1207999D03*
X1211599Y1642386D03*
X1207999D03*
X1224024Y1510295D03*
Y1512395D03*
X1227624Y1510295D03*
Y1512395D03*
X1223659Y1640286D03*
X1220059D03*
X1223659Y1642386D03*
X1220059D03*
X1241024Y1490895D03*
X1237424D03*
X1241024Y1492995D03*
X1237424D03*
X1230724Y1500595D03*
Y1502695D03*
X1234324Y1500595D03*
Y1502695D03*
X1244179Y1640286D03*
X1235719D03*
X1232119D03*
X1244179Y1642386D03*
X1235719D03*
X1232119D03*
X1257524Y1500595D03*
Y1502695D03*
X1250824Y1510295D03*
Y1512395D03*
X1254424Y1510295D03*
Y1512395D03*
X1259839Y1640286D03*
X1256239D03*
X1247779D03*
X1259839Y1642386D03*
X1256239D03*
X1247779D03*
X1264224Y1490895D03*
X1267824D03*
X1264224Y1492995D03*
X1261124Y1500595D03*
Y1502695D03*
X1267824Y1492995D03*
X1262253Y1588300D03*
Y1586200D03*
X1269153Y1586410D03*
Y1588510D03*
X1271899Y1640286D03*
X1268299D03*
X1271899Y1642386D03*
X1268299D03*
X1277624Y1490895D03*
X1281224D03*
X1277624Y1492995D03*
X1281224D03*
X1276253Y1591650D03*
Y1589550D03*
Y1586650D03*
Y1584550D03*
X1279453Y1587350D03*
Y1585250D03*
X1283959Y1640286D03*
X1280359D03*
X1283959Y1642386D03*
X1280359D03*
X1290873Y1549750D03*
Y1551850D03*
X1294073Y1549750D03*
Y1551850D03*
X1290873Y1554750D03*
Y1556850D03*
X1294073Y1554750D03*
Y1556850D03*
X1304479Y1640286D03*
X1296019D03*
X1292419D03*
X1304479Y1642386D03*
X1296019D03*
X1292419D03*
X1311886Y1490895D03*
X1315486D03*
X1311886Y1492995D03*
X1305186Y1500595D03*
Y1502695D03*
X1308786Y1500595D03*
Y1502695D03*
X1315486Y1492995D03*
X1307368Y1559631D03*
Y1561731D03*
Y1556431D03*
Y1554331D03*
X1319349Y1590039D03*
Y1587939D03*
Y1595039D03*
Y1592939D03*
X1315072Y1585888D03*
Y1583788D03*
Y1590888D03*
Y1588788D03*
X1308072Y1586688D03*
Y1588788D03*
X1311872Y1585888D03*
Y1583788D03*
Y1590888D03*
Y1588788D03*
X1316539Y1640286D03*
X1308079D03*
X1316539Y1642386D03*
X1308079D03*
X1331986Y1500595D03*
Y1502695D03*
X1325286Y1510295D03*
Y1512395D03*
X1328886Y1510295D03*
Y1512395D03*
X1332199Y1640286D03*
X1328599D03*
X1320139D03*
X1332199Y1642386D03*
X1328599D03*
X1320139D03*
X1342286Y1490895D03*
X1338686D03*
X1335586Y1500595D03*
Y1502695D03*
X1342286Y1492995D03*
X1338686D03*
X1344259Y1640286D03*
X1340659D03*
X1344259Y1642386D03*
X1340659D03*
X1358786Y1500595D03*
Y1502695D03*
X1362386Y1500595D03*
Y1502695D03*
X1355686Y1510295D03*
Y1512395D03*
X1352086Y1510295D03*
Y1512395D03*
X1356319Y1640286D03*
X1352719D03*
X1356319Y1642386D03*
X1352719D03*
X1369086Y1490895D03*
X1365486D03*
X1369086Y1492995D03*
X1365486D03*
X1378886Y1510295D03*
Y1512395D03*
X1376839Y1640286D03*
X1368379D03*
X1364779D03*
X1376839Y1642386D03*
X1368379D03*
X1364779D03*
X1392286Y1490895D03*
X1385586Y1500595D03*
Y1502695D03*
X1392286Y1492995D03*
X1389186Y1500595D03*
Y1502695D03*
X1382486Y1510295D03*
Y1512395D03*
X1383800Y1604750D03*
Y1606850D03*
X1387000Y1604750D03*
Y1606850D03*
X1390200Y1604750D03*
Y1606850D03*
X1393400Y1604750D03*
Y1606850D03*
X1380439Y1640286D03*
Y1642386D03*
X1405686Y1490895D03*
X1395886D03*
X1405686Y1492995D03*
X1395886D03*
X1404315Y1591650D03*
Y1589550D03*
Y1586650D03*
Y1584550D03*
X1397955Y1591650D03*
Y1589550D03*
X1407515Y1586650D03*
Y1584550D03*
X1397955Y1586650D03*
Y1584550D03*
X1409286Y1490895D03*
Y1492995D03*
X1418935Y1549750D03*
Y1551850D03*
X1422135Y1549750D03*
Y1551850D03*
X1418935Y1554750D03*
Y1556850D03*
X1422135Y1554750D03*
Y1556850D03*
X1451598Y1490895D03*
X1447998D03*
X1441298Y1500595D03*
Y1502695D03*
X1444898Y1500595D03*
Y1502695D03*
X1451598Y1492995D03*
X1447998D03*
X1443480Y1559631D03*
Y1561731D03*
Y1556431D03*
Y1554331D03*
X1451184Y1585888D03*
Y1583788D03*
Y1590888D03*
Y1588788D03*
X1444184Y1586688D03*
Y1588788D03*
X1447984Y1585888D03*
Y1583788D03*
Y1590888D03*
Y1588788D03*
X1468098Y1500595D03*
Y1502695D03*
X1464998Y1510295D03*
Y1512395D03*
X1461398Y1510295D03*
Y1512395D03*
X1455461Y1590039D03*
Y1587939D03*
Y1595039D03*
Y1592939D03*
X1459713Y1631377D03*
Y1633477D03*
X1463313Y1631377D03*
Y1633477D03*
X1465500Y1668450D03*
Y1670550D03*
X1478398Y1490895D03*
X1474798D03*
X1478398Y1492995D03*
X1474798D03*
X1471698Y1500595D03*
Y1502695D03*
X1475773Y1640286D03*
X1472173D03*
X1475773Y1642386D03*
X1472173D03*
X1481000Y1684050D03*
Y1681950D03*
X1494898Y1500595D03*
Y1502695D03*
X1498498Y1500595D03*
Y1502695D03*
X1491798Y1510295D03*
Y1512395D03*
X1488198Y1510295D03*
Y1512395D03*
X1496293Y1640286D03*
X1487833D03*
X1484233D03*
X1496293Y1642386D03*
X1487833D03*
X1484233D03*
X1505198Y1490895D03*
X1501598D03*
X1505198Y1492995D03*
X1501598D03*
X1511953Y1640286D03*
X1508353D03*
X1499893D03*
X1511953Y1642386D03*
X1508353D03*
X1499893D03*
X1528398Y1490895D03*
Y1492995D03*
X1521698Y1500595D03*
Y1502695D03*
X1525298Y1500595D03*
Y1502695D03*
X1518598Y1510295D03*
Y1512395D03*
X1514998Y1510295D03*
Y1512395D03*
X1524013Y1640286D03*
X1520413D03*
X1524013Y1642386D03*
X1520413D03*
X1539062Y64437D03*
Y62337D03*
X1535462Y64437D03*
Y62337D03*
X1541798Y1490895D03*
X1531998D03*
X1541798Y1492995D03*
X1531998D03*
X1540427Y1591650D03*
Y1589550D03*
Y1586650D03*
Y1584550D03*
X1534067Y1591650D03*
Y1589550D03*
Y1586650D03*
Y1584550D03*
X1536073Y1640286D03*
X1532473D03*
X1536073Y1642386D03*
X1532473D03*
X1550062Y70437D03*
Y68337D03*
X1557462Y64437D03*
Y62337D03*
X1546462Y70437D03*
Y68337D03*
X1545398Y1490895D03*
Y1492995D03*
X1555047Y1549750D03*
Y1551850D03*
X1558247Y1549750D03*
Y1551850D03*
X1555047Y1554750D03*
Y1556850D03*
X1558247Y1554750D03*
Y1556850D03*
X1543627Y1587350D03*
Y1585250D03*
X1556593Y1640286D03*
X1548133D03*
X1544533D03*
X1556593Y1642386D03*
X1548133D03*
X1544533D03*
X1568462Y70437D03*
Y68337D03*
X1572062Y70437D03*
Y68337D03*
X1561062Y64437D03*
Y62337D03*
X1569360Y1500595D03*
Y1502695D03*
X1572960Y1500595D03*
Y1502695D03*
X1571542Y1559631D03*
Y1561731D03*
Y1556431D03*
Y1554331D03*
X1572246Y1586688D03*
Y1588788D03*
X1572253Y1640286D03*
X1568653D03*
X1560193D03*
X1572253Y1642386D03*
X1568653D03*
X1560193D03*
X1583062Y64437D03*
Y62337D03*
X1579462Y64437D03*
Y62337D03*
X1579660Y1490895D03*
X1576060D03*
X1579660Y1492995D03*
X1576060D03*
X1583523Y1590039D03*
Y1587939D03*
Y1595039D03*
Y1592939D03*
X1579246Y1585888D03*
Y1583788D03*
Y1590888D03*
Y1588788D03*
X1576046Y1585888D03*
Y1583788D03*
Y1590888D03*
Y1588788D03*
X1584313Y1640286D03*
X1580713D03*
X1584313Y1642386D03*
X1580713D03*
X1590462Y70437D03*
Y68337D03*
X1601462Y64437D03*
Y62337D03*
X1594062Y70437D03*
Y68337D03*
X1602860Y1490895D03*
Y1492995D03*
X1596160Y1500595D03*
Y1502695D03*
X1599760Y1500595D03*
Y1502695D03*
X1593060Y1510295D03*
Y1512395D03*
X1589460Y1510295D03*
Y1512395D03*
X1596373Y1640286D03*
X1592773D03*
X1596373Y1642386D03*
X1592773D03*
X1616062Y70437D03*
Y68337D03*
X1605062Y64437D03*
Y62337D03*
X1612462Y70437D03*
Y68337D03*
X1606460Y1490895D03*
Y1492995D03*
X1616260Y1510295D03*
Y1512395D03*
X1616893Y1640286D03*
X1608433D03*
X1604833D03*
X1616893Y1642386D03*
X1608433D03*
X1604833D03*
X1623462Y64437D03*
Y62337D03*
X1627062Y64437D03*
Y62337D03*
X1629660Y1490895D03*
Y1492995D03*
X1622960Y1500595D03*
Y1502695D03*
X1626560Y1500595D03*
Y1502695D03*
X1619860Y1510295D03*
Y1512395D03*
X1632553Y1640286D03*
X1628953D03*
X1620493D03*
X1632553Y1642386D03*
X1628953D03*
X1620493D03*
X1639266Y70437D03*
Y68337D03*
X1635666Y70437D03*
Y68337D03*
X1646666Y64437D03*
Y62337D03*
X1633260Y1490895D03*
Y1492995D03*
X1646660Y1510295D03*
Y1512395D03*
X1643060Y1510295D03*
Y1512395D03*
X1644613Y1640286D03*
X1641013D03*
X1644613Y1642386D03*
X1641013D03*
X1650266Y64437D03*
Y62337D03*
X1661266Y70437D03*
Y68337D03*
X1657666Y70437D03*
Y68337D03*
X1660060Y1490895D03*
X1656460D03*
X1649760Y1500595D03*
Y1502695D03*
X1653360Y1500595D03*
Y1502695D03*
X1660060Y1492995D03*
X1656460D03*
X1662129Y1591650D03*
Y1589550D03*
Y1586650D03*
Y1584550D03*
X1651146Y1667366D03*
Y1669466D03*
X1656136Y1667236D03*
Y1669336D03*
X1668666Y64437D03*
Y62337D03*
X1672266Y64437D03*
Y62337D03*
X1669860Y1490895D03*
X1673460D03*
X1669860Y1492995D03*
X1673460D03*
X1676345Y1535704D03*
Y1533604D03*
X1668489Y1591650D03*
Y1589550D03*
Y1586650D03*
Y1584550D03*
X1671689Y1586650D03*
Y1584550D03*
X1671400Y1665250D03*
Y1667350D03*
X1674600Y1658950D03*
Y1661050D03*
X1671400Y1658950D03*
Y1661050D03*
X1679800Y70437D03*
Y68337D03*
X1690800Y64437D03*
Y62337D03*
X1683400Y70437D03*
Y68337D03*
X1690650Y1579742D03*
Y1577642D03*
X1681000Y1658950D03*
Y1661050D03*
X1677800Y1658950D03*
Y1661050D03*
X1701800Y70437D03*
Y68337D03*
X1694400Y64437D03*
Y62337D03*
X1705400Y70437D03*
Y68337D03*
X1693850Y1579742D03*
Y1577642D03*
G54D254*
X829028Y491614D03*
Y486496D03*
X821588D03*
Y489055D03*
Y491614D03*
X931348Y267222D03*
Y272340D03*
X938788Y269781D03*
Y267222D03*
Y272340D03*
G54D317*
X1796261Y189732D03*
X1794292D03*
X1792324D03*
X1802166D03*
X1800198D03*
X1798229D03*
G54D209*
X600647Y772929D03*
G54D62*
X79740Y1418669D03*
X72260D03*
X76000Y1427331D03*
G54D35*
X50380Y520331D03*
X48412D03*
Y535095D03*
X50380D03*
X58254Y520331D03*
X56286D03*
X54317D03*
X52349D03*
Y535095D03*
X54317D03*
X56286D03*
X58254D03*
X411403Y1603375D03*
X413372D03*
X415340D03*
X417309D03*
X419277D03*
X421246D03*
X423214D03*
X411403Y1622075D03*
X413372D03*
X415340D03*
X417309D03*
X419277D03*
X421246D03*
X423214D03*
X425183Y1603375D03*
Y1622075D03*
X1124532Y1637591D03*
X1122563D03*
X1120595D03*
X1118626D03*
X1124532Y1656291D03*
X1122563D03*
X1120595D03*
X1118626D03*
X1132406Y1637591D03*
X1130437D03*
X1128469D03*
X1126500D03*
X1132406Y1656291D03*
X1130437D03*
X1128469D03*
X1126500D03*
G54D26*
X31099Y387783D03*
X24997D03*
X31099Y395067D03*
X24997D03*
X486949Y109959D03*
Y117243D03*
X493051D03*
Y109959D03*
G54D290*
X1124186Y1546733D03*
X1119067D03*
X1121626D03*
X1119067Y1565237D03*
X1121626D03*
X1124186D03*
X1126745Y1546733D03*
Y1565237D03*
G54D80*
X139770Y445819D03*
X154770D03*
X149770D03*
X144770D03*
X171550Y445279D03*
X166550D03*
X181550D03*
X176550D03*
X943902Y1505029D03*
X958902D03*
X953902D03*
X948902D03*
X977268D03*
X972268D03*
X967268D03*
X982268D03*
X990634D03*
X1005634D03*
X1000634D03*
X995634D03*
X1019000D03*
X1014000D03*
X1029000D03*
X1024000D03*
X1047366D03*
X1042366D03*
X1037366D03*
X1065732D03*
X1060732D03*
X1052366D03*
X1075732D03*
X1070732D03*
X1094098D03*
X1089098D03*
X1084098D03*
X1099098D03*
X1730571Y286855D03*
X1735571D03*
X1740571D03*
X1745571D03*
G54D227*
X720157Y1335285D03*
Y1361269D03*
X752939Y1335385D03*
Y1361369D03*
X1667890Y1334574D03*
Y1360558D03*
X1700672Y1334674D03*
Y1360658D03*
G54D308*
X1653642Y418139D03*
X1655610D03*
X1657578D03*
Y410265D03*
X1655610D03*
X1653642D03*
G54D191*
X475559Y1643260D03*
X473000D03*
X470441D03*
Y1650740D03*
X473000D03*
X475559D03*
X748441Y220240D03*
X751000D03*
Y212760D03*
X748441D03*
X753559Y220240D03*
Y212760D03*
X822559Y520760D03*
X820000D03*
X817441D03*
Y528240D03*
X820000D03*
X822559D03*
X1183354Y75185D03*
Y82665D03*
X1188472Y75185D03*
X1185913D03*
Y82665D03*
X1188472D03*
X1192612Y1677910D03*
X1195171D03*
X1192612Y1685390D03*
X1197730D03*
X1195171D03*
X1197730Y1677910D03*
X1207954Y1677919D03*
X1210513D03*
X1207954Y1685399D03*
X1213072D03*
X1210513D03*
X1213072Y1677919D03*
X1344958Y75369D03*
X1342399D03*
X1339840D03*
Y82849D03*
X1342399D03*
X1344958D03*
X1356868Y75335D03*
X1354309D03*
X1351750D03*
Y82815D03*
X1354309D03*
X1356868D03*
X1388918Y1682898D03*
X1383800D03*
X1386359D03*
X1388918Y1690378D03*
X1386359D03*
X1383800D03*
X1405058Y1642107D03*
X1402499D03*
X1405058Y1634627D03*
X1399940D03*
X1402499D03*
X1399940Y1642107D03*
X1426513Y1640469D03*
X1429072D03*
X1431631D03*
Y1632989D03*
X1429072D03*
X1426513D03*
G54D119*
X242215Y144320D03*
Y146879D03*
Y149438D03*
X242255Y155044D03*
Y157603D03*
Y160162D03*
X249695Y149438D03*
Y146879D03*
Y144320D03*
X249735Y160162D03*
Y157603D03*
Y155044D03*
X449760Y1632441D03*
Y1635000D03*
Y1637559D03*
X457240D03*
Y1635000D03*
Y1632441D03*
X573388Y415846D03*
Y413287D03*
Y410728D03*
X565908D03*
Y413287D03*
Y415846D03*
Y421390D03*
Y423949D03*
Y426508D03*
X573388D03*
Y423949D03*
Y421390D03*
X624760Y416441D03*
Y419000D03*
X632240D03*
Y416441D03*
X624760Y421559D03*
X632240D03*
X643785Y299730D03*
Y297171D03*
X636305D03*
Y299730D03*
X643785Y302289D03*
X636305D03*
X646984Y507479D03*
X639504D03*
X646984Y512597D03*
Y510038D03*
X639504D03*
Y512597D03*
X657173Y1727718D03*
Y1730277D03*
Y1717056D03*
Y1722174D03*
Y1719615D03*
Y1732836D03*
X664653Y1727718D03*
Y1730277D03*
Y1717056D03*
Y1719615D03*
Y1722174D03*
Y1732836D03*
X689781Y1640773D03*
Y1643332D03*
Y1645891D03*
X697261Y1640773D03*
Y1645891D03*
Y1643332D03*
X761245Y167518D03*
Y170077D03*
Y172636D03*
X768725D03*
Y170077D03*
Y167518D03*
X1005169Y268884D03*
X997689D03*
X1005169Y263340D03*
Y260781D03*
Y258222D03*
X997689D03*
Y260781D03*
Y263340D03*
X1005169Y274002D03*
Y271443D03*
X997689D03*
Y274002D03*
X1107021Y1718991D03*
Y1724109D03*
Y1721550D03*
X1114501Y1718991D03*
Y1721550D03*
Y1724109D03*
X1194267Y1712261D03*
Y1709702D03*
Y1707143D03*
X1194314Y1726261D03*
Y1723702D03*
Y1721143D03*
X1201747Y1712261D03*
Y1707143D03*
Y1709702D03*
X1201794Y1726261D03*
Y1721143D03*
Y1723702D03*
X1301705Y77748D03*
Y80307D03*
Y82866D03*
X1309185D03*
Y80307D03*
Y77748D03*
X1425569Y1596545D03*
X1433049D03*
X1425569Y1599104D03*
Y1601663D03*
X1433049D03*
Y1599104D03*
X1582927Y536344D03*
Y533785D03*
Y531226D03*
X1590407Y536344D03*
Y531226D03*
Y533785D03*
X1670500Y1714318D03*
Y1711759D03*
X1663020D03*
Y1714318D03*
X1670500Y1729468D03*
Y1726909D03*
X1663020D03*
Y1729468D03*
X1670500Y1716877D03*
X1663020D03*
X1670500Y1732027D03*
X1663020D03*
X1705500Y1714318D03*
Y1711759D03*
X1698020D03*
Y1714318D03*
X1705500Y1716877D03*
X1698020D03*
X1737140Y1708265D03*
Y1710824D03*
Y1713383D03*
Y1723415D03*
Y1725974D03*
Y1728533D03*
X1744620Y1713383D03*
Y1710824D03*
Y1708265D03*
Y1728533D03*
Y1725974D03*
Y1723415D03*
X1810045Y164393D03*
Y161834D03*
Y159275D03*
X1802565D03*
Y161834D03*
Y164393D03*
X1827636Y159275D03*
Y161834D03*
Y164393D03*
X1835116D03*
Y161834D03*
Y159275D03*
G54D173*
X453472Y489760D03*
Y497240D03*
X462528Y493500D03*
G54D155*
X366588Y288429D03*
X773766Y275881D03*
G54D281*
X999456Y193090D03*
G54D182*
X481550Y295282D03*
X568550Y304282D03*
G54D236*
X753500Y196547D03*
Y202453D03*
X1301710Y60741D03*
Y66647D03*
X1313620Y60741D03*
Y66647D03*
X1349350Y60741D03*
Y66647D03*
G54D71*
X113065Y1323736D03*
Y1332988D03*
X145665Y1323736D03*
Y1332988D03*
X178165Y1323736D03*
Y1332988D03*
X210765Y1323736D03*
Y1332988D03*
X243365Y1323736D03*
Y1332988D03*
X257991Y697129D03*
Y706381D03*
X277665Y1277590D03*
Y1286842D03*
X290721Y731370D03*
Y740622D03*
X310561Y1277505D03*
Y1286757D03*
X323491Y760772D03*
Y751520D03*
X343465Y1277505D03*
Y1286757D03*
X356551Y760684D03*
Y751432D03*
X375961Y1277562D03*
Y1286814D03*
X389591Y760572D03*
Y751320D03*
X408847Y1297036D03*
Y1306288D03*
X425562Y733535D03*
Y742787D03*
X457090Y718172D03*
Y708920D03*
X489462Y682420D03*
Y691672D03*
X522062Y657572D03*
Y648320D03*
X1084803Y1323717D03*
Y1332969D03*
X1117403Y1323717D03*
Y1332969D03*
X1150103Y1323717D03*
Y1332969D03*
X1183003Y1323717D03*
Y1332969D03*
X1215803Y1323717D03*
Y1332969D03*
X1253794Y1277571D03*
Y1286823D03*
X1286690Y1277486D03*
Y1286738D03*
X1319594Y1277486D03*
Y1286738D03*
X1352090Y1277543D03*
Y1286795D03*
X1368861Y666465D03*
Y675717D03*
X1384976Y1297017D03*
Y1306269D03*
X1401243Y699363D03*
Y708615D03*
X1433843Y731943D03*
Y741195D03*
X1466761Y760772D03*
Y751520D03*
X1499843Y760772D03*
Y751520D03*
X1532643Y760772D03*
Y751520D03*
X1567114Y729580D03*
Y738832D03*
X1600244Y695811D03*
Y705063D03*
X1633043Y686063D03*
Y676811D03*
G54D237*
X771220Y1482049D03*
G54D45*
X69323Y760178D03*
Y756832D03*
Y776911D03*
Y773564D03*
Y770218D03*
Y766871D03*
Y763525D03*
Y790297D03*
Y786950D03*
Y783604D03*
Y780257D03*
Y807029D03*
Y803682D03*
Y800336D03*
Y796989D03*
Y793643D03*
Y820415D03*
Y817068D03*
Y813722D03*
Y810375D03*
Y837147D03*
Y833800D03*
Y830454D03*
Y827108D03*
Y823761D03*
Y850533D03*
Y847186D03*
Y843840D03*
Y840493D03*
Y863919D03*
Y860572D03*
Y857226D03*
Y853879D03*
Y880651D03*
Y877304D03*
Y873958D03*
Y870611D03*
Y867265D03*
Y894037D03*
Y890690D03*
Y887344D03*
Y883997D03*
Y910769D03*
Y907423D03*
Y904076D03*
Y900730D03*
Y897383D03*
Y924155D03*
Y920808D03*
Y917462D03*
Y914115D03*
Y940887D03*
Y937541D03*
Y934194D03*
Y930848D03*
Y927501D03*
Y954273D03*
Y950926D03*
Y947580D03*
Y944234D03*
Y971005D03*
Y967659D03*
Y964312D03*
Y960966D03*
Y957619D03*
Y984391D03*
Y981045D03*
Y977698D03*
Y974352D03*
Y1001123D03*
Y997777D03*
Y994430D03*
Y991084D03*
Y987737D03*
Y1004470D03*
Y1027895D03*
Y1044627D03*
Y1041281D03*
Y1037934D03*
Y1034588D03*
Y1031241D03*
Y1058013D03*
Y1054667D03*
Y1051320D03*
Y1047974D03*
Y1074745D03*
Y1071399D03*
Y1068052D03*
Y1064706D03*
Y1061360D03*
Y1088131D03*
Y1084785D03*
Y1081438D03*
Y1078092D03*
Y1104863D03*
Y1101517D03*
Y1098171D03*
Y1094824D03*
Y1091478D03*
Y1118249D03*
Y1114903D03*
Y1111556D03*
Y1108210D03*
Y1134982D03*
Y1131635D03*
Y1128289D03*
Y1124942D03*
Y1121596D03*
Y1148367D03*
Y1145021D03*
Y1141675D03*
Y1138328D03*
Y1165100D03*
Y1161753D03*
Y1158407D03*
Y1155060D03*
Y1151714D03*
Y1178486D03*
Y1175139D03*
Y1171793D03*
Y1168446D03*
Y1191871D03*
Y1188525D03*
Y1185178D03*
Y1181832D03*
Y1208604D03*
Y1205257D03*
Y1201911D03*
Y1198564D03*
Y1195218D03*
Y1221989D03*
Y1218643D03*
Y1215297D03*
Y1211950D03*
Y1238722D03*
Y1235375D03*
Y1232029D03*
Y1228682D03*
Y1225336D03*
Y1252108D03*
Y1248761D03*
Y1245415D03*
Y1242068D03*
Y1255454D03*
X99024Y760178D03*
Y756832D03*
X85465Y760178D03*
Y756832D03*
X99024Y776911D03*
Y773564D03*
Y770218D03*
Y766871D03*
Y763525D03*
X85465Y776911D03*
Y773564D03*
Y770218D03*
Y766871D03*
Y763525D03*
X99024Y790297D03*
Y786950D03*
Y783604D03*
Y780257D03*
X85465Y790297D03*
Y786950D03*
Y783604D03*
Y780257D03*
X99024Y807029D03*
Y803682D03*
Y800336D03*
Y796989D03*
Y793643D03*
X85465Y807029D03*
Y803682D03*
Y800336D03*
Y796989D03*
Y793643D03*
X99024Y820415D03*
Y817068D03*
Y813722D03*
Y810375D03*
X85465Y820415D03*
Y817068D03*
Y813722D03*
Y810375D03*
X99024Y837147D03*
Y833800D03*
Y830454D03*
Y827108D03*
Y823761D03*
X85465Y837147D03*
Y833800D03*
Y830454D03*
Y827108D03*
Y823761D03*
X99024Y850533D03*
Y847186D03*
Y843840D03*
Y840493D03*
X85465Y850533D03*
Y847186D03*
Y843840D03*
Y840493D03*
X99024Y863919D03*
Y860572D03*
Y857226D03*
Y853879D03*
X85465Y863919D03*
Y860572D03*
Y857226D03*
Y853879D03*
X99024Y880651D03*
Y877304D03*
Y873958D03*
Y870611D03*
Y867265D03*
X85465Y880651D03*
Y877304D03*
Y873958D03*
Y870611D03*
Y867265D03*
X99024Y894037D03*
Y890690D03*
Y887344D03*
Y883997D03*
X85465Y894037D03*
Y890690D03*
Y887344D03*
Y883997D03*
X99024Y910769D03*
Y907423D03*
Y904076D03*
Y900730D03*
Y897383D03*
X85465Y910769D03*
Y907423D03*
Y904076D03*
Y900730D03*
Y897383D03*
X99024Y924155D03*
Y920808D03*
Y917462D03*
Y914115D03*
X85465Y924155D03*
Y920808D03*
Y917462D03*
Y914115D03*
X99024Y940887D03*
Y937541D03*
Y934194D03*
Y930848D03*
Y927501D03*
X85465Y940887D03*
Y937541D03*
Y934194D03*
Y930848D03*
Y927501D03*
X99024Y954273D03*
Y950926D03*
Y947580D03*
Y944234D03*
X85465Y954273D03*
Y950926D03*
Y947580D03*
Y944234D03*
X99024Y971005D03*
Y967659D03*
Y964312D03*
Y960966D03*
Y957619D03*
X85465Y971005D03*
Y967659D03*
Y964312D03*
Y960966D03*
Y957619D03*
X99024Y984391D03*
Y981045D03*
Y977698D03*
Y974352D03*
X85465Y984391D03*
Y981045D03*
Y977698D03*
Y974352D03*
X99024Y1001123D03*
Y997777D03*
Y994430D03*
Y991084D03*
Y987737D03*
X85465Y1001123D03*
Y997777D03*
Y994430D03*
Y991084D03*
Y987737D03*
X99024Y1004470D03*
X85465D03*
X99024Y1027895D03*
X85465D03*
X99024Y1044627D03*
Y1041281D03*
Y1037934D03*
Y1034588D03*
Y1031241D03*
X85465Y1044627D03*
Y1041281D03*
Y1037934D03*
Y1034588D03*
Y1031241D03*
X99024Y1058013D03*
Y1054667D03*
Y1051320D03*
Y1047974D03*
X85465Y1058013D03*
Y1054667D03*
Y1051320D03*
Y1047974D03*
X99024Y1074745D03*
Y1071399D03*
Y1068052D03*
Y1064706D03*
Y1061360D03*
X85465Y1074745D03*
Y1071399D03*
Y1068052D03*
Y1064706D03*
Y1061360D03*
X99024Y1088131D03*
Y1084785D03*
Y1081438D03*
Y1078092D03*
X85465Y1088131D03*
Y1084785D03*
Y1081438D03*
Y1078092D03*
X99024Y1104863D03*
Y1101517D03*
Y1098171D03*
Y1094824D03*
Y1091478D03*
X85465Y1104863D03*
Y1101517D03*
Y1098171D03*
Y1094824D03*
Y1091478D03*
X99024Y1118249D03*
Y1114903D03*
Y1111556D03*
Y1108210D03*
X85465Y1118249D03*
Y1114903D03*
Y1111556D03*
Y1108210D03*
X99024Y1134982D03*
Y1131635D03*
Y1128289D03*
Y1124942D03*
Y1121596D03*
X85465Y1134982D03*
Y1131635D03*
Y1128289D03*
Y1124942D03*
Y1121596D03*
X99024Y1148367D03*
Y1145021D03*
Y1141675D03*
Y1138328D03*
X85465Y1148367D03*
Y1145021D03*
Y1141675D03*
Y1138328D03*
X99024Y1165100D03*
Y1161753D03*
Y1158407D03*
Y1155060D03*
Y1151714D03*
X85465Y1165100D03*
Y1161753D03*
Y1158407D03*
Y1155060D03*
Y1151714D03*
X99024Y1178486D03*
Y1175139D03*
Y1171793D03*
Y1168446D03*
X85465Y1178486D03*
Y1175139D03*
Y1171793D03*
Y1168446D03*
X99024Y1191871D03*
Y1188525D03*
Y1185178D03*
Y1181832D03*
X85465Y1191871D03*
Y1188525D03*
Y1185178D03*
Y1181832D03*
X99024Y1208604D03*
Y1205257D03*
Y1201911D03*
Y1198564D03*
Y1195218D03*
X85465Y1208604D03*
Y1205257D03*
Y1201911D03*
Y1198564D03*
Y1195218D03*
X99024Y1221989D03*
Y1218643D03*
Y1215297D03*
Y1211950D03*
X85465Y1221989D03*
Y1218643D03*
Y1215297D03*
Y1211950D03*
X99024Y1238722D03*
Y1235375D03*
Y1232029D03*
Y1228682D03*
Y1225336D03*
X85465Y1238722D03*
Y1235375D03*
Y1232029D03*
Y1228682D03*
Y1225336D03*
X99024Y1252108D03*
Y1248761D03*
Y1245415D03*
Y1242068D03*
X85465Y1252108D03*
Y1248761D03*
Y1245415D03*
Y1242068D03*
X99024Y1255454D03*
X85465D03*
X128724Y760178D03*
Y756832D03*
X115166Y760178D03*
Y756832D03*
X128724Y776911D03*
Y773564D03*
Y770218D03*
Y766871D03*
Y763525D03*
X115166Y776911D03*
Y773564D03*
Y770218D03*
Y766871D03*
Y763525D03*
X128724Y790297D03*
Y786950D03*
Y783604D03*
Y780257D03*
X115166Y790297D03*
Y786950D03*
Y783604D03*
Y780257D03*
X128724Y807029D03*
Y803682D03*
Y800336D03*
Y796989D03*
Y793643D03*
X115166Y807029D03*
Y803682D03*
Y800336D03*
Y796989D03*
Y793643D03*
X128724Y820415D03*
Y817068D03*
Y813722D03*
Y810375D03*
X115166Y820415D03*
Y817068D03*
Y813722D03*
Y810375D03*
X128724Y837147D03*
Y833800D03*
Y830454D03*
Y827108D03*
Y823761D03*
X115166Y837147D03*
Y833800D03*
Y830454D03*
Y827108D03*
Y823761D03*
X128724Y850533D03*
Y847186D03*
Y843840D03*
Y840493D03*
X115166Y850533D03*
Y847186D03*
Y843840D03*
Y840493D03*
X128724Y863919D03*
Y860572D03*
Y857226D03*
Y853879D03*
X115166Y863919D03*
Y860572D03*
Y857226D03*
Y853879D03*
X128724Y880651D03*
Y877304D03*
Y873958D03*
Y870611D03*
Y867265D03*
X115166Y880651D03*
Y877304D03*
Y873958D03*
Y870611D03*
Y867265D03*
X128724Y894037D03*
Y890690D03*
Y887344D03*
Y883997D03*
X115166Y894037D03*
Y890690D03*
Y887344D03*
Y883997D03*
X128724Y910769D03*
Y907423D03*
Y904076D03*
Y900730D03*
Y897383D03*
X115166Y910769D03*
Y907423D03*
Y904076D03*
Y900730D03*
Y897383D03*
X128724Y924155D03*
Y920808D03*
Y917462D03*
Y914115D03*
X115166Y924155D03*
Y920808D03*
Y917462D03*
Y914115D03*
X128724Y940887D03*
Y937541D03*
Y934194D03*
Y930848D03*
Y927501D03*
X115166Y940887D03*
Y937541D03*
Y934194D03*
Y930848D03*
Y927501D03*
X128724Y954273D03*
Y950926D03*
Y947580D03*
Y944234D03*
X115166Y954273D03*
Y950926D03*
Y947580D03*
Y944234D03*
X128724Y971005D03*
Y967659D03*
Y964312D03*
Y960966D03*
Y957619D03*
X115166Y971005D03*
Y967659D03*
Y964312D03*
Y960966D03*
Y957619D03*
X128724Y984391D03*
Y981045D03*
Y977698D03*
Y974352D03*
X115166Y984391D03*
Y981045D03*
Y977698D03*
Y974352D03*
X128724Y1001123D03*
Y997777D03*
Y994430D03*
Y991084D03*
Y987737D03*
X115166Y1001123D03*
Y997777D03*
Y994430D03*
Y991084D03*
Y987737D03*
X128724Y1004470D03*
X115166D03*
X128724Y1027895D03*
X115166D03*
X128724Y1044627D03*
Y1041281D03*
Y1037934D03*
Y1034588D03*
Y1031241D03*
X115166Y1044627D03*
Y1041281D03*
Y1037934D03*
Y1034588D03*
Y1031241D03*
X128724Y1058013D03*
Y1054667D03*
Y1051320D03*
Y1047974D03*
X115166Y1058013D03*
Y1054667D03*
Y1051320D03*
Y1047974D03*
X128724Y1074745D03*
Y1071399D03*
Y1068052D03*
Y1064706D03*
Y1061360D03*
X115166Y1074745D03*
Y1071399D03*
Y1068052D03*
Y1064706D03*
Y1061360D03*
X128724Y1088131D03*
Y1084785D03*
Y1081438D03*
Y1078092D03*
X115166Y1088131D03*
Y1084785D03*
Y1081438D03*
Y1078092D03*
X128724Y1104863D03*
Y1101517D03*
Y1098171D03*
Y1094824D03*
Y1091478D03*
X115166Y1104863D03*
Y1101517D03*
Y1098171D03*
Y1094824D03*
Y1091478D03*
X128724Y1118249D03*
Y1114903D03*
Y1111556D03*
Y1108210D03*
X115166Y1118249D03*
Y1114903D03*
Y1111556D03*
Y1108210D03*
X128724Y1134982D03*
Y1131635D03*
Y1128289D03*
Y1124942D03*
Y1121596D03*
X115166Y1134982D03*
Y1131635D03*
Y1128289D03*
Y1124942D03*
Y1121596D03*
X128724Y1148367D03*
Y1145021D03*
Y1141675D03*
Y1138328D03*
X115166Y1148367D03*
Y1145021D03*
Y1141675D03*
Y1138328D03*
X128724Y1165100D03*
Y1161753D03*
Y1158407D03*
Y1155060D03*
Y1151714D03*
X115166Y1165100D03*
Y1161753D03*
Y1158407D03*
Y1155060D03*
Y1151714D03*
X128724Y1178486D03*
Y1175139D03*
Y1171793D03*
Y1168446D03*
X115166Y1178486D03*
Y1175139D03*
Y1171793D03*
Y1168446D03*
X128724Y1191871D03*
Y1188525D03*
Y1185178D03*
Y1181832D03*
X115166Y1191871D03*
Y1188525D03*
Y1185178D03*
Y1181832D03*
X128724Y1208604D03*
Y1205257D03*
Y1201911D03*
Y1198564D03*
Y1195218D03*
X115166Y1208604D03*
Y1205257D03*
Y1201911D03*
Y1198564D03*
Y1195218D03*
X128724Y1221989D03*
Y1218643D03*
Y1215297D03*
Y1211950D03*
X115166Y1221989D03*
Y1218643D03*
Y1215297D03*
Y1211950D03*
X128724Y1238722D03*
Y1235375D03*
Y1232029D03*
Y1228682D03*
Y1225336D03*
X115166Y1238722D03*
Y1235375D03*
Y1232029D03*
Y1228682D03*
Y1225336D03*
X128724Y1252108D03*
Y1248761D03*
Y1245415D03*
Y1242068D03*
X115166Y1252108D03*
Y1248761D03*
Y1245415D03*
Y1242068D03*
X128724Y1255454D03*
X115166D03*
X158425Y760178D03*
Y756832D03*
X144866Y760178D03*
Y756832D03*
X158425Y776911D03*
Y773564D03*
Y770218D03*
Y766871D03*
Y763525D03*
X144866Y776911D03*
Y773564D03*
Y770218D03*
Y766871D03*
Y763525D03*
X158425Y790297D03*
Y786950D03*
Y783604D03*
Y780257D03*
X144866Y790297D03*
Y786950D03*
Y783604D03*
Y780257D03*
X158425Y807029D03*
Y803682D03*
Y800336D03*
Y796989D03*
Y793643D03*
X144866Y807029D03*
Y803682D03*
Y800336D03*
Y796989D03*
Y793643D03*
X158425Y820415D03*
Y817068D03*
Y813722D03*
Y810375D03*
X144866Y820415D03*
Y817068D03*
Y813722D03*
Y810375D03*
X158425Y837147D03*
Y833800D03*
Y830454D03*
Y827108D03*
Y823761D03*
X144866Y837147D03*
Y833800D03*
Y830454D03*
Y827108D03*
Y823761D03*
X158425Y850533D03*
Y847186D03*
Y843840D03*
Y840493D03*
X144866Y850533D03*
Y847186D03*
Y843840D03*
Y840493D03*
X158425Y863919D03*
Y860572D03*
Y857226D03*
Y853879D03*
X144866Y863919D03*
Y860572D03*
Y857226D03*
Y853879D03*
X158425Y880651D03*
Y877304D03*
Y873958D03*
Y870611D03*
Y867265D03*
X144866Y880651D03*
Y877304D03*
Y873958D03*
Y870611D03*
Y867265D03*
X158425Y894037D03*
Y890690D03*
Y887344D03*
Y883997D03*
X144866Y894037D03*
Y890690D03*
Y887344D03*
Y883997D03*
X158425Y910769D03*
Y907423D03*
Y904076D03*
Y900730D03*
Y897383D03*
X144866Y910769D03*
Y907423D03*
Y904076D03*
Y900730D03*
Y897383D03*
X158425Y924155D03*
Y920808D03*
Y917462D03*
Y914115D03*
X144866Y924155D03*
Y920808D03*
Y917462D03*
Y914115D03*
X158425Y940887D03*
Y937541D03*
Y934194D03*
Y930848D03*
Y927501D03*
X144866Y940887D03*
Y937541D03*
Y934194D03*
Y930848D03*
Y927501D03*
X158425Y954273D03*
Y950926D03*
Y947580D03*
Y944234D03*
X144866Y954273D03*
Y950926D03*
Y947580D03*
Y944234D03*
X158425Y971005D03*
Y967659D03*
Y964312D03*
Y960966D03*
Y957619D03*
X144866Y971005D03*
Y967659D03*
Y964312D03*
Y960966D03*
Y957619D03*
X158425Y984391D03*
Y981045D03*
Y977698D03*
Y974352D03*
X144866Y984391D03*
Y981045D03*
Y977698D03*
Y974352D03*
X158425Y1001123D03*
Y997777D03*
Y994430D03*
Y991084D03*
Y987737D03*
X144866Y1001123D03*
Y997777D03*
Y994430D03*
Y991084D03*
Y987737D03*
X158425Y1004470D03*
X144866D03*
X158425Y1027895D03*
X144866D03*
X158425Y1044627D03*
Y1041281D03*
Y1037934D03*
Y1034588D03*
Y1031241D03*
X144866Y1044627D03*
Y1041281D03*
Y1037934D03*
Y1034588D03*
Y1031241D03*
X158425Y1058013D03*
Y1054667D03*
Y1051320D03*
Y1047974D03*
X144866Y1058013D03*
Y1054667D03*
Y1051320D03*
Y1047974D03*
X158425Y1074745D03*
Y1071399D03*
Y1068052D03*
Y1064706D03*
Y1061360D03*
X144866Y1074745D03*
Y1071399D03*
Y1068052D03*
Y1064706D03*
Y1061360D03*
X158425Y1088131D03*
Y1084785D03*
Y1081438D03*
Y1078092D03*
X144866Y1088131D03*
Y1084785D03*
Y1081438D03*
Y1078092D03*
X158425Y1104863D03*
Y1101517D03*
Y1098171D03*
Y1094824D03*
Y1091478D03*
X144866Y1104863D03*
Y1101517D03*
Y1098171D03*
Y1094824D03*
Y1091478D03*
X158425Y1118249D03*
Y1114903D03*
Y1111556D03*
Y1108210D03*
X144866Y1118249D03*
Y1114903D03*
Y1111556D03*
Y1108210D03*
X158425Y1134982D03*
Y1131635D03*
Y1128289D03*
Y1124942D03*
Y1121596D03*
X144866Y1134982D03*
Y1131635D03*
Y1128289D03*
Y1124942D03*
Y1121596D03*
X158425Y1148367D03*
Y1145021D03*
Y1141675D03*
Y1138328D03*
X144866Y1148367D03*
Y1145021D03*
Y1141675D03*
Y1138328D03*
X158425Y1165100D03*
Y1161753D03*
Y1158407D03*
Y1155060D03*
Y1151714D03*
X144866Y1165100D03*
Y1161753D03*
Y1158407D03*
Y1155060D03*
Y1151714D03*
X158425Y1178486D03*
Y1175139D03*
Y1171793D03*
Y1168446D03*
X144866Y1178486D03*
Y1175139D03*
Y1171793D03*
Y1168446D03*
X158425Y1191871D03*
Y1188525D03*
Y1185178D03*
Y1181832D03*
X144866Y1191871D03*
Y1188525D03*
Y1185178D03*
Y1181832D03*
X158425Y1208604D03*
Y1205257D03*
Y1201911D03*
Y1198564D03*
Y1195218D03*
X144866Y1208604D03*
Y1205257D03*
Y1201911D03*
Y1198564D03*
Y1195218D03*
X158425Y1221989D03*
Y1218643D03*
Y1215297D03*
Y1211950D03*
X144866Y1221989D03*
Y1218643D03*
Y1215297D03*
Y1211950D03*
X158425Y1238722D03*
Y1235375D03*
Y1232029D03*
Y1228682D03*
Y1225336D03*
X144866Y1238722D03*
Y1235375D03*
Y1232029D03*
Y1228682D03*
Y1225336D03*
X158425Y1252108D03*
Y1248761D03*
Y1245415D03*
Y1242068D03*
X144866Y1252108D03*
Y1248761D03*
Y1245415D03*
Y1242068D03*
X158425Y1255454D03*
X144866D03*
X188126Y760178D03*
Y756832D03*
X174567Y760178D03*
Y756832D03*
X188126Y776911D03*
Y773564D03*
Y770218D03*
Y766871D03*
Y763525D03*
X174567Y776911D03*
Y773564D03*
Y770218D03*
Y766871D03*
Y763525D03*
X188126Y790297D03*
Y786950D03*
Y783604D03*
Y780257D03*
X174567Y790297D03*
Y786950D03*
Y783604D03*
Y780257D03*
X188126Y807029D03*
Y803682D03*
Y800336D03*
Y796989D03*
Y793643D03*
X174567Y807029D03*
Y803682D03*
Y800336D03*
Y796989D03*
Y793643D03*
X188126Y820415D03*
Y817068D03*
Y813722D03*
Y810375D03*
X174567Y820415D03*
Y817068D03*
Y813722D03*
Y810375D03*
X188126Y837147D03*
Y833800D03*
Y830454D03*
Y827108D03*
Y823761D03*
X174567Y837147D03*
Y833800D03*
Y830454D03*
Y827108D03*
Y823761D03*
X188126Y850533D03*
Y847186D03*
Y843840D03*
Y840493D03*
X174567Y850533D03*
Y847186D03*
Y843840D03*
Y840493D03*
X188126Y863919D03*
Y860572D03*
Y857226D03*
Y853879D03*
X174567Y863919D03*
Y860572D03*
Y857226D03*
Y853879D03*
X188126Y880651D03*
Y877304D03*
Y873958D03*
Y870611D03*
Y867265D03*
X174567Y880651D03*
Y877304D03*
Y873958D03*
Y870611D03*
Y867265D03*
X188126Y894037D03*
Y890690D03*
Y887344D03*
Y883997D03*
X174567Y894037D03*
Y890690D03*
Y887344D03*
Y883997D03*
X188126Y910769D03*
Y907423D03*
Y904076D03*
Y900730D03*
Y897383D03*
X174567Y910769D03*
Y907423D03*
Y904076D03*
Y900730D03*
Y897383D03*
X188126Y924155D03*
Y920808D03*
Y917462D03*
Y914115D03*
X174567Y924155D03*
Y920808D03*
Y917462D03*
Y914115D03*
X188126Y940887D03*
Y937541D03*
Y934194D03*
Y930848D03*
Y927501D03*
X174567Y940887D03*
Y937541D03*
Y934194D03*
Y930848D03*
Y927501D03*
X188126Y954273D03*
Y950926D03*
Y947580D03*
Y944234D03*
X174567Y954273D03*
Y950926D03*
Y947580D03*
Y944234D03*
X188126Y971005D03*
Y967659D03*
Y964312D03*
Y960966D03*
Y957619D03*
X174567Y971005D03*
Y967659D03*
Y964312D03*
Y960966D03*
Y957619D03*
X188126Y984391D03*
Y981045D03*
Y977698D03*
Y974352D03*
X174567Y984391D03*
Y981045D03*
Y977698D03*
Y974352D03*
X188126Y1001123D03*
Y997777D03*
Y994430D03*
Y991084D03*
Y987737D03*
X174567Y1001123D03*
Y997777D03*
Y994430D03*
Y991084D03*
Y987737D03*
X188126Y1004470D03*
X174567D03*
X188126Y1027895D03*
X174567D03*
X188126Y1044627D03*
Y1041281D03*
Y1037934D03*
Y1034588D03*
Y1031241D03*
X174567Y1044627D03*
Y1041281D03*
Y1037934D03*
Y1034588D03*
Y1031241D03*
X188126Y1058013D03*
Y1054667D03*
Y1051320D03*
Y1047974D03*
X174567Y1058013D03*
Y1054667D03*
Y1051320D03*
Y1047974D03*
X188126Y1074745D03*
Y1071399D03*
Y1068052D03*
Y1064706D03*
Y1061360D03*
X174567Y1074745D03*
Y1071399D03*
Y1068052D03*
Y1064706D03*
Y1061360D03*
X188126Y1088131D03*
Y1084785D03*
Y1081438D03*
Y1078092D03*
X174567Y1088131D03*
Y1084785D03*
Y1081438D03*
Y1078092D03*
X188126Y1104863D03*
Y1101517D03*
Y1098171D03*
Y1094824D03*
Y1091478D03*
X174567Y1104863D03*
Y1101517D03*
Y1098171D03*
Y1094824D03*
Y1091478D03*
X188126Y1118249D03*
Y1114903D03*
Y1111556D03*
Y1108210D03*
X174567Y1118249D03*
Y1114903D03*
Y1111556D03*
Y1108210D03*
X188126Y1134982D03*
Y1131635D03*
Y1128289D03*
Y1124942D03*
Y1121596D03*
X174567Y1134982D03*
Y1131635D03*
Y1128289D03*
Y1124942D03*
Y1121596D03*
X188126Y1148367D03*
Y1145021D03*
Y1141675D03*
Y1138328D03*
X174567Y1148367D03*
Y1145021D03*
Y1141675D03*
Y1138328D03*
X188126Y1165100D03*
Y1161753D03*
Y1158407D03*
Y1155060D03*
Y1151714D03*
X174567Y1165100D03*
Y1161753D03*
Y1158407D03*
Y1155060D03*
Y1151714D03*
X188126Y1178486D03*
Y1175139D03*
Y1171793D03*
Y1168446D03*
X174567Y1178486D03*
Y1175139D03*
Y1171793D03*
Y1168446D03*
X188126Y1191871D03*
Y1188525D03*
Y1185178D03*
Y1181832D03*
X174567Y1191871D03*
Y1188525D03*
Y1185178D03*
Y1181832D03*
X188126Y1208604D03*
Y1205257D03*
Y1201911D03*
Y1198564D03*
Y1195218D03*
X174567Y1208604D03*
Y1205257D03*
Y1201911D03*
Y1198564D03*
Y1195218D03*
X188126Y1221989D03*
Y1218643D03*
Y1215297D03*
Y1211950D03*
X174567Y1221989D03*
Y1218643D03*
Y1215297D03*
Y1211950D03*
X188126Y1238722D03*
Y1235375D03*
Y1232029D03*
Y1228682D03*
Y1225336D03*
X174567Y1238722D03*
Y1235375D03*
Y1232029D03*
Y1228682D03*
Y1225336D03*
X188126Y1252108D03*
Y1248761D03*
Y1245415D03*
Y1242068D03*
X174567Y1252108D03*
Y1248761D03*
Y1245415D03*
Y1242068D03*
X188126Y1255454D03*
X174567D03*
X217827Y760178D03*
Y756832D03*
X204268Y760178D03*
Y756832D03*
X217827Y776911D03*
Y773564D03*
Y770218D03*
Y766871D03*
Y763525D03*
X204268Y776911D03*
Y773564D03*
Y770218D03*
Y766871D03*
Y763525D03*
X217827Y790297D03*
Y786950D03*
Y783604D03*
Y780257D03*
X204268Y790297D03*
Y786950D03*
Y783604D03*
Y780257D03*
X217827Y807029D03*
Y803682D03*
Y800336D03*
Y796989D03*
Y793643D03*
X204268Y807029D03*
Y803682D03*
Y800336D03*
Y796989D03*
Y793643D03*
X217827Y820415D03*
Y817068D03*
Y813722D03*
Y810375D03*
X204268Y820415D03*
Y817068D03*
Y813722D03*
Y810375D03*
X217827Y837147D03*
Y833800D03*
Y830454D03*
Y827108D03*
Y823761D03*
X204268Y837147D03*
Y833800D03*
Y830454D03*
Y827108D03*
Y823761D03*
X217827Y850533D03*
Y847186D03*
Y843840D03*
Y840493D03*
X204268Y850533D03*
Y847186D03*
Y843840D03*
Y840493D03*
X217827Y863919D03*
Y860572D03*
Y857226D03*
Y853879D03*
X204268Y863919D03*
Y860572D03*
Y857226D03*
Y853879D03*
X217827Y880651D03*
Y877304D03*
Y873958D03*
Y870611D03*
Y867265D03*
X204268Y880651D03*
Y877304D03*
Y873958D03*
Y870611D03*
Y867265D03*
X217827Y894037D03*
Y890690D03*
Y887344D03*
Y883997D03*
X204268Y894037D03*
Y890690D03*
Y887344D03*
Y883997D03*
X217827Y910769D03*
Y907423D03*
Y904076D03*
Y900730D03*
Y897383D03*
X204268Y910769D03*
Y907423D03*
Y904076D03*
Y900730D03*
Y897383D03*
X217827Y924155D03*
Y920808D03*
Y917462D03*
Y914115D03*
X204268Y924155D03*
Y920808D03*
Y917462D03*
Y914115D03*
X217827Y940887D03*
Y937541D03*
Y934194D03*
Y930848D03*
Y927501D03*
X204268Y940887D03*
Y937541D03*
Y934194D03*
Y930848D03*
Y927501D03*
X217827Y954273D03*
Y950926D03*
Y947580D03*
Y944234D03*
X204268Y954273D03*
Y950926D03*
Y947580D03*
Y944234D03*
X217827Y971005D03*
Y967659D03*
Y964312D03*
Y960966D03*
Y957619D03*
X204268Y971005D03*
Y967659D03*
Y964312D03*
Y960966D03*
Y957619D03*
X217827Y984391D03*
Y981045D03*
Y977698D03*
Y974352D03*
X204268Y984391D03*
Y981045D03*
Y977698D03*
Y974352D03*
X217827Y1001123D03*
Y997777D03*
Y994430D03*
Y991084D03*
Y987737D03*
X204268Y1001123D03*
Y997777D03*
Y994430D03*
Y991084D03*
Y987737D03*
X217827Y1004470D03*
X204268D03*
X217827Y1027895D03*
X204268D03*
X217827Y1044627D03*
Y1041281D03*
Y1037934D03*
Y1034588D03*
Y1031241D03*
X204268Y1044627D03*
Y1041281D03*
Y1037934D03*
Y1034588D03*
Y1031241D03*
X217827Y1058013D03*
Y1054667D03*
Y1051320D03*
Y1047974D03*
X204268Y1058013D03*
Y1054667D03*
Y1051320D03*
Y1047974D03*
X217827Y1074745D03*
Y1071399D03*
Y1068052D03*
Y1064706D03*
Y1061360D03*
X204268Y1074745D03*
Y1071399D03*
Y1068052D03*
Y1064706D03*
Y1061360D03*
X217827Y1088131D03*
Y1084785D03*
Y1081438D03*
Y1078092D03*
X204268Y1088131D03*
Y1084785D03*
Y1081438D03*
Y1078092D03*
X217827Y1104863D03*
Y1101517D03*
Y1098171D03*
Y1094824D03*
Y1091478D03*
X204268Y1104863D03*
Y1101517D03*
Y1098171D03*
Y1094824D03*
Y1091478D03*
X217827Y1118249D03*
Y1114903D03*
Y1111556D03*
Y1108210D03*
X204268Y1118249D03*
Y1114903D03*
Y1111556D03*
Y1108210D03*
X217827Y1134982D03*
Y1131635D03*
Y1128289D03*
Y1124942D03*
Y1121596D03*
X204268Y1134982D03*
Y1131635D03*
Y1128289D03*
Y1124942D03*
Y1121596D03*
X217827Y1148367D03*
Y1145021D03*
Y1141675D03*
Y1138328D03*
X204268Y1148367D03*
Y1145021D03*
Y1141675D03*
Y1138328D03*
X217827Y1165100D03*
Y1161753D03*
Y1158407D03*
Y1155060D03*
Y1151714D03*
X204268Y1165100D03*
Y1161753D03*
Y1158407D03*
Y1155060D03*
Y1151714D03*
X217827Y1178486D03*
Y1175139D03*
Y1171793D03*
Y1168446D03*
X204268Y1178486D03*
Y1175139D03*
Y1171793D03*
Y1168446D03*
X217827Y1191871D03*
Y1188525D03*
Y1185178D03*
Y1181832D03*
X204268Y1191871D03*
Y1188525D03*
Y1185178D03*
Y1181832D03*
X217827Y1208604D03*
Y1205257D03*
Y1201911D03*
Y1198564D03*
Y1195218D03*
X204268Y1208604D03*
Y1205257D03*
Y1201911D03*
Y1198564D03*
Y1195218D03*
X217827Y1221989D03*
Y1218643D03*
Y1215297D03*
Y1211950D03*
X204268Y1221989D03*
Y1218643D03*
Y1215297D03*
Y1211950D03*
X217827Y1238722D03*
Y1235375D03*
Y1232029D03*
Y1228682D03*
Y1225336D03*
X204268Y1238722D03*
Y1235375D03*
Y1232029D03*
Y1228682D03*
Y1225336D03*
X217827Y1252108D03*
Y1248761D03*
Y1245415D03*
Y1242068D03*
X204268Y1252108D03*
Y1248761D03*
Y1245415D03*
Y1242068D03*
X217827Y1255454D03*
X204268D03*
X233969Y760178D03*
Y756832D03*
Y776911D03*
Y773564D03*
Y770218D03*
Y766871D03*
Y763525D03*
Y790297D03*
Y786950D03*
Y783604D03*
Y780257D03*
Y807029D03*
Y803682D03*
Y800336D03*
Y796989D03*
Y793643D03*
Y820415D03*
Y817068D03*
Y813722D03*
Y810375D03*
Y837147D03*
Y833800D03*
Y830454D03*
Y827108D03*
Y823761D03*
Y850533D03*
Y847186D03*
Y843840D03*
Y840493D03*
Y863919D03*
Y860572D03*
Y857226D03*
Y853879D03*
Y880651D03*
Y877304D03*
Y873958D03*
Y870611D03*
Y867265D03*
Y894037D03*
Y890690D03*
Y887344D03*
Y883997D03*
Y910769D03*
Y907423D03*
Y904076D03*
Y900730D03*
Y897383D03*
Y924155D03*
Y920808D03*
Y917462D03*
Y914115D03*
Y940887D03*
Y937541D03*
Y934194D03*
Y930848D03*
Y927501D03*
Y954273D03*
Y950926D03*
Y947580D03*
Y944234D03*
Y971005D03*
Y967659D03*
Y964312D03*
Y960966D03*
Y957619D03*
Y984391D03*
Y981045D03*
Y977698D03*
Y974352D03*
Y1001123D03*
Y997777D03*
Y994430D03*
Y991084D03*
Y987737D03*
Y1004470D03*
Y1027895D03*
Y1044627D03*
Y1041281D03*
Y1037934D03*
Y1034588D03*
Y1031241D03*
Y1058013D03*
Y1054667D03*
Y1051320D03*
Y1047974D03*
Y1074745D03*
Y1071399D03*
Y1068052D03*
Y1064706D03*
Y1061360D03*
Y1088131D03*
Y1084785D03*
Y1081438D03*
Y1078092D03*
Y1104863D03*
Y1101517D03*
Y1098171D03*
Y1094824D03*
Y1091478D03*
Y1118249D03*
Y1114903D03*
Y1111556D03*
Y1108210D03*
Y1134982D03*
Y1131635D03*
Y1128289D03*
Y1124942D03*
Y1121596D03*
Y1148367D03*
Y1145021D03*
Y1141675D03*
Y1138328D03*
Y1165100D03*
Y1161753D03*
Y1158407D03*
Y1155060D03*
Y1151714D03*
Y1178486D03*
Y1175139D03*
Y1171793D03*
Y1168446D03*
Y1191871D03*
Y1188525D03*
Y1185178D03*
Y1181832D03*
Y1208604D03*
Y1205257D03*
Y1201911D03*
Y1198564D03*
Y1195218D03*
Y1221989D03*
Y1218643D03*
Y1215297D03*
Y1211950D03*
Y1238722D03*
Y1235375D03*
Y1232029D03*
Y1228682D03*
Y1225336D03*
Y1252108D03*
Y1248761D03*
Y1245415D03*
Y1242068D03*
Y1255454D03*
X647354Y760178D03*
Y756832D03*
Y776911D03*
Y773564D03*
Y770218D03*
Y766871D03*
Y763525D03*
Y790297D03*
Y786950D03*
Y783604D03*
Y780257D03*
Y807029D03*
Y803682D03*
Y800336D03*
Y796989D03*
Y793643D03*
Y820415D03*
Y817068D03*
Y813722D03*
Y810375D03*
Y837147D03*
Y833800D03*
Y830454D03*
Y827108D03*
Y823761D03*
Y850533D03*
Y847186D03*
Y843840D03*
Y840493D03*
Y863919D03*
Y860572D03*
Y857226D03*
Y853879D03*
Y880651D03*
Y877304D03*
Y873958D03*
Y870611D03*
Y867265D03*
Y894037D03*
Y890690D03*
Y887344D03*
Y883997D03*
Y910769D03*
Y907423D03*
Y904076D03*
Y900730D03*
Y897383D03*
Y924155D03*
Y920808D03*
Y917462D03*
Y914115D03*
Y940887D03*
Y937541D03*
Y934194D03*
Y930848D03*
Y927501D03*
Y954273D03*
Y950926D03*
Y947580D03*
Y944234D03*
Y971005D03*
Y967659D03*
Y964312D03*
Y960966D03*
Y957619D03*
Y984391D03*
Y981045D03*
Y977698D03*
Y974352D03*
Y1001123D03*
Y997777D03*
Y994430D03*
Y991084D03*
Y987737D03*
Y1004470D03*
Y1027895D03*
Y1044627D03*
Y1041281D03*
Y1037934D03*
Y1034588D03*
Y1031241D03*
Y1058013D03*
Y1054667D03*
Y1051320D03*
Y1047974D03*
Y1074745D03*
Y1071399D03*
Y1068052D03*
Y1064706D03*
Y1061360D03*
Y1088131D03*
Y1084785D03*
Y1081438D03*
Y1078092D03*
Y1104863D03*
Y1101517D03*
Y1098171D03*
Y1094824D03*
Y1091478D03*
Y1118249D03*
Y1114903D03*
Y1111556D03*
Y1108210D03*
Y1134982D03*
Y1131635D03*
Y1128289D03*
Y1124942D03*
Y1121596D03*
Y1148367D03*
Y1145021D03*
Y1141675D03*
Y1138328D03*
Y1165100D03*
Y1161753D03*
Y1158407D03*
Y1155060D03*
Y1151714D03*
Y1178486D03*
Y1175139D03*
Y1171793D03*
Y1168446D03*
Y1191871D03*
Y1188525D03*
Y1185178D03*
Y1181832D03*
Y1208604D03*
Y1205257D03*
Y1201911D03*
Y1198564D03*
Y1195218D03*
Y1221989D03*
Y1218643D03*
Y1215297D03*
Y1211950D03*
Y1238722D03*
Y1235375D03*
Y1232029D03*
Y1228682D03*
Y1225336D03*
Y1252108D03*
Y1248761D03*
Y1245415D03*
Y1242068D03*
Y1255454D03*
X663496Y760178D03*
Y756832D03*
Y776911D03*
Y773564D03*
Y770218D03*
Y766871D03*
Y763525D03*
Y790297D03*
Y786950D03*
Y783604D03*
Y780257D03*
Y807029D03*
Y803682D03*
Y800336D03*
Y796989D03*
Y793643D03*
Y820415D03*
Y817068D03*
Y813722D03*
Y810375D03*
Y837147D03*
Y833800D03*
Y830454D03*
Y827108D03*
Y823761D03*
Y850533D03*
Y847186D03*
Y843840D03*
Y840493D03*
Y863919D03*
Y860572D03*
Y857226D03*
Y853879D03*
Y880651D03*
Y877304D03*
Y873958D03*
Y870611D03*
Y867265D03*
Y894037D03*
Y890690D03*
Y887344D03*
Y883997D03*
Y910769D03*
Y907423D03*
Y904076D03*
Y900730D03*
Y897383D03*
Y924155D03*
Y920808D03*
Y917462D03*
Y914115D03*
Y940887D03*
Y937541D03*
Y934194D03*
Y930848D03*
Y927501D03*
Y954273D03*
Y950926D03*
Y947580D03*
Y944234D03*
Y971005D03*
Y967659D03*
Y964312D03*
Y960966D03*
Y957619D03*
Y984391D03*
Y981045D03*
Y977698D03*
Y974352D03*
Y1001123D03*
Y997777D03*
Y994430D03*
Y991084D03*
Y987737D03*
Y1004470D03*
Y1027895D03*
Y1044627D03*
Y1041281D03*
Y1037934D03*
Y1034588D03*
Y1031241D03*
Y1058013D03*
Y1054667D03*
Y1051320D03*
Y1047974D03*
Y1074745D03*
Y1071399D03*
Y1068052D03*
Y1064706D03*
Y1061360D03*
Y1088131D03*
Y1084785D03*
Y1081438D03*
Y1078092D03*
Y1104863D03*
Y1101517D03*
Y1098171D03*
Y1094824D03*
Y1091478D03*
Y1118249D03*
Y1114903D03*
Y1111556D03*
Y1108210D03*
Y1134982D03*
Y1131635D03*
Y1128289D03*
Y1124942D03*
Y1121596D03*
Y1148367D03*
Y1145021D03*
Y1141675D03*
Y1138328D03*
Y1165100D03*
Y1161753D03*
Y1158407D03*
Y1155060D03*
Y1151714D03*
Y1178486D03*
Y1175139D03*
Y1171793D03*
Y1168446D03*
Y1191871D03*
Y1188525D03*
Y1185178D03*
Y1181832D03*
Y1208604D03*
Y1205257D03*
Y1201911D03*
Y1198564D03*
Y1195218D03*
Y1221989D03*
Y1218643D03*
Y1215297D03*
Y1211950D03*
Y1238722D03*
Y1235375D03*
Y1232029D03*
Y1228682D03*
Y1225336D03*
Y1252108D03*
Y1248761D03*
Y1245415D03*
Y1242068D03*
Y1255454D03*
X677055Y760178D03*
Y756832D03*
Y776911D03*
Y773564D03*
Y770218D03*
Y766871D03*
Y763525D03*
Y790297D03*
Y786950D03*
Y783604D03*
Y780257D03*
Y807029D03*
Y803682D03*
Y800336D03*
Y796989D03*
Y793643D03*
Y820415D03*
Y817068D03*
Y813722D03*
Y810375D03*
Y837147D03*
Y833800D03*
Y830454D03*
Y827108D03*
Y823761D03*
Y850533D03*
Y847186D03*
Y843840D03*
Y840493D03*
Y863919D03*
Y860572D03*
Y857226D03*
Y853879D03*
Y880651D03*
Y877304D03*
Y873958D03*
Y870611D03*
Y867265D03*
Y894037D03*
Y890690D03*
Y887344D03*
Y883997D03*
Y910769D03*
Y907423D03*
Y904076D03*
Y900730D03*
Y897383D03*
Y924155D03*
Y920808D03*
Y917462D03*
Y914115D03*
Y940887D03*
Y937541D03*
Y934194D03*
Y930848D03*
Y927501D03*
Y954273D03*
Y950926D03*
Y947580D03*
Y944234D03*
Y971005D03*
Y967659D03*
Y964312D03*
Y960966D03*
Y957619D03*
Y984391D03*
Y981045D03*
Y977698D03*
Y974352D03*
Y1001123D03*
Y997777D03*
Y994430D03*
Y991084D03*
Y987737D03*
Y1004470D03*
Y1027895D03*
Y1044627D03*
Y1041281D03*
Y1037934D03*
Y1034588D03*
Y1031241D03*
Y1058013D03*
Y1054667D03*
Y1051320D03*
Y1047974D03*
Y1074745D03*
Y1071399D03*
Y1068052D03*
Y1064706D03*
Y1061360D03*
Y1088131D03*
Y1084785D03*
Y1081438D03*
Y1078092D03*
Y1104863D03*
Y1101517D03*
Y1098171D03*
Y1094824D03*
Y1091478D03*
Y1118249D03*
Y1114903D03*
Y1111556D03*
Y1108210D03*
Y1134982D03*
Y1131635D03*
Y1128289D03*
Y1124942D03*
Y1121596D03*
Y1148367D03*
Y1145021D03*
Y1141675D03*
Y1138328D03*
Y1165100D03*
Y1161753D03*
Y1158407D03*
Y1155060D03*
Y1151714D03*
Y1178486D03*
Y1175139D03*
Y1171793D03*
Y1168446D03*
Y1191871D03*
Y1188525D03*
Y1185178D03*
Y1181832D03*
Y1208604D03*
Y1205257D03*
Y1201911D03*
Y1198564D03*
Y1195218D03*
Y1221989D03*
Y1218643D03*
Y1215297D03*
Y1211950D03*
Y1238722D03*
Y1235375D03*
Y1232029D03*
Y1228682D03*
Y1225336D03*
Y1252108D03*
Y1248761D03*
Y1245415D03*
Y1242068D03*
Y1255454D03*
X693197Y760178D03*
Y756832D03*
Y776911D03*
Y773564D03*
Y770218D03*
Y766871D03*
Y763525D03*
Y790297D03*
Y786950D03*
Y783604D03*
Y780257D03*
Y807029D03*
Y803682D03*
Y800336D03*
Y796989D03*
Y793643D03*
Y820415D03*
Y817068D03*
Y813722D03*
Y810375D03*
Y837147D03*
Y833800D03*
Y830454D03*
Y827108D03*
Y823761D03*
Y850533D03*
Y847186D03*
Y843840D03*
Y840493D03*
Y863919D03*
Y860572D03*
Y857226D03*
Y853879D03*
Y880651D03*
Y877304D03*
Y873958D03*
Y870611D03*
Y867265D03*
Y894037D03*
Y890690D03*
Y887344D03*
Y883997D03*
Y910769D03*
Y907423D03*
Y904076D03*
Y900730D03*
Y897383D03*
Y924155D03*
Y920808D03*
Y917462D03*
Y914115D03*
Y940887D03*
Y937541D03*
Y934194D03*
Y930848D03*
Y927501D03*
Y954273D03*
Y950926D03*
Y947580D03*
Y944234D03*
Y971005D03*
Y967659D03*
Y964312D03*
Y960966D03*
Y957619D03*
Y984391D03*
Y981045D03*
Y977698D03*
Y974352D03*
Y1001123D03*
Y997777D03*
Y994430D03*
Y991084D03*
Y987737D03*
Y1004470D03*
Y1027895D03*
Y1044627D03*
Y1041281D03*
Y1037934D03*
Y1034588D03*
Y1031241D03*
Y1058013D03*
Y1054667D03*
Y1051320D03*
Y1047974D03*
Y1074745D03*
Y1071399D03*
Y1068052D03*
Y1064706D03*
Y1061360D03*
Y1088131D03*
Y1084785D03*
Y1081438D03*
Y1078092D03*
Y1104863D03*
Y1101517D03*
Y1098171D03*
Y1094824D03*
Y1091478D03*
Y1118249D03*
Y1114903D03*
Y1111556D03*
Y1108210D03*
Y1134982D03*
Y1131635D03*
Y1128289D03*
Y1124942D03*
Y1121596D03*
Y1148367D03*
Y1145021D03*
Y1141675D03*
Y1138328D03*
Y1165100D03*
Y1161753D03*
Y1158407D03*
Y1155060D03*
Y1151714D03*
Y1178486D03*
Y1175139D03*
Y1171793D03*
Y1168446D03*
Y1191871D03*
Y1188525D03*
Y1185178D03*
Y1181832D03*
Y1208604D03*
Y1205257D03*
Y1201911D03*
Y1198564D03*
Y1195218D03*
Y1221989D03*
Y1218643D03*
Y1215297D03*
Y1211950D03*
Y1238722D03*
Y1235375D03*
Y1232029D03*
Y1228682D03*
Y1225336D03*
Y1252108D03*
Y1248761D03*
Y1245415D03*
Y1242068D03*
Y1255454D03*
X706756Y760178D03*
Y756832D03*
Y776911D03*
Y773564D03*
Y770218D03*
Y766871D03*
Y763525D03*
Y790297D03*
Y786950D03*
Y783604D03*
Y780257D03*
Y807029D03*
Y803682D03*
Y800336D03*
Y796989D03*
Y793643D03*
Y820415D03*
Y817068D03*
Y813722D03*
Y810375D03*
Y837147D03*
Y833800D03*
Y830454D03*
Y827108D03*
Y823761D03*
Y850533D03*
Y847186D03*
Y843840D03*
Y840493D03*
Y863919D03*
Y860572D03*
Y857226D03*
Y853879D03*
Y880651D03*
Y877304D03*
Y873958D03*
Y870611D03*
Y867265D03*
Y894037D03*
Y890690D03*
Y887344D03*
Y883997D03*
Y910769D03*
Y907423D03*
Y904076D03*
Y900730D03*
Y897383D03*
Y924155D03*
Y920808D03*
Y917462D03*
Y914115D03*
Y940887D03*
Y937541D03*
Y934194D03*
Y930848D03*
Y927501D03*
Y954273D03*
Y950926D03*
Y947580D03*
Y944234D03*
Y971005D03*
Y967659D03*
Y964312D03*
Y960966D03*
Y957619D03*
Y984391D03*
Y981045D03*
Y977698D03*
Y974352D03*
Y1001123D03*
Y997777D03*
Y994430D03*
Y991084D03*
Y987737D03*
Y1004470D03*
Y1027895D03*
Y1044627D03*
Y1041281D03*
Y1037934D03*
Y1034588D03*
Y1031241D03*
Y1058013D03*
Y1054667D03*
Y1051320D03*
Y1047974D03*
Y1074745D03*
Y1071399D03*
Y1068052D03*
Y1064706D03*
Y1061360D03*
Y1088131D03*
Y1084785D03*
Y1081438D03*
Y1078092D03*
Y1104863D03*
Y1101517D03*
Y1098171D03*
Y1094824D03*
Y1091478D03*
Y1118249D03*
Y1114903D03*
Y1111556D03*
Y1108210D03*
Y1134982D03*
Y1131635D03*
Y1128289D03*
Y1124942D03*
Y1121596D03*
Y1148367D03*
Y1145021D03*
Y1141675D03*
Y1138328D03*
Y1165100D03*
Y1161753D03*
Y1158407D03*
Y1155060D03*
Y1151714D03*
Y1178486D03*
Y1175139D03*
Y1171793D03*
Y1168446D03*
Y1191871D03*
Y1188525D03*
Y1185178D03*
Y1181832D03*
Y1208604D03*
Y1205257D03*
Y1201911D03*
Y1198564D03*
Y1195218D03*
Y1221989D03*
Y1218643D03*
Y1215297D03*
Y1211950D03*
Y1238722D03*
Y1235375D03*
Y1232029D03*
Y1228682D03*
Y1225336D03*
Y1252108D03*
Y1248761D03*
Y1245415D03*
Y1242068D03*
Y1255454D03*
X722898Y760178D03*
Y756832D03*
Y776911D03*
Y773564D03*
Y770218D03*
Y766871D03*
Y763525D03*
Y790297D03*
Y786950D03*
Y783604D03*
Y780257D03*
Y807029D03*
Y803682D03*
Y800336D03*
Y796989D03*
Y793643D03*
Y820415D03*
Y817068D03*
Y813722D03*
Y810375D03*
Y837147D03*
Y833800D03*
Y830454D03*
Y827108D03*
Y823761D03*
Y850533D03*
Y847186D03*
Y843840D03*
Y840493D03*
Y863919D03*
Y860572D03*
Y857226D03*
Y853879D03*
Y880651D03*
Y877304D03*
Y873958D03*
Y870611D03*
Y867265D03*
Y894037D03*
Y890690D03*
Y887344D03*
Y883997D03*
Y910769D03*
Y907423D03*
Y904076D03*
Y900730D03*
Y897383D03*
Y924155D03*
Y920808D03*
Y917462D03*
Y914115D03*
Y940887D03*
Y937541D03*
Y934194D03*
Y930848D03*
Y927501D03*
Y954273D03*
Y950926D03*
Y947580D03*
Y944234D03*
Y971005D03*
Y967659D03*
Y964312D03*
Y960966D03*
Y957619D03*
Y984391D03*
Y981045D03*
Y977698D03*
Y974352D03*
Y1001123D03*
Y997777D03*
Y994430D03*
Y991084D03*
Y987737D03*
Y1004470D03*
Y1027895D03*
Y1044627D03*
Y1041281D03*
Y1037934D03*
Y1034588D03*
Y1031241D03*
Y1058013D03*
Y1054667D03*
Y1051320D03*
Y1047974D03*
Y1074745D03*
Y1071399D03*
Y1068052D03*
Y1064706D03*
Y1061360D03*
Y1088131D03*
Y1084785D03*
Y1081438D03*
Y1078092D03*
Y1104863D03*
Y1101517D03*
Y1098171D03*
Y1094824D03*
Y1091478D03*
Y1118249D03*
Y1114903D03*
Y1111556D03*
Y1108210D03*
Y1134982D03*
Y1131635D03*
Y1128289D03*
Y1124942D03*
Y1121596D03*
Y1148367D03*
Y1145021D03*
Y1141675D03*
Y1138328D03*
Y1165100D03*
Y1161753D03*
Y1158407D03*
Y1155060D03*
Y1151714D03*
Y1178486D03*
Y1175139D03*
Y1171793D03*
Y1168446D03*
Y1191871D03*
Y1188525D03*
Y1185178D03*
Y1181832D03*
Y1208604D03*
Y1205257D03*
Y1201911D03*
Y1198564D03*
Y1195218D03*
Y1221989D03*
Y1218643D03*
Y1215297D03*
Y1211950D03*
Y1238722D03*
Y1235375D03*
Y1232029D03*
Y1228682D03*
Y1225336D03*
Y1252108D03*
Y1248761D03*
Y1245415D03*
Y1242068D03*
Y1255454D03*
X736457Y760178D03*
Y756832D03*
Y776911D03*
Y773564D03*
Y770218D03*
Y766871D03*
Y763525D03*
Y790297D03*
Y786950D03*
Y783604D03*
Y780257D03*
Y807029D03*
Y803682D03*
Y800336D03*
Y796989D03*
Y793643D03*
Y820415D03*
Y817068D03*
Y813722D03*
Y810375D03*
Y837147D03*
Y833800D03*
Y830454D03*
Y827108D03*
Y823761D03*
Y850533D03*
Y847186D03*
Y843840D03*
Y840493D03*
Y863919D03*
Y860572D03*
Y857226D03*
Y853879D03*
Y880651D03*
Y877304D03*
Y873958D03*
Y870611D03*
Y867265D03*
Y894037D03*
Y890690D03*
Y887344D03*
Y883997D03*
Y910769D03*
Y907423D03*
Y904076D03*
Y900730D03*
Y897383D03*
Y924155D03*
Y920808D03*
Y917462D03*
Y914115D03*
Y940887D03*
Y937541D03*
Y934194D03*
Y930848D03*
Y927501D03*
Y954273D03*
Y950926D03*
Y947580D03*
Y944234D03*
Y971005D03*
Y967659D03*
Y964312D03*
Y960966D03*
Y957619D03*
Y984391D03*
Y981045D03*
Y977698D03*
Y974352D03*
Y1001123D03*
Y997777D03*
Y994430D03*
Y991084D03*
Y987737D03*
Y1004470D03*
Y1027895D03*
Y1044627D03*
Y1041281D03*
Y1037934D03*
Y1034588D03*
Y1031241D03*
Y1058013D03*
Y1054667D03*
Y1051320D03*
Y1047974D03*
Y1074745D03*
Y1071399D03*
Y1068052D03*
Y1064706D03*
Y1061360D03*
Y1088131D03*
Y1084785D03*
Y1081438D03*
Y1078092D03*
Y1104863D03*
Y1101517D03*
Y1098171D03*
Y1094824D03*
Y1091478D03*
Y1118249D03*
Y1114903D03*
Y1111556D03*
Y1108210D03*
Y1134982D03*
Y1131635D03*
Y1128289D03*
Y1124942D03*
Y1121596D03*
Y1148367D03*
Y1145021D03*
Y1141675D03*
Y1138328D03*
Y1165100D03*
Y1161753D03*
Y1158407D03*
Y1155060D03*
Y1151714D03*
Y1178486D03*
Y1175139D03*
Y1171793D03*
Y1168446D03*
Y1191871D03*
Y1188525D03*
Y1185178D03*
Y1181832D03*
Y1208604D03*
Y1205257D03*
Y1201911D03*
Y1198564D03*
Y1195218D03*
Y1221989D03*
Y1218643D03*
Y1215297D03*
Y1211950D03*
Y1238722D03*
Y1235375D03*
Y1232029D03*
Y1228682D03*
Y1225336D03*
Y1252108D03*
Y1248761D03*
Y1245415D03*
Y1242068D03*
Y1255454D03*
X752599Y760178D03*
Y756832D03*
Y776911D03*
Y773564D03*
Y770218D03*
Y766871D03*
Y763525D03*
Y790297D03*
Y786950D03*
Y783604D03*
Y780257D03*
Y807029D03*
Y803682D03*
Y800336D03*
Y796989D03*
Y793643D03*
Y820415D03*
Y817068D03*
Y813722D03*
Y810375D03*
Y837147D03*
Y833800D03*
Y830454D03*
Y827108D03*
Y823761D03*
Y850533D03*
Y847186D03*
Y843840D03*
Y840493D03*
Y863919D03*
Y860572D03*
Y857226D03*
Y853879D03*
Y880651D03*
Y877304D03*
Y873958D03*
Y870611D03*
Y867265D03*
Y894037D03*
Y890690D03*
Y887344D03*
Y883997D03*
Y910769D03*
Y907423D03*
Y904076D03*
Y900730D03*
Y897383D03*
Y924155D03*
Y920808D03*
Y917462D03*
Y914115D03*
Y940887D03*
Y937541D03*
Y934194D03*
Y930848D03*
Y927501D03*
Y954273D03*
Y950926D03*
Y947580D03*
Y944234D03*
Y971005D03*
Y967659D03*
Y964312D03*
Y960966D03*
Y957619D03*
Y984391D03*
Y981045D03*
Y977698D03*
Y974352D03*
Y1001123D03*
Y997777D03*
Y994430D03*
Y991084D03*
Y987737D03*
Y1004470D03*
Y1027895D03*
Y1044627D03*
Y1041281D03*
Y1037934D03*
Y1034588D03*
Y1031241D03*
Y1058013D03*
Y1054667D03*
Y1051320D03*
Y1047974D03*
Y1074745D03*
Y1071399D03*
Y1068052D03*
Y1064706D03*
Y1061360D03*
Y1088131D03*
Y1084785D03*
Y1081438D03*
Y1078092D03*
Y1104863D03*
Y1101517D03*
Y1098171D03*
Y1094824D03*
Y1091478D03*
Y1118249D03*
Y1114903D03*
Y1111556D03*
Y1108210D03*
Y1134982D03*
Y1131635D03*
Y1128289D03*
Y1124942D03*
Y1121596D03*
Y1148367D03*
Y1145021D03*
Y1141675D03*
Y1138328D03*
Y1165100D03*
Y1161753D03*
Y1158407D03*
Y1155060D03*
Y1151714D03*
Y1178486D03*
Y1175139D03*
Y1171793D03*
Y1168446D03*
Y1191871D03*
Y1188525D03*
Y1185178D03*
Y1181832D03*
Y1208604D03*
Y1205257D03*
Y1201911D03*
Y1198564D03*
Y1195218D03*
Y1221989D03*
Y1218643D03*
Y1215297D03*
Y1211950D03*
Y1238722D03*
Y1235375D03*
Y1232029D03*
Y1228682D03*
Y1225336D03*
Y1252108D03*
Y1248761D03*
Y1245415D03*
Y1242068D03*
Y1255454D03*
X766158Y760178D03*
Y756832D03*
Y776911D03*
Y773564D03*
Y770218D03*
Y766871D03*
Y763525D03*
Y790297D03*
Y786950D03*
Y783604D03*
Y780257D03*
Y807029D03*
Y803682D03*
Y800336D03*
Y796989D03*
Y793643D03*
Y820415D03*
Y817068D03*
Y813722D03*
Y810375D03*
Y837147D03*
Y833800D03*
Y830454D03*
Y827108D03*
Y823761D03*
Y850533D03*
Y847186D03*
Y843840D03*
Y840493D03*
Y863919D03*
Y860572D03*
Y857226D03*
Y853879D03*
Y880651D03*
Y877304D03*
Y873958D03*
Y870611D03*
Y867265D03*
Y894037D03*
Y890690D03*
Y887344D03*
Y883997D03*
Y910769D03*
Y907423D03*
Y904076D03*
Y900730D03*
Y897383D03*
Y924155D03*
Y920808D03*
Y917462D03*
Y914115D03*
Y940887D03*
Y937541D03*
Y934194D03*
Y930848D03*
Y927501D03*
Y954273D03*
Y950926D03*
Y947580D03*
Y944234D03*
Y971005D03*
Y967659D03*
Y964312D03*
Y960966D03*
Y957619D03*
Y984391D03*
Y981045D03*
Y977698D03*
Y974352D03*
Y1001123D03*
Y997777D03*
Y994430D03*
Y991084D03*
Y987737D03*
Y1004470D03*
Y1027895D03*
Y1044627D03*
Y1041281D03*
Y1037934D03*
Y1034588D03*
Y1031241D03*
Y1058013D03*
Y1054667D03*
Y1051320D03*
Y1047974D03*
Y1074745D03*
Y1071399D03*
Y1068052D03*
Y1064706D03*
Y1061360D03*
Y1088131D03*
Y1084785D03*
Y1081438D03*
Y1078092D03*
Y1104863D03*
Y1101517D03*
Y1098171D03*
Y1094824D03*
Y1091478D03*
Y1118249D03*
Y1114903D03*
Y1111556D03*
Y1108210D03*
Y1134982D03*
Y1131635D03*
Y1128289D03*
Y1124942D03*
Y1121596D03*
Y1148367D03*
Y1145021D03*
Y1141675D03*
Y1138328D03*
Y1165100D03*
Y1161753D03*
Y1158407D03*
Y1155060D03*
Y1151714D03*
Y1178486D03*
Y1175139D03*
Y1171793D03*
Y1168446D03*
Y1191871D03*
Y1188525D03*
Y1185178D03*
Y1181832D03*
Y1208604D03*
Y1205257D03*
Y1201911D03*
Y1198564D03*
Y1195218D03*
Y1221989D03*
Y1218643D03*
Y1215297D03*
Y1211950D03*
Y1238722D03*
Y1235375D03*
Y1232029D03*
Y1228682D03*
Y1225336D03*
Y1252108D03*
Y1248761D03*
Y1245415D03*
Y1242068D03*
Y1255454D03*
X782300Y760178D03*
Y756832D03*
Y776911D03*
Y773564D03*
Y770218D03*
Y766871D03*
Y763525D03*
Y790297D03*
Y786950D03*
Y783604D03*
Y780257D03*
Y807029D03*
Y803682D03*
Y800336D03*
Y796989D03*
Y793643D03*
Y820415D03*
Y817068D03*
Y813722D03*
Y810375D03*
Y837147D03*
Y833800D03*
Y830454D03*
Y827108D03*
Y823761D03*
Y850533D03*
Y847186D03*
Y843840D03*
Y840493D03*
Y863919D03*
Y860572D03*
Y857226D03*
Y853879D03*
Y880651D03*
Y877304D03*
Y873958D03*
Y870611D03*
Y867265D03*
Y894037D03*
Y890690D03*
Y887344D03*
Y883997D03*
Y910769D03*
Y907423D03*
Y904076D03*
Y900730D03*
Y897383D03*
Y924155D03*
Y920808D03*
Y917462D03*
Y914115D03*
Y940887D03*
Y937541D03*
Y934194D03*
Y930848D03*
Y927501D03*
Y954273D03*
Y950926D03*
Y947580D03*
Y944234D03*
Y971005D03*
Y967659D03*
Y964312D03*
Y960966D03*
Y957619D03*
Y984391D03*
Y981045D03*
Y977698D03*
Y974352D03*
Y1001123D03*
Y997777D03*
Y994430D03*
Y991084D03*
Y987737D03*
Y1004470D03*
Y1027895D03*
Y1044627D03*
Y1041281D03*
Y1037934D03*
Y1034588D03*
Y1031241D03*
Y1058013D03*
Y1054667D03*
Y1051320D03*
Y1047974D03*
Y1074745D03*
Y1071399D03*
Y1068052D03*
Y1064706D03*
Y1061360D03*
Y1088131D03*
Y1084785D03*
Y1081438D03*
Y1078092D03*
Y1104863D03*
Y1101517D03*
Y1098171D03*
Y1094824D03*
Y1091478D03*
Y1118249D03*
Y1114903D03*
Y1111556D03*
Y1108210D03*
Y1134982D03*
Y1131635D03*
Y1128289D03*
Y1124942D03*
Y1121596D03*
Y1148367D03*
Y1145021D03*
Y1141675D03*
Y1138328D03*
Y1165100D03*
Y1161753D03*
Y1158407D03*
Y1155060D03*
Y1151714D03*
Y1178486D03*
Y1175139D03*
Y1171793D03*
Y1168446D03*
Y1191871D03*
Y1188525D03*
Y1185178D03*
Y1181832D03*
Y1208604D03*
Y1205257D03*
Y1201911D03*
Y1198564D03*
Y1195218D03*
Y1221989D03*
Y1218643D03*
Y1215297D03*
Y1211950D03*
Y1238722D03*
Y1235375D03*
Y1232029D03*
Y1228682D03*
Y1225336D03*
Y1252108D03*
Y1248761D03*
Y1245415D03*
Y1242068D03*
Y1255454D03*
X795858Y760178D03*
Y756832D03*
Y776911D03*
Y773564D03*
Y770218D03*
Y766871D03*
Y763525D03*
Y790297D03*
Y786950D03*
Y783604D03*
Y780257D03*
Y807029D03*
Y803682D03*
Y800336D03*
Y796989D03*
Y793643D03*
Y820415D03*
Y817068D03*
Y813722D03*
Y810375D03*
Y837147D03*
Y833800D03*
Y830454D03*
Y827108D03*
Y823761D03*
Y850533D03*
Y847186D03*
Y843840D03*
Y840493D03*
Y863919D03*
Y860572D03*
Y857226D03*
Y853879D03*
Y880651D03*
Y877304D03*
Y873958D03*
Y870611D03*
Y867265D03*
Y894037D03*
Y890690D03*
Y887344D03*
Y883997D03*
Y910769D03*
Y907423D03*
Y904076D03*
Y900730D03*
Y897383D03*
Y924155D03*
Y920808D03*
Y917462D03*
Y914115D03*
Y940887D03*
Y937541D03*
Y934194D03*
Y930848D03*
Y927501D03*
Y954273D03*
Y950926D03*
Y947580D03*
Y944234D03*
Y971005D03*
Y967659D03*
Y964312D03*
Y960966D03*
Y957619D03*
Y984391D03*
Y981045D03*
Y977698D03*
Y974352D03*
Y1001123D03*
Y997777D03*
Y994430D03*
Y991084D03*
Y987737D03*
Y1004470D03*
Y1027895D03*
Y1044627D03*
Y1041281D03*
Y1037934D03*
Y1034588D03*
Y1031241D03*
Y1058013D03*
Y1054667D03*
Y1051320D03*
Y1047974D03*
Y1074745D03*
Y1071399D03*
Y1068052D03*
Y1064706D03*
Y1061360D03*
Y1088131D03*
Y1084785D03*
Y1081438D03*
Y1078092D03*
Y1104863D03*
Y1101517D03*
Y1098171D03*
Y1094824D03*
Y1091478D03*
Y1118249D03*
Y1114903D03*
Y1111556D03*
Y1108210D03*
Y1134982D03*
Y1131635D03*
Y1128289D03*
Y1124942D03*
Y1121596D03*
Y1148367D03*
Y1145021D03*
Y1141675D03*
Y1138328D03*
Y1165100D03*
Y1161753D03*
Y1158407D03*
Y1155060D03*
Y1151714D03*
Y1178486D03*
Y1175139D03*
Y1171793D03*
Y1168446D03*
Y1191871D03*
Y1188525D03*
Y1185178D03*
Y1181832D03*
Y1208604D03*
Y1205257D03*
Y1201911D03*
Y1198564D03*
Y1195218D03*
Y1221989D03*
Y1218643D03*
Y1215297D03*
Y1211950D03*
Y1238722D03*
Y1235375D03*
Y1232029D03*
Y1228682D03*
Y1225336D03*
Y1252108D03*
Y1248761D03*
Y1245415D03*
Y1242068D03*
Y1255454D03*
X812000Y760178D03*
Y756832D03*
Y776911D03*
Y773564D03*
Y770218D03*
Y766871D03*
Y763525D03*
Y790297D03*
Y786950D03*
Y783604D03*
Y780257D03*
Y807029D03*
Y803682D03*
Y800336D03*
Y796989D03*
Y793643D03*
Y820415D03*
Y817068D03*
Y813722D03*
Y810375D03*
Y837147D03*
Y833800D03*
Y830454D03*
Y827108D03*
Y823761D03*
Y850533D03*
Y847186D03*
Y843840D03*
Y840493D03*
Y863919D03*
Y860572D03*
Y857226D03*
Y853879D03*
Y880651D03*
Y877304D03*
Y873958D03*
Y870611D03*
Y867265D03*
Y894037D03*
Y890690D03*
Y887344D03*
Y883997D03*
Y910769D03*
Y907423D03*
Y904076D03*
Y900730D03*
Y897383D03*
Y924155D03*
Y920808D03*
Y917462D03*
Y914115D03*
Y940887D03*
Y937541D03*
Y934194D03*
Y930848D03*
Y927501D03*
Y954273D03*
Y950926D03*
Y947580D03*
Y944234D03*
Y971005D03*
Y967659D03*
Y964312D03*
Y960966D03*
Y957619D03*
Y984391D03*
Y981045D03*
Y977698D03*
Y974352D03*
Y1001123D03*
Y997777D03*
Y994430D03*
Y991084D03*
Y987737D03*
Y1004470D03*
Y1027895D03*
Y1044627D03*
Y1041281D03*
Y1037934D03*
Y1034588D03*
Y1031241D03*
Y1058013D03*
Y1054667D03*
Y1051320D03*
Y1047974D03*
Y1074745D03*
Y1071399D03*
Y1068052D03*
Y1064706D03*
Y1061360D03*
Y1088131D03*
Y1084785D03*
Y1081438D03*
Y1078092D03*
Y1104863D03*
Y1101517D03*
Y1098171D03*
Y1094824D03*
Y1091478D03*
Y1118249D03*
Y1114903D03*
Y1111556D03*
Y1108210D03*
Y1134982D03*
Y1131635D03*
Y1128289D03*
Y1124942D03*
Y1121596D03*
Y1148367D03*
Y1145021D03*
Y1141675D03*
Y1138328D03*
Y1165100D03*
Y1161753D03*
Y1158407D03*
Y1155060D03*
Y1151714D03*
Y1178486D03*
Y1175139D03*
Y1171793D03*
Y1168446D03*
Y1191871D03*
Y1188525D03*
Y1185178D03*
Y1181832D03*
Y1208604D03*
Y1205257D03*
Y1201911D03*
Y1198564D03*
Y1195218D03*
Y1221989D03*
Y1218643D03*
Y1215297D03*
Y1211950D03*
Y1238722D03*
Y1235375D03*
Y1232029D03*
Y1228682D03*
Y1225336D03*
Y1252108D03*
Y1248761D03*
Y1245415D03*
Y1242068D03*
Y1255454D03*
X1045465Y760177D03*
Y756831D03*
Y776910D03*
Y773563D03*
Y770217D03*
Y766870D03*
Y763524D03*
Y790296D03*
Y786949D03*
Y783603D03*
Y780256D03*
Y807028D03*
Y803681D03*
Y800335D03*
Y796988D03*
Y793642D03*
Y820414D03*
Y817067D03*
Y813721D03*
Y810374D03*
Y837146D03*
Y833799D03*
Y830453D03*
Y827107D03*
Y823760D03*
Y850532D03*
Y847185D03*
Y843839D03*
Y840492D03*
Y863918D03*
Y860571D03*
Y857225D03*
Y853878D03*
Y880650D03*
Y877303D03*
Y873957D03*
Y870610D03*
Y867264D03*
Y894036D03*
Y890689D03*
Y887343D03*
Y883996D03*
Y910768D03*
Y907422D03*
Y904075D03*
Y900729D03*
Y897382D03*
Y924154D03*
Y920807D03*
Y917461D03*
Y914114D03*
Y940886D03*
Y937540D03*
Y934193D03*
Y930847D03*
Y927500D03*
Y954272D03*
Y950925D03*
Y947579D03*
Y944233D03*
Y971004D03*
Y967658D03*
Y964311D03*
Y960965D03*
Y957618D03*
Y984390D03*
Y981044D03*
Y977697D03*
Y974351D03*
Y1001122D03*
Y997776D03*
Y994429D03*
Y991083D03*
Y987736D03*
Y1004469D03*
Y1027894D03*
Y1044626D03*
Y1041280D03*
Y1037933D03*
Y1034587D03*
Y1031240D03*
Y1058012D03*
Y1054666D03*
Y1051319D03*
Y1047973D03*
Y1074744D03*
Y1071398D03*
Y1068051D03*
Y1064705D03*
Y1061359D03*
Y1088130D03*
Y1084784D03*
Y1081437D03*
Y1078091D03*
Y1104862D03*
Y1101516D03*
Y1098170D03*
Y1094823D03*
Y1091477D03*
Y1118248D03*
Y1114902D03*
Y1111555D03*
Y1108209D03*
Y1134981D03*
Y1131634D03*
Y1128288D03*
Y1124941D03*
Y1121595D03*
Y1148366D03*
Y1145020D03*
Y1141674D03*
Y1138327D03*
Y1165099D03*
Y1161752D03*
Y1158406D03*
Y1155059D03*
Y1151713D03*
Y1178485D03*
Y1175138D03*
Y1171792D03*
Y1168445D03*
Y1191870D03*
Y1188524D03*
Y1185177D03*
Y1181831D03*
Y1208603D03*
Y1205256D03*
Y1201910D03*
Y1198563D03*
Y1195217D03*
Y1221988D03*
Y1218642D03*
Y1215296D03*
Y1211949D03*
Y1238721D03*
Y1235374D03*
Y1232028D03*
Y1228681D03*
Y1225335D03*
Y1252107D03*
Y1248760D03*
Y1245414D03*
Y1242067D03*
Y1255453D03*
X1061607Y760177D03*
Y756831D03*
Y776910D03*
Y773563D03*
Y770217D03*
Y766870D03*
Y763524D03*
Y790296D03*
Y786949D03*
Y783603D03*
Y780256D03*
Y807028D03*
Y803681D03*
Y800335D03*
Y796988D03*
Y793642D03*
Y820414D03*
Y817067D03*
Y813721D03*
Y810374D03*
Y837146D03*
Y833799D03*
Y830453D03*
Y827107D03*
Y823760D03*
Y850532D03*
Y847185D03*
Y843839D03*
Y840492D03*
Y863918D03*
Y860571D03*
Y857225D03*
Y853878D03*
Y880650D03*
Y877303D03*
Y873957D03*
Y870610D03*
Y867264D03*
Y894036D03*
Y890689D03*
Y887343D03*
Y883996D03*
Y910768D03*
Y907422D03*
Y904075D03*
Y900729D03*
Y897382D03*
Y924154D03*
Y920807D03*
Y917461D03*
Y914114D03*
Y940886D03*
Y937540D03*
Y934193D03*
Y930847D03*
Y927500D03*
Y954272D03*
Y950925D03*
Y947579D03*
Y944233D03*
Y971004D03*
Y967658D03*
Y964311D03*
Y960965D03*
Y957618D03*
Y984390D03*
Y981044D03*
Y977697D03*
Y974351D03*
Y1001122D03*
Y997776D03*
Y994429D03*
Y991083D03*
Y987736D03*
Y1004469D03*
Y1027894D03*
Y1044626D03*
Y1041280D03*
Y1037933D03*
Y1034587D03*
Y1031240D03*
Y1058012D03*
Y1054666D03*
Y1051319D03*
Y1047973D03*
Y1074744D03*
Y1071398D03*
Y1068051D03*
Y1064705D03*
Y1061359D03*
Y1088130D03*
Y1084784D03*
Y1081437D03*
Y1078091D03*
Y1104862D03*
Y1101516D03*
Y1098170D03*
Y1094823D03*
Y1091477D03*
Y1118248D03*
Y1114902D03*
Y1111555D03*
Y1108209D03*
Y1134981D03*
Y1131634D03*
Y1128288D03*
Y1124941D03*
Y1121595D03*
Y1148366D03*
Y1145020D03*
Y1141674D03*
Y1138327D03*
Y1165099D03*
Y1161752D03*
Y1158406D03*
Y1155059D03*
Y1151713D03*
Y1178485D03*
Y1175138D03*
Y1171792D03*
Y1168445D03*
Y1191870D03*
Y1188524D03*
Y1185177D03*
Y1181831D03*
Y1208603D03*
Y1205256D03*
Y1201910D03*
Y1198563D03*
Y1195217D03*
Y1221988D03*
Y1218642D03*
Y1215296D03*
Y1211949D03*
Y1238721D03*
Y1235374D03*
Y1232028D03*
Y1228681D03*
Y1225335D03*
Y1252107D03*
Y1248760D03*
Y1245414D03*
Y1242067D03*
Y1255453D03*
X1075166Y760177D03*
Y756831D03*
Y776910D03*
Y773563D03*
Y770217D03*
Y766870D03*
Y763524D03*
Y790296D03*
Y786949D03*
Y783603D03*
Y780256D03*
Y807028D03*
Y803681D03*
Y800335D03*
Y796988D03*
Y793642D03*
Y820414D03*
Y817067D03*
Y813721D03*
Y810374D03*
Y837146D03*
Y833799D03*
Y830453D03*
Y827107D03*
Y823760D03*
Y850532D03*
Y847185D03*
Y843839D03*
Y840492D03*
Y863918D03*
Y860571D03*
Y857225D03*
Y853878D03*
Y880650D03*
Y877303D03*
Y873957D03*
Y870610D03*
Y867264D03*
Y894036D03*
Y890689D03*
Y887343D03*
Y883996D03*
Y910768D03*
Y907422D03*
Y904075D03*
Y900729D03*
Y897382D03*
Y924154D03*
Y920807D03*
Y917461D03*
Y914114D03*
Y940886D03*
Y937540D03*
Y934193D03*
Y930847D03*
Y927500D03*
Y954272D03*
Y950925D03*
Y947579D03*
Y944233D03*
Y971004D03*
Y967658D03*
Y964311D03*
Y960965D03*
Y957618D03*
Y984390D03*
Y981044D03*
Y977697D03*
Y974351D03*
Y1001122D03*
Y997776D03*
Y994429D03*
Y991083D03*
Y987736D03*
Y1004469D03*
Y1027894D03*
Y1044626D03*
Y1041280D03*
Y1037933D03*
Y1034587D03*
Y1031240D03*
Y1058012D03*
Y1054666D03*
Y1051319D03*
Y1047973D03*
Y1074744D03*
Y1071398D03*
Y1068051D03*
Y1064705D03*
Y1061359D03*
Y1088130D03*
Y1084784D03*
Y1081437D03*
Y1078091D03*
Y1104862D03*
Y1101516D03*
Y1098170D03*
Y1094823D03*
Y1091477D03*
Y1118248D03*
Y1114902D03*
Y1111555D03*
Y1108209D03*
Y1134981D03*
Y1131634D03*
Y1128288D03*
Y1124941D03*
Y1121595D03*
Y1148366D03*
Y1145020D03*
Y1141674D03*
Y1138327D03*
Y1165099D03*
Y1161752D03*
Y1158406D03*
Y1155059D03*
Y1151713D03*
Y1178485D03*
Y1175138D03*
Y1171792D03*
Y1168445D03*
Y1191870D03*
Y1188524D03*
Y1185177D03*
Y1181831D03*
Y1208603D03*
Y1205256D03*
Y1201910D03*
Y1198563D03*
Y1195217D03*
Y1221988D03*
Y1218642D03*
Y1215296D03*
Y1211949D03*
Y1238721D03*
Y1235374D03*
Y1232028D03*
Y1228681D03*
Y1225335D03*
Y1252107D03*
Y1248760D03*
Y1245414D03*
Y1242067D03*
Y1255453D03*
X1091308Y760177D03*
Y756831D03*
Y776910D03*
Y773563D03*
Y770217D03*
Y766870D03*
Y763524D03*
Y790296D03*
Y786949D03*
Y783603D03*
Y780256D03*
Y807028D03*
Y803681D03*
Y800335D03*
Y796988D03*
Y793642D03*
Y820414D03*
Y817067D03*
Y813721D03*
Y810374D03*
Y837146D03*
Y833799D03*
Y830453D03*
Y827107D03*
Y823760D03*
Y850532D03*
Y847185D03*
Y843839D03*
Y840492D03*
Y863918D03*
Y860571D03*
Y857225D03*
Y853878D03*
Y880650D03*
Y877303D03*
Y873957D03*
Y870610D03*
Y867264D03*
Y894036D03*
Y890689D03*
Y887343D03*
Y883996D03*
Y910768D03*
Y907422D03*
Y904075D03*
Y900729D03*
Y897382D03*
Y924154D03*
Y920807D03*
Y917461D03*
Y914114D03*
Y940886D03*
Y937540D03*
Y934193D03*
Y930847D03*
Y927500D03*
Y954272D03*
Y950925D03*
Y947579D03*
Y944233D03*
Y971004D03*
Y967658D03*
Y964311D03*
Y960965D03*
Y957618D03*
Y984390D03*
Y981044D03*
Y977697D03*
Y974351D03*
Y1001122D03*
Y997776D03*
Y994429D03*
Y991083D03*
Y987736D03*
Y1004469D03*
Y1027894D03*
Y1044626D03*
Y1041280D03*
Y1037933D03*
Y1034587D03*
Y1031240D03*
Y1058012D03*
Y1054666D03*
Y1051319D03*
Y1047973D03*
Y1074744D03*
Y1071398D03*
Y1068051D03*
Y1064705D03*
Y1061359D03*
Y1088130D03*
Y1084784D03*
Y1081437D03*
Y1078091D03*
Y1104862D03*
Y1101516D03*
Y1098170D03*
Y1094823D03*
Y1091477D03*
Y1118248D03*
Y1114902D03*
Y1111555D03*
Y1108209D03*
Y1134981D03*
Y1131634D03*
Y1128288D03*
Y1124941D03*
Y1121595D03*
Y1148366D03*
Y1145020D03*
Y1141674D03*
Y1138327D03*
Y1165099D03*
Y1161752D03*
Y1158406D03*
Y1155059D03*
Y1151713D03*
Y1178485D03*
Y1175138D03*
Y1171792D03*
Y1168445D03*
Y1191870D03*
Y1188524D03*
Y1185177D03*
Y1181831D03*
Y1208603D03*
Y1205256D03*
Y1201910D03*
Y1198563D03*
Y1195217D03*
Y1221988D03*
Y1218642D03*
Y1215296D03*
Y1211949D03*
Y1238721D03*
Y1235374D03*
Y1232028D03*
Y1228681D03*
Y1225335D03*
Y1252107D03*
Y1248760D03*
Y1245414D03*
Y1242067D03*
Y1255453D03*
X1104866Y760177D03*
Y756831D03*
Y776910D03*
Y773563D03*
Y770217D03*
Y766870D03*
Y763524D03*
Y790296D03*
Y786949D03*
Y783603D03*
Y780256D03*
Y807028D03*
Y803681D03*
Y800335D03*
Y796988D03*
Y793642D03*
Y820414D03*
Y817067D03*
Y813721D03*
Y810374D03*
Y837146D03*
Y833799D03*
Y830453D03*
Y827107D03*
Y823760D03*
Y850532D03*
Y847185D03*
Y843839D03*
Y840492D03*
Y863918D03*
Y860571D03*
Y857225D03*
Y853878D03*
Y880650D03*
Y877303D03*
Y873957D03*
Y870610D03*
Y867264D03*
Y894036D03*
Y890689D03*
Y887343D03*
Y883996D03*
Y910768D03*
Y907422D03*
Y904075D03*
Y900729D03*
Y897382D03*
Y924154D03*
Y920807D03*
Y917461D03*
Y914114D03*
Y940886D03*
Y937540D03*
Y934193D03*
Y930847D03*
Y927500D03*
Y954272D03*
Y950925D03*
Y947579D03*
Y944233D03*
Y971004D03*
Y967658D03*
Y964311D03*
Y960965D03*
Y957618D03*
Y984390D03*
Y981044D03*
Y977697D03*
Y974351D03*
Y1001122D03*
Y997776D03*
Y994429D03*
Y991083D03*
Y987736D03*
Y1004469D03*
Y1027894D03*
Y1044626D03*
Y1041280D03*
Y1037933D03*
Y1034587D03*
Y1031240D03*
Y1058012D03*
Y1054666D03*
Y1051319D03*
Y1047973D03*
Y1074744D03*
Y1071398D03*
Y1068051D03*
Y1064705D03*
Y1061359D03*
Y1088130D03*
Y1084784D03*
Y1081437D03*
Y1078091D03*
Y1104862D03*
Y1101516D03*
Y1098170D03*
Y1094823D03*
Y1091477D03*
Y1118248D03*
Y1114902D03*
Y1111555D03*
Y1108209D03*
Y1134981D03*
Y1131634D03*
Y1128288D03*
Y1124941D03*
Y1121595D03*
Y1148366D03*
Y1145020D03*
Y1141674D03*
Y1138327D03*
Y1165099D03*
Y1161752D03*
Y1158406D03*
Y1155059D03*
Y1151713D03*
Y1178485D03*
Y1175138D03*
Y1171792D03*
Y1168445D03*
Y1191870D03*
Y1188524D03*
Y1185177D03*
Y1181831D03*
Y1208603D03*
Y1205256D03*
Y1201910D03*
Y1198563D03*
Y1195217D03*
Y1221988D03*
Y1218642D03*
Y1215296D03*
Y1211949D03*
Y1238721D03*
Y1235374D03*
Y1232028D03*
Y1228681D03*
Y1225335D03*
Y1252107D03*
Y1248760D03*
Y1245414D03*
Y1242067D03*
Y1255453D03*
X1121008Y760177D03*
Y756831D03*
Y776910D03*
Y773563D03*
Y770217D03*
Y766870D03*
Y763524D03*
Y790296D03*
Y786949D03*
Y783603D03*
Y780256D03*
Y807028D03*
Y803681D03*
Y800335D03*
Y796988D03*
Y793642D03*
Y820414D03*
Y817067D03*
Y813721D03*
Y810374D03*
Y837146D03*
Y833799D03*
Y830453D03*
Y827107D03*
Y823760D03*
Y850532D03*
Y847185D03*
Y843839D03*
Y840492D03*
Y863918D03*
Y860571D03*
Y857225D03*
Y853878D03*
Y880650D03*
Y877303D03*
Y873957D03*
Y870610D03*
Y867264D03*
Y894036D03*
Y890689D03*
Y887343D03*
Y883996D03*
Y910768D03*
Y907422D03*
Y904075D03*
Y900729D03*
Y897382D03*
Y924154D03*
Y920807D03*
Y917461D03*
Y914114D03*
Y940886D03*
Y937540D03*
Y934193D03*
Y930847D03*
Y927500D03*
Y954272D03*
Y950925D03*
Y947579D03*
Y944233D03*
Y971004D03*
Y967658D03*
Y964311D03*
Y960965D03*
Y957618D03*
Y984390D03*
Y981044D03*
Y977697D03*
Y974351D03*
Y1001122D03*
Y997776D03*
Y994429D03*
Y991083D03*
Y987736D03*
Y1004469D03*
Y1027894D03*
Y1044626D03*
Y1041280D03*
Y1037933D03*
Y1034587D03*
Y1031240D03*
Y1058012D03*
Y1054666D03*
Y1051319D03*
Y1047973D03*
Y1074744D03*
Y1071398D03*
Y1068051D03*
Y1064705D03*
Y1061359D03*
Y1088130D03*
Y1084784D03*
Y1081437D03*
Y1078091D03*
Y1104862D03*
Y1101516D03*
Y1098170D03*
Y1094823D03*
Y1091477D03*
Y1118248D03*
Y1114902D03*
Y1111555D03*
Y1108209D03*
Y1134981D03*
Y1131634D03*
Y1128288D03*
Y1124941D03*
Y1121595D03*
Y1148366D03*
Y1145020D03*
Y1141674D03*
Y1138327D03*
Y1165099D03*
Y1161752D03*
Y1158406D03*
Y1155059D03*
Y1151713D03*
Y1178485D03*
Y1175138D03*
Y1171792D03*
Y1168445D03*
Y1191870D03*
Y1188524D03*
Y1185177D03*
Y1181831D03*
Y1208603D03*
Y1205256D03*
Y1201910D03*
Y1198563D03*
Y1195217D03*
Y1221988D03*
Y1218642D03*
Y1215296D03*
Y1211949D03*
Y1238721D03*
Y1235374D03*
Y1232028D03*
Y1228681D03*
Y1225335D03*
Y1252107D03*
Y1248760D03*
Y1245414D03*
Y1242067D03*
Y1255453D03*
X1134567Y760177D03*
Y756831D03*
Y776910D03*
Y773563D03*
Y770217D03*
Y766870D03*
Y763524D03*
Y790296D03*
Y786949D03*
Y783603D03*
Y780256D03*
Y807028D03*
Y803681D03*
Y800335D03*
Y796988D03*
Y793642D03*
Y820414D03*
Y817067D03*
Y813721D03*
Y810374D03*
Y837146D03*
Y833799D03*
Y830453D03*
Y827107D03*
Y823760D03*
Y850532D03*
Y847185D03*
Y843839D03*
Y840492D03*
Y863918D03*
Y860571D03*
Y857225D03*
Y853878D03*
Y880650D03*
Y877303D03*
Y873957D03*
Y870610D03*
Y867264D03*
Y894036D03*
Y890689D03*
Y887343D03*
Y883996D03*
Y910768D03*
Y907422D03*
Y904075D03*
Y900729D03*
Y897382D03*
Y924154D03*
Y920807D03*
Y917461D03*
Y914114D03*
Y940886D03*
Y937540D03*
Y934193D03*
Y930847D03*
Y927500D03*
Y954272D03*
Y950925D03*
Y947579D03*
Y944233D03*
Y971004D03*
Y967658D03*
Y964311D03*
Y960965D03*
Y957618D03*
Y984390D03*
Y981044D03*
Y977697D03*
Y974351D03*
Y1001122D03*
Y997776D03*
Y994429D03*
Y991083D03*
Y987736D03*
Y1004469D03*
Y1027894D03*
Y1044626D03*
Y1041280D03*
Y1037933D03*
Y1034587D03*
Y1031240D03*
Y1058012D03*
Y1054666D03*
Y1051319D03*
Y1047973D03*
Y1074744D03*
Y1071398D03*
Y1068051D03*
Y1064705D03*
Y1061359D03*
Y1088130D03*
Y1084784D03*
Y1081437D03*
Y1078091D03*
Y1104862D03*
Y1101516D03*
Y1098170D03*
Y1094823D03*
Y1091477D03*
Y1118248D03*
Y1114902D03*
Y1111555D03*
Y1108209D03*
Y1134981D03*
Y1131634D03*
Y1128288D03*
Y1124941D03*
Y1121595D03*
Y1148366D03*
Y1145020D03*
Y1141674D03*
Y1138327D03*
Y1165099D03*
Y1161752D03*
Y1158406D03*
Y1155059D03*
Y1151713D03*
Y1178485D03*
Y1175138D03*
Y1171792D03*
Y1168445D03*
Y1191870D03*
Y1188524D03*
Y1185177D03*
Y1181831D03*
Y1208603D03*
Y1205256D03*
Y1201910D03*
Y1198563D03*
Y1195217D03*
Y1221988D03*
Y1218642D03*
Y1215296D03*
Y1211949D03*
Y1238721D03*
Y1235374D03*
Y1232028D03*
Y1228681D03*
Y1225335D03*
Y1252107D03*
Y1248760D03*
Y1245414D03*
Y1242067D03*
Y1255453D03*
X1150709Y760177D03*
Y756831D03*
Y776910D03*
Y773563D03*
Y770217D03*
Y766870D03*
Y763524D03*
Y790296D03*
Y786949D03*
Y783603D03*
Y780256D03*
Y807028D03*
Y803681D03*
Y800335D03*
Y796988D03*
Y793642D03*
Y820414D03*
Y817067D03*
Y813721D03*
Y810374D03*
Y837146D03*
Y833799D03*
Y830453D03*
Y827107D03*
Y823760D03*
Y850532D03*
Y847185D03*
Y843839D03*
Y840492D03*
Y863918D03*
Y860571D03*
Y857225D03*
Y853878D03*
Y880650D03*
Y877303D03*
Y873957D03*
Y870610D03*
Y867264D03*
Y894036D03*
Y890689D03*
Y887343D03*
Y883996D03*
Y910768D03*
Y907422D03*
Y904075D03*
Y900729D03*
Y897382D03*
Y924154D03*
Y920807D03*
Y917461D03*
Y914114D03*
Y940886D03*
Y937540D03*
Y934193D03*
Y930847D03*
Y927500D03*
Y954272D03*
Y950925D03*
Y947579D03*
Y944233D03*
Y971004D03*
Y967658D03*
Y964311D03*
Y960965D03*
Y957618D03*
Y984390D03*
Y981044D03*
Y977697D03*
Y974351D03*
Y1001122D03*
Y997776D03*
Y994429D03*
Y991083D03*
Y987736D03*
Y1004469D03*
Y1027894D03*
Y1044626D03*
Y1041280D03*
Y1037933D03*
Y1034587D03*
Y1031240D03*
Y1058012D03*
Y1054666D03*
Y1051319D03*
Y1047973D03*
Y1074744D03*
Y1071398D03*
Y1068051D03*
Y1064705D03*
Y1061359D03*
Y1088130D03*
Y1084784D03*
Y1081437D03*
Y1078091D03*
Y1104862D03*
Y1101516D03*
Y1098170D03*
Y1094823D03*
Y1091477D03*
Y1118248D03*
Y1114902D03*
Y1111555D03*
Y1108209D03*
Y1134981D03*
Y1131634D03*
Y1128288D03*
Y1124941D03*
Y1121595D03*
Y1148366D03*
Y1145020D03*
Y1141674D03*
Y1138327D03*
Y1165099D03*
Y1161752D03*
Y1158406D03*
Y1155059D03*
Y1151713D03*
Y1178485D03*
Y1175138D03*
Y1171792D03*
Y1168445D03*
Y1191870D03*
Y1188524D03*
Y1185177D03*
Y1181831D03*
Y1208603D03*
Y1205256D03*
Y1201910D03*
Y1198563D03*
Y1195217D03*
Y1221988D03*
Y1218642D03*
Y1215296D03*
Y1211949D03*
Y1238721D03*
Y1235374D03*
Y1232028D03*
Y1228681D03*
Y1225335D03*
Y1252107D03*
Y1248760D03*
Y1245414D03*
Y1242067D03*
Y1255453D03*
X1164268Y760177D03*
Y756831D03*
Y776910D03*
Y773563D03*
Y770217D03*
Y766870D03*
Y763524D03*
Y790296D03*
Y786949D03*
Y783603D03*
Y780256D03*
Y807028D03*
Y803681D03*
Y800335D03*
Y796988D03*
Y793642D03*
Y820414D03*
Y817067D03*
Y813721D03*
Y810374D03*
Y837146D03*
Y833799D03*
Y830453D03*
Y827107D03*
Y823760D03*
Y850532D03*
Y847185D03*
Y843839D03*
Y840492D03*
Y863918D03*
Y860571D03*
Y857225D03*
Y853878D03*
Y880650D03*
Y877303D03*
Y873957D03*
Y870610D03*
Y867264D03*
Y894036D03*
Y890689D03*
Y887343D03*
Y883996D03*
Y910768D03*
Y907422D03*
Y904075D03*
Y900729D03*
Y897382D03*
Y924154D03*
Y920807D03*
Y917461D03*
Y914114D03*
Y940886D03*
Y937540D03*
Y934193D03*
Y930847D03*
Y927500D03*
Y954272D03*
Y950925D03*
Y947579D03*
Y944233D03*
Y971004D03*
Y967658D03*
Y964311D03*
Y960965D03*
Y957618D03*
Y984390D03*
Y981044D03*
Y977697D03*
Y974351D03*
Y1001122D03*
Y997776D03*
Y994429D03*
Y991083D03*
Y987736D03*
Y1004469D03*
Y1027894D03*
Y1044626D03*
Y1041280D03*
Y1037933D03*
Y1034587D03*
Y1031240D03*
Y1058012D03*
Y1054666D03*
Y1051319D03*
Y1047973D03*
Y1074744D03*
Y1071398D03*
Y1068051D03*
Y1064705D03*
Y1061359D03*
Y1088130D03*
Y1084784D03*
Y1081437D03*
Y1078091D03*
Y1104862D03*
Y1101516D03*
Y1098170D03*
Y1094823D03*
Y1091477D03*
Y1118248D03*
Y1114902D03*
Y1111555D03*
Y1108209D03*
Y1134981D03*
Y1131634D03*
Y1128288D03*
Y1124941D03*
Y1121595D03*
Y1148366D03*
Y1145020D03*
Y1141674D03*
Y1138327D03*
Y1165099D03*
Y1161752D03*
Y1158406D03*
Y1155059D03*
Y1151713D03*
Y1178485D03*
Y1175138D03*
Y1171792D03*
Y1168445D03*
Y1191870D03*
Y1188524D03*
Y1185177D03*
Y1181831D03*
Y1208603D03*
Y1205256D03*
Y1201910D03*
Y1198563D03*
Y1195217D03*
Y1221988D03*
Y1218642D03*
Y1215296D03*
Y1211949D03*
Y1238721D03*
Y1235374D03*
Y1232028D03*
Y1228681D03*
Y1225335D03*
Y1252107D03*
Y1248760D03*
Y1245414D03*
Y1242067D03*
Y1255453D03*
X1180410Y760177D03*
Y756831D03*
Y776910D03*
Y773563D03*
Y770217D03*
Y766870D03*
Y763524D03*
Y790296D03*
Y786949D03*
Y783603D03*
Y780256D03*
Y807028D03*
Y803681D03*
Y800335D03*
Y796988D03*
Y793642D03*
Y820414D03*
Y817067D03*
Y813721D03*
Y810374D03*
Y837146D03*
Y833799D03*
Y830453D03*
Y827107D03*
Y823760D03*
Y850532D03*
Y847185D03*
Y843839D03*
Y840492D03*
Y863918D03*
Y860571D03*
Y857225D03*
Y853878D03*
Y880650D03*
Y877303D03*
Y873957D03*
Y870610D03*
Y867264D03*
Y894036D03*
Y890689D03*
Y887343D03*
Y883996D03*
Y910768D03*
Y907422D03*
Y904075D03*
Y900729D03*
Y897382D03*
Y924154D03*
Y920807D03*
Y917461D03*
Y914114D03*
Y940886D03*
Y937540D03*
Y934193D03*
Y930847D03*
Y927500D03*
Y954272D03*
Y950925D03*
Y947579D03*
Y944233D03*
Y971004D03*
Y967658D03*
Y964311D03*
Y960965D03*
Y957618D03*
Y984390D03*
Y981044D03*
Y977697D03*
Y974351D03*
Y1001122D03*
Y997776D03*
Y994429D03*
Y991083D03*
Y987736D03*
Y1004469D03*
Y1027894D03*
Y1044626D03*
Y1041280D03*
Y1037933D03*
Y1034587D03*
Y1031240D03*
Y1058012D03*
Y1054666D03*
Y1051319D03*
Y1047973D03*
Y1074744D03*
Y1071398D03*
Y1068051D03*
Y1064705D03*
Y1061359D03*
Y1088130D03*
Y1084784D03*
Y1081437D03*
Y1078091D03*
Y1104862D03*
Y1101516D03*
Y1098170D03*
Y1094823D03*
Y1091477D03*
Y1118248D03*
Y1114902D03*
Y1111555D03*
Y1108209D03*
Y1134981D03*
Y1131634D03*
Y1128288D03*
Y1124941D03*
Y1121595D03*
Y1148366D03*
Y1145020D03*
Y1141674D03*
Y1138327D03*
Y1165099D03*
Y1161752D03*
Y1158406D03*
Y1155059D03*
Y1151713D03*
Y1178485D03*
Y1175138D03*
Y1171792D03*
Y1168445D03*
Y1191870D03*
Y1188524D03*
Y1185177D03*
Y1181831D03*
Y1208603D03*
Y1205256D03*
Y1201910D03*
Y1198563D03*
Y1195217D03*
Y1221988D03*
Y1218642D03*
Y1215296D03*
Y1211949D03*
Y1238721D03*
Y1235374D03*
Y1232028D03*
Y1228681D03*
Y1225335D03*
Y1252107D03*
Y1248760D03*
Y1245414D03*
Y1242067D03*
Y1255453D03*
X1193969Y760177D03*
Y756831D03*
Y776910D03*
Y773563D03*
Y770217D03*
Y766870D03*
Y763524D03*
Y790296D03*
Y786949D03*
Y783603D03*
Y780256D03*
Y807028D03*
Y803681D03*
Y800335D03*
Y796988D03*
Y793642D03*
Y820414D03*
Y817067D03*
Y813721D03*
Y810374D03*
Y837146D03*
Y833799D03*
Y830453D03*
Y827107D03*
Y823760D03*
Y850532D03*
Y847185D03*
Y843839D03*
Y840492D03*
Y863918D03*
Y860571D03*
Y857225D03*
Y853878D03*
Y880650D03*
Y877303D03*
Y873957D03*
Y870610D03*
Y867264D03*
Y894036D03*
Y890689D03*
Y887343D03*
Y883996D03*
Y910768D03*
Y907422D03*
Y904075D03*
Y900729D03*
Y897382D03*
Y924154D03*
Y920807D03*
Y917461D03*
Y914114D03*
Y940886D03*
Y937540D03*
Y934193D03*
Y930847D03*
Y927500D03*
Y954272D03*
Y950925D03*
Y947579D03*
Y944233D03*
Y971004D03*
Y967658D03*
Y964311D03*
Y960965D03*
Y957618D03*
Y984390D03*
Y981044D03*
Y977697D03*
Y974351D03*
Y1001122D03*
Y997776D03*
Y994429D03*
Y991083D03*
Y987736D03*
Y1004469D03*
Y1027894D03*
Y1044626D03*
Y1041280D03*
Y1037933D03*
Y1034587D03*
Y1031240D03*
Y1058012D03*
Y1054666D03*
Y1051319D03*
Y1047973D03*
Y1074744D03*
Y1071398D03*
Y1068051D03*
Y1064705D03*
Y1061359D03*
Y1088130D03*
Y1084784D03*
Y1081437D03*
Y1078091D03*
Y1104862D03*
Y1101516D03*
Y1098170D03*
Y1094823D03*
Y1091477D03*
Y1118248D03*
Y1114902D03*
Y1111555D03*
Y1108209D03*
Y1134981D03*
Y1131634D03*
Y1128288D03*
Y1124941D03*
Y1121595D03*
Y1148366D03*
Y1145020D03*
Y1141674D03*
Y1138327D03*
Y1165099D03*
Y1161752D03*
Y1158406D03*
Y1155059D03*
Y1151713D03*
Y1178485D03*
Y1175138D03*
Y1171792D03*
Y1168445D03*
Y1191870D03*
Y1188524D03*
Y1185177D03*
Y1181831D03*
Y1208603D03*
Y1205256D03*
Y1201910D03*
Y1198563D03*
Y1195217D03*
Y1221988D03*
Y1218642D03*
Y1215296D03*
Y1211949D03*
Y1238721D03*
Y1235374D03*
Y1232028D03*
Y1228681D03*
Y1225335D03*
Y1252107D03*
Y1248760D03*
Y1245414D03*
Y1242067D03*
Y1255453D03*
X1210111Y760177D03*
Y756831D03*
Y776910D03*
Y773563D03*
Y770217D03*
Y766870D03*
Y763524D03*
Y790296D03*
Y786949D03*
Y783603D03*
Y780256D03*
Y807028D03*
Y803681D03*
Y800335D03*
Y796988D03*
Y793642D03*
Y820414D03*
Y817067D03*
Y813721D03*
Y810374D03*
Y837146D03*
Y833799D03*
Y830453D03*
Y827107D03*
Y823760D03*
Y850532D03*
Y847185D03*
Y843839D03*
Y840492D03*
Y863918D03*
Y860571D03*
Y857225D03*
Y853878D03*
Y880650D03*
Y877303D03*
Y873957D03*
Y870610D03*
Y867264D03*
Y894036D03*
Y890689D03*
Y887343D03*
Y883996D03*
Y910768D03*
Y907422D03*
Y904075D03*
Y900729D03*
Y897382D03*
Y924154D03*
Y920807D03*
Y917461D03*
Y914114D03*
Y940886D03*
Y937540D03*
Y934193D03*
Y930847D03*
Y927500D03*
Y954272D03*
Y950925D03*
Y947579D03*
Y944233D03*
Y971004D03*
Y967658D03*
Y964311D03*
Y960965D03*
Y957618D03*
Y984390D03*
Y981044D03*
Y977697D03*
Y974351D03*
Y1001122D03*
Y997776D03*
Y994429D03*
Y991083D03*
Y987736D03*
Y1004469D03*
Y1027894D03*
Y1044626D03*
Y1041280D03*
Y1037933D03*
Y1034587D03*
Y1031240D03*
Y1058012D03*
Y1054666D03*
Y1051319D03*
Y1047973D03*
Y1074744D03*
Y1071398D03*
Y1068051D03*
Y1064705D03*
Y1061359D03*
Y1088130D03*
Y1084784D03*
Y1081437D03*
Y1078091D03*
Y1104862D03*
Y1101516D03*
Y1098170D03*
Y1094823D03*
Y1091477D03*
Y1118248D03*
Y1114902D03*
Y1111555D03*
Y1108209D03*
Y1134981D03*
Y1131634D03*
Y1128288D03*
Y1124941D03*
Y1121595D03*
Y1148366D03*
Y1145020D03*
Y1141674D03*
Y1138327D03*
Y1165099D03*
Y1161752D03*
Y1158406D03*
Y1155059D03*
Y1151713D03*
Y1178485D03*
Y1175138D03*
Y1171792D03*
Y1168445D03*
Y1191870D03*
Y1188524D03*
Y1185177D03*
Y1181831D03*
Y1208603D03*
Y1205256D03*
Y1201910D03*
Y1198563D03*
Y1195217D03*
Y1221988D03*
Y1218642D03*
Y1215296D03*
Y1211949D03*
Y1238721D03*
Y1235374D03*
Y1232028D03*
Y1228681D03*
Y1225335D03*
Y1252107D03*
Y1248760D03*
Y1245414D03*
Y1242067D03*
Y1255453D03*
X1623496Y760177D03*
Y756831D03*
Y776910D03*
Y773563D03*
Y770217D03*
Y766870D03*
Y763524D03*
Y790296D03*
Y786949D03*
Y783603D03*
Y780256D03*
Y807028D03*
Y803681D03*
Y800335D03*
Y796988D03*
Y793642D03*
Y820414D03*
Y817067D03*
Y813721D03*
Y810374D03*
Y837146D03*
Y833799D03*
Y830453D03*
Y827107D03*
Y823760D03*
Y850532D03*
Y847185D03*
Y843839D03*
Y840492D03*
Y863918D03*
Y860571D03*
Y857225D03*
Y853878D03*
Y880650D03*
Y877303D03*
Y873957D03*
Y870610D03*
Y867264D03*
Y894036D03*
Y890689D03*
Y887343D03*
Y883996D03*
Y910768D03*
Y907422D03*
Y904075D03*
Y900729D03*
Y897382D03*
Y924154D03*
Y920807D03*
Y917461D03*
Y914114D03*
Y940886D03*
Y937540D03*
Y934193D03*
Y930847D03*
Y927500D03*
Y954272D03*
Y950925D03*
Y947579D03*
Y944233D03*
Y971004D03*
Y967658D03*
Y964311D03*
Y960965D03*
Y957618D03*
Y984390D03*
Y981044D03*
Y977697D03*
Y974351D03*
Y1001122D03*
Y997776D03*
Y994429D03*
Y991083D03*
Y987736D03*
Y1004469D03*
Y1027894D03*
Y1044626D03*
Y1041280D03*
Y1037933D03*
Y1034587D03*
Y1031240D03*
Y1058012D03*
Y1054666D03*
Y1051319D03*
Y1047973D03*
Y1074744D03*
Y1071398D03*
Y1068051D03*
Y1064705D03*
Y1061359D03*
Y1088130D03*
Y1084784D03*
Y1081437D03*
Y1078091D03*
Y1104862D03*
Y1101516D03*
Y1098170D03*
Y1094823D03*
Y1091477D03*
Y1118248D03*
Y1114902D03*
Y1111555D03*
Y1108209D03*
Y1134981D03*
Y1131634D03*
Y1128288D03*
Y1124941D03*
Y1121595D03*
Y1148366D03*
Y1145020D03*
Y1141674D03*
Y1138327D03*
Y1165099D03*
Y1161752D03*
Y1158406D03*
Y1155059D03*
Y1151713D03*
Y1178485D03*
Y1175138D03*
Y1171792D03*
Y1168445D03*
Y1191870D03*
Y1188524D03*
Y1185177D03*
Y1181831D03*
Y1208603D03*
Y1205256D03*
Y1201910D03*
Y1198563D03*
Y1195217D03*
Y1221988D03*
Y1218642D03*
Y1215296D03*
Y1211949D03*
Y1238721D03*
Y1235374D03*
Y1232028D03*
Y1228681D03*
Y1225335D03*
Y1252107D03*
Y1248760D03*
Y1245414D03*
Y1242067D03*
Y1255453D03*
X1639638Y760177D03*
Y756831D03*
Y776910D03*
Y773563D03*
Y770217D03*
Y766870D03*
Y763524D03*
Y790296D03*
Y786949D03*
Y783603D03*
Y780256D03*
Y807028D03*
Y803681D03*
Y800335D03*
Y796988D03*
Y793642D03*
Y820414D03*
Y817067D03*
Y813721D03*
Y810374D03*
Y837146D03*
Y833799D03*
Y830453D03*
Y827107D03*
Y823760D03*
Y850532D03*
Y847185D03*
Y843839D03*
Y840492D03*
Y863918D03*
Y860571D03*
Y857225D03*
Y853878D03*
Y880650D03*
Y877303D03*
Y873957D03*
Y870610D03*
Y867264D03*
Y894036D03*
Y890689D03*
Y887343D03*
Y883996D03*
Y910768D03*
Y907422D03*
Y904075D03*
Y900729D03*
Y897382D03*
Y924154D03*
Y920807D03*
Y917461D03*
Y914114D03*
Y940886D03*
Y937540D03*
Y934193D03*
Y930847D03*
Y927500D03*
Y954272D03*
Y950925D03*
Y947579D03*
Y944233D03*
Y971004D03*
Y967658D03*
Y964311D03*
Y960965D03*
Y957618D03*
Y984390D03*
Y981044D03*
Y977697D03*
Y974351D03*
Y1001122D03*
Y997776D03*
Y994429D03*
Y991083D03*
Y987736D03*
Y1004469D03*
Y1027894D03*
Y1044626D03*
Y1041280D03*
Y1037933D03*
Y1034587D03*
Y1031240D03*
Y1058012D03*
Y1054666D03*
Y1051319D03*
Y1047973D03*
Y1074744D03*
Y1071398D03*
Y1068051D03*
Y1064705D03*
Y1061359D03*
Y1088130D03*
Y1084784D03*
Y1081437D03*
Y1078091D03*
Y1104862D03*
Y1101516D03*
Y1098170D03*
Y1094823D03*
Y1091477D03*
Y1118248D03*
Y1114902D03*
Y1111555D03*
Y1108209D03*
Y1134981D03*
Y1131634D03*
Y1128288D03*
Y1124941D03*
Y1121595D03*
Y1148366D03*
Y1145020D03*
Y1141674D03*
Y1138327D03*
Y1165099D03*
Y1161752D03*
Y1158406D03*
Y1155059D03*
Y1151713D03*
Y1178485D03*
Y1175138D03*
Y1171792D03*
Y1168445D03*
Y1191870D03*
Y1188524D03*
Y1185177D03*
Y1181831D03*
Y1208603D03*
Y1205256D03*
Y1201910D03*
Y1198563D03*
Y1195217D03*
Y1221988D03*
Y1218642D03*
Y1215296D03*
Y1211949D03*
Y1238721D03*
Y1235374D03*
Y1232028D03*
Y1228681D03*
Y1225335D03*
Y1252107D03*
Y1248760D03*
Y1245414D03*
Y1242067D03*
Y1255453D03*
X1653197Y760177D03*
Y756831D03*
Y776910D03*
Y773563D03*
Y770217D03*
Y766870D03*
Y763524D03*
Y790296D03*
Y786949D03*
Y783603D03*
Y780256D03*
Y807028D03*
Y803681D03*
Y800335D03*
Y796988D03*
Y793642D03*
Y820414D03*
Y817067D03*
Y813721D03*
Y810374D03*
Y837146D03*
Y833799D03*
Y830453D03*
Y827107D03*
Y823760D03*
Y850532D03*
Y847185D03*
Y843839D03*
Y840492D03*
Y863918D03*
Y860571D03*
Y857225D03*
Y853878D03*
Y880650D03*
Y877303D03*
Y873957D03*
Y870610D03*
Y867264D03*
Y894036D03*
Y890689D03*
Y887343D03*
Y883996D03*
Y910768D03*
Y907422D03*
Y904075D03*
Y900729D03*
Y897382D03*
Y924154D03*
Y920807D03*
Y917461D03*
Y914114D03*
Y940886D03*
Y937540D03*
Y934193D03*
Y930847D03*
Y927500D03*
Y954272D03*
Y950925D03*
Y947579D03*
Y944233D03*
Y971004D03*
Y967658D03*
Y964311D03*
Y960965D03*
Y957618D03*
Y984390D03*
Y981044D03*
Y977697D03*
Y974351D03*
Y1001122D03*
Y997776D03*
Y994429D03*
Y991083D03*
Y987736D03*
Y1004469D03*
Y1027894D03*
Y1044626D03*
Y1041280D03*
Y1037933D03*
Y1034587D03*
Y1031240D03*
Y1058012D03*
Y1054666D03*
Y1051319D03*
Y1047973D03*
Y1074744D03*
Y1071398D03*
Y1068051D03*
Y1064705D03*
Y1061359D03*
Y1088130D03*
Y1084784D03*
Y1081437D03*
Y1078091D03*
Y1104862D03*
Y1101516D03*
Y1098170D03*
Y1094823D03*
Y1091477D03*
Y1118248D03*
Y1114902D03*
Y1111555D03*
Y1108209D03*
Y1134981D03*
Y1131634D03*
Y1128288D03*
Y1124941D03*
Y1121595D03*
Y1148366D03*
Y1145020D03*
Y1141674D03*
Y1138327D03*
Y1165099D03*
Y1161752D03*
Y1158406D03*
Y1155059D03*
Y1151713D03*
Y1178485D03*
Y1175138D03*
Y1171792D03*
Y1168445D03*
Y1191870D03*
Y1188524D03*
Y1185177D03*
Y1181831D03*
Y1208603D03*
Y1205256D03*
Y1201910D03*
Y1198563D03*
Y1195217D03*
Y1221988D03*
Y1218642D03*
Y1215296D03*
Y1211949D03*
Y1238721D03*
Y1235374D03*
Y1232028D03*
Y1228681D03*
Y1225335D03*
Y1252107D03*
Y1248760D03*
Y1245414D03*
Y1242067D03*
Y1255453D03*
X1669339Y760177D03*
Y756831D03*
Y776910D03*
Y773563D03*
Y770217D03*
Y766870D03*
Y763524D03*
Y790296D03*
Y786949D03*
Y783603D03*
Y780256D03*
Y807028D03*
Y803681D03*
Y800335D03*
Y796988D03*
Y793642D03*
Y820414D03*
Y817067D03*
Y813721D03*
Y810374D03*
Y837146D03*
Y833799D03*
Y830453D03*
Y827107D03*
Y823760D03*
Y850532D03*
Y847185D03*
Y843839D03*
Y840492D03*
Y863918D03*
Y860571D03*
Y857225D03*
Y853878D03*
Y880650D03*
Y877303D03*
Y873957D03*
Y870610D03*
Y867264D03*
Y894036D03*
Y890689D03*
Y887343D03*
Y883996D03*
Y910768D03*
Y907422D03*
Y904075D03*
Y900729D03*
Y897382D03*
Y924154D03*
Y920807D03*
Y917461D03*
Y914114D03*
Y940886D03*
Y937540D03*
Y934193D03*
Y930847D03*
Y927500D03*
Y954272D03*
Y950925D03*
Y947579D03*
Y944233D03*
Y971004D03*
Y967658D03*
Y964311D03*
Y960965D03*
Y957618D03*
Y984390D03*
Y981044D03*
Y977697D03*
Y974351D03*
Y1001122D03*
Y997776D03*
Y994429D03*
Y991083D03*
Y987736D03*
Y1004469D03*
Y1027894D03*
Y1044626D03*
Y1041280D03*
Y1037933D03*
Y1034587D03*
Y1031240D03*
Y1058012D03*
Y1054666D03*
Y1051319D03*
Y1047973D03*
Y1074744D03*
Y1071398D03*
Y1068051D03*
Y1064705D03*
Y1061359D03*
Y1088130D03*
Y1084784D03*
Y1081437D03*
Y1078091D03*
Y1104862D03*
Y1101516D03*
Y1098170D03*
Y1094823D03*
Y1091477D03*
Y1118248D03*
Y1114902D03*
Y1111555D03*
Y1108209D03*
Y1134981D03*
Y1131634D03*
Y1128288D03*
Y1124941D03*
Y1121595D03*
Y1148366D03*
Y1145020D03*
Y1141674D03*
Y1138327D03*
Y1165099D03*
Y1161752D03*
Y1158406D03*
Y1155059D03*
Y1151713D03*
Y1178485D03*
Y1175138D03*
Y1171792D03*
Y1168445D03*
Y1191870D03*
Y1188524D03*
Y1185177D03*
Y1181831D03*
Y1208603D03*
Y1205256D03*
Y1201910D03*
Y1198563D03*
Y1195217D03*
Y1221988D03*
Y1218642D03*
Y1215296D03*
Y1211949D03*
Y1238721D03*
Y1235374D03*
Y1232028D03*
Y1228681D03*
Y1225335D03*
Y1252107D03*
Y1248760D03*
Y1245414D03*
Y1242067D03*
Y1255453D03*
X1682898Y760177D03*
Y756831D03*
Y776910D03*
Y773563D03*
Y770217D03*
Y766870D03*
Y763524D03*
Y790296D03*
Y786949D03*
Y783603D03*
Y780256D03*
Y807028D03*
Y803681D03*
Y800335D03*
Y796988D03*
Y793642D03*
Y820414D03*
Y817067D03*
Y813721D03*
Y810374D03*
Y837146D03*
Y833799D03*
Y830453D03*
Y827107D03*
Y823760D03*
Y850532D03*
Y847185D03*
Y843839D03*
Y840492D03*
Y863918D03*
Y860571D03*
Y857225D03*
Y853878D03*
Y880650D03*
Y877303D03*
Y873957D03*
Y870610D03*
Y867264D03*
Y894036D03*
Y890689D03*
Y887343D03*
Y883996D03*
Y910768D03*
Y907422D03*
Y904075D03*
Y900729D03*
Y897382D03*
Y924154D03*
Y920807D03*
Y917461D03*
Y914114D03*
Y940886D03*
Y937540D03*
Y934193D03*
Y930847D03*
Y927500D03*
Y954272D03*
Y950925D03*
Y947579D03*
Y944233D03*
Y971004D03*
Y967658D03*
Y964311D03*
Y960965D03*
Y957618D03*
Y984390D03*
Y981044D03*
Y977697D03*
Y974351D03*
Y1001122D03*
Y997776D03*
Y994429D03*
Y991083D03*
Y987736D03*
Y1004469D03*
Y1027894D03*
Y1044626D03*
Y1041280D03*
Y1037933D03*
Y1034587D03*
Y1031240D03*
Y1058012D03*
Y1054666D03*
Y1051319D03*
Y1047973D03*
Y1074744D03*
Y1071398D03*
Y1068051D03*
Y1064705D03*
Y1061359D03*
Y1088130D03*
Y1084784D03*
Y1081437D03*
Y1078091D03*
Y1104862D03*
Y1101516D03*
Y1098170D03*
Y1094823D03*
Y1091477D03*
Y1118248D03*
Y1114902D03*
Y1111555D03*
Y1108209D03*
Y1134981D03*
Y1131634D03*
Y1128288D03*
Y1124941D03*
Y1121595D03*
Y1148366D03*
Y1145020D03*
Y1141674D03*
Y1138327D03*
Y1165099D03*
Y1161752D03*
Y1158406D03*
Y1155059D03*
Y1151713D03*
Y1178485D03*
Y1175138D03*
Y1171792D03*
Y1168445D03*
Y1191870D03*
Y1188524D03*
Y1185177D03*
Y1181831D03*
Y1208603D03*
Y1205256D03*
Y1201910D03*
Y1198563D03*
Y1195217D03*
Y1221988D03*
Y1218642D03*
Y1215296D03*
Y1211949D03*
Y1238721D03*
Y1235374D03*
Y1232028D03*
Y1228681D03*
Y1225335D03*
Y1252107D03*
Y1248760D03*
Y1245414D03*
Y1242067D03*
Y1255453D03*
X1699040Y760177D03*
Y756831D03*
Y776910D03*
Y773563D03*
Y770217D03*
Y766870D03*
Y763524D03*
Y790296D03*
Y786949D03*
Y783603D03*
Y780256D03*
Y807028D03*
Y803681D03*
Y800335D03*
Y796988D03*
Y793642D03*
Y820414D03*
Y817067D03*
Y813721D03*
Y810374D03*
Y837146D03*
Y833799D03*
Y830453D03*
Y827107D03*
Y823760D03*
Y850532D03*
Y847185D03*
Y843839D03*
Y840492D03*
Y863918D03*
Y860571D03*
Y857225D03*
Y853878D03*
Y880650D03*
Y877303D03*
Y873957D03*
Y870610D03*
Y867264D03*
Y894036D03*
Y890689D03*
Y887343D03*
Y883996D03*
Y910768D03*
Y907422D03*
Y904075D03*
Y900729D03*
Y897382D03*
Y924154D03*
Y920807D03*
Y917461D03*
Y914114D03*
Y940886D03*
Y937540D03*
Y934193D03*
Y930847D03*
Y927500D03*
Y954272D03*
Y950925D03*
Y947579D03*
Y944233D03*
Y971004D03*
Y967658D03*
Y964311D03*
Y960965D03*
Y957618D03*
Y984390D03*
Y981044D03*
Y977697D03*
Y974351D03*
Y1001122D03*
Y997776D03*
Y994429D03*
Y991083D03*
Y987736D03*
Y1004469D03*
Y1027894D03*
Y1044626D03*
Y1041280D03*
Y1037933D03*
Y1034587D03*
Y1031240D03*
Y1058012D03*
Y1054666D03*
Y1051319D03*
Y1047973D03*
Y1074744D03*
Y1071398D03*
Y1068051D03*
Y1064705D03*
Y1061359D03*
Y1088130D03*
Y1084784D03*
Y1081437D03*
Y1078091D03*
Y1104862D03*
Y1101516D03*
Y1098170D03*
Y1094823D03*
Y1091477D03*
Y1118248D03*
Y1114902D03*
Y1111555D03*
Y1108209D03*
Y1134981D03*
Y1131634D03*
Y1128288D03*
Y1124941D03*
Y1121595D03*
Y1148366D03*
Y1145020D03*
Y1141674D03*
Y1138327D03*
Y1165099D03*
Y1161752D03*
Y1158406D03*
Y1155059D03*
Y1151713D03*
Y1178485D03*
Y1175138D03*
Y1171792D03*
Y1168445D03*
Y1191870D03*
Y1188524D03*
Y1185177D03*
Y1181831D03*
Y1208603D03*
Y1205256D03*
Y1201910D03*
Y1198563D03*
Y1195217D03*
Y1221988D03*
Y1218642D03*
Y1215296D03*
Y1211949D03*
Y1238721D03*
Y1235374D03*
Y1232028D03*
Y1228681D03*
Y1225335D03*
Y1252107D03*
Y1248760D03*
Y1245414D03*
Y1242067D03*
Y1255453D03*
X1712599Y760177D03*
Y756831D03*
Y776910D03*
Y773563D03*
Y770217D03*
Y766870D03*
Y763524D03*
Y790296D03*
Y786949D03*
Y783603D03*
Y780256D03*
Y807028D03*
Y803681D03*
Y800335D03*
Y796988D03*
Y793642D03*
Y820414D03*
Y817067D03*
Y813721D03*
Y810374D03*
Y837146D03*
Y833799D03*
Y830453D03*
Y827107D03*
Y823760D03*
Y850532D03*
Y847185D03*
Y843839D03*
Y840492D03*
Y863918D03*
Y860571D03*
Y857225D03*
Y853878D03*
Y880650D03*
Y877303D03*
Y873957D03*
Y870610D03*
Y867264D03*
Y894036D03*
Y890689D03*
Y887343D03*
Y883996D03*
Y910768D03*
Y907422D03*
Y904075D03*
Y900729D03*
Y897382D03*
Y924154D03*
Y920807D03*
Y917461D03*
Y914114D03*
Y940886D03*
Y937540D03*
Y934193D03*
Y930847D03*
Y927500D03*
Y954272D03*
Y950925D03*
Y947579D03*
Y944233D03*
Y971004D03*
Y967658D03*
Y964311D03*
Y960965D03*
Y957618D03*
Y984390D03*
Y981044D03*
Y977697D03*
Y974351D03*
Y1001122D03*
Y997776D03*
Y994429D03*
Y991083D03*
Y987736D03*
Y1004469D03*
Y1027894D03*
Y1044626D03*
Y1041280D03*
Y1037933D03*
Y1034587D03*
Y1031240D03*
Y1058012D03*
Y1054666D03*
Y1051319D03*
Y1047973D03*
Y1074744D03*
Y1071398D03*
Y1068051D03*
Y1064705D03*
Y1061359D03*
Y1088130D03*
Y1084784D03*
Y1081437D03*
Y1078091D03*
Y1104862D03*
Y1101516D03*
Y1098170D03*
Y1094823D03*
Y1091477D03*
Y1118248D03*
Y1114902D03*
Y1111555D03*
Y1108209D03*
Y1134981D03*
Y1131634D03*
Y1128288D03*
Y1124941D03*
Y1121595D03*
Y1148366D03*
Y1145020D03*
Y1141674D03*
Y1138327D03*
Y1165099D03*
Y1161752D03*
Y1158406D03*
Y1155059D03*
Y1151713D03*
Y1178485D03*
Y1175138D03*
Y1171792D03*
Y1168445D03*
Y1191870D03*
Y1188524D03*
Y1185177D03*
Y1181831D03*
Y1208603D03*
Y1205256D03*
Y1201910D03*
Y1198563D03*
Y1195217D03*
Y1221988D03*
Y1218642D03*
Y1215296D03*
Y1211949D03*
Y1238721D03*
Y1235374D03*
Y1232028D03*
Y1228681D03*
Y1225335D03*
Y1252107D03*
Y1248760D03*
Y1245414D03*
Y1242067D03*
Y1255453D03*
X1728741Y760177D03*
Y756831D03*
Y776910D03*
Y773563D03*
Y770217D03*
Y766870D03*
Y763524D03*
Y790296D03*
Y786949D03*
Y783603D03*
Y780256D03*
Y807028D03*
Y803681D03*
Y800335D03*
Y796988D03*
Y793642D03*
Y820414D03*
Y817067D03*
Y813721D03*
Y810374D03*
Y837146D03*
Y833799D03*
Y830453D03*
Y827107D03*
Y823760D03*
Y850532D03*
Y847185D03*
Y843839D03*
Y840492D03*
Y863918D03*
Y860571D03*
Y857225D03*
Y853878D03*
Y880650D03*
Y877303D03*
Y873957D03*
Y870610D03*
Y867264D03*
Y894036D03*
Y890689D03*
Y887343D03*
Y883996D03*
Y910768D03*
Y907422D03*
Y904075D03*
Y900729D03*
Y897382D03*
Y924154D03*
Y920807D03*
Y917461D03*
Y914114D03*
Y940886D03*
Y937540D03*
Y934193D03*
Y930847D03*
Y927500D03*
Y954272D03*
Y950925D03*
Y947579D03*
Y944233D03*
Y971004D03*
Y967658D03*
Y964311D03*
Y960965D03*
Y957618D03*
Y984390D03*
Y981044D03*
Y977697D03*
Y974351D03*
Y1001122D03*
Y997776D03*
Y994429D03*
Y991083D03*
Y987736D03*
Y1004469D03*
Y1027894D03*
Y1044626D03*
Y1041280D03*
Y1037933D03*
Y1034587D03*
Y1031240D03*
Y1058012D03*
Y1054666D03*
Y1051319D03*
Y1047973D03*
Y1074744D03*
Y1071398D03*
Y1068051D03*
Y1064705D03*
Y1061359D03*
Y1088130D03*
Y1084784D03*
Y1081437D03*
Y1078091D03*
Y1104862D03*
Y1101516D03*
Y1098170D03*
Y1094823D03*
Y1091477D03*
Y1118248D03*
Y1114902D03*
Y1111555D03*
Y1108209D03*
Y1134981D03*
Y1131634D03*
Y1128288D03*
Y1124941D03*
Y1121595D03*
Y1148366D03*
Y1145020D03*
Y1141674D03*
Y1138327D03*
Y1165099D03*
Y1161752D03*
Y1158406D03*
Y1155059D03*
Y1151713D03*
Y1178485D03*
Y1175138D03*
Y1171792D03*
Y1168445D03*
Y1191870D03*
Y1188524D03*
Y1185177D03*
Y1181831D03*
Y1208603D03*
Y1205256D03*
Y1201910D03*
Y1198563D03*
Y1195217D03*
Y1221988D03*
Y1218642D03*
Y1215296D03*
Y1211949D03*
Y1238721D03*
Y1235374D03*
Y1232028D03*
Y1228681D03*
Y1225335D03*
Y1252107D03*
Y1248760D03*
Y1245414D03*
Y1242067D03*
Y1255453D03*
X1742300Y760177D03*
Y756831D03*
Y776910D03*
Y773563D03*
Y770217D03*
Y766870D03*
Y763524D03*
Y790296D03*
Y786949D03*
Y783603D03*
Y780256D03*
Y807028D03*
Y803681D03*
Y800335D03*
Y796988D03*
Y793642D03*
Y820414D03*
Y817067D03*
Y813721D03*
Y810374D03*
Y837146D03*
Y833799D03*
Y830453D03*
Y827107D03*
Y823760D03*
Y850532D03*
Y847185D03*
Y843839D03*
Y840492D03*
Y863918D03*
Y860571D03*
Y857225D03*
Y853878D03*
Y880650D03*
Y877303D03*
Y873957D03*
Y870610D03*
Y867264D03*
Y894036D03*
Y890689D03*
Y887343D03*
Y883996D03*
Y910768D03*
Y907422D03*
Y904075D03*
Y900729D03*
Y897382D03*
Y924154D03*
Y920807D03*
Y917461D03*
Y914114D03*
Y940886D03*
Y937540D03*
Y934193D03*
Y930847D03*
Y927500D03*
Y954272D03*
Y950925D03*
Y947579D03*
Y944233D03*
Y971004D03*
Y967658D03*
Y964311D03*
Y960965D03*
Y957618D03*
Y984390D03*
Y981044D03*
Y977697D03*
Y974351D03*
Y1001122D03*
Y997776D03*
Y994429D03*
Y991083D03*
Y987736D03*
Y1004469D03*
Y1027894D03*
Y1044626D03*
Y1041280D03*
Y1037933D03*
Y1034587D03*
Y1031240D03*
Y1058012D03*
Y1054666D03*
Y1051319D03*
Y1047973D03*
Y1074744D03*
Y1071398D03*
Y1068051D03*
Y1064705D03*
Y1061359D03*
Y1088130D03*
Y1084784D03*
Y1081437D03*
Y1078091D03*
Y1104862D03*
Y1101516D03*
Y1098170D03*
Y1094823D03*
Y1091477D03*
Y1118248D03*
Y1114902D03*
Y1111555D03*
Y1108209D03*
Y1134981D03*
Y1131634D03*
Y1128288D03*
Y1124941D03*
Y1121595D03*
Y1148366D03*
Y1145020D03*
Y1141674D03*
Y1138327D03*
Y1165099D03*
Y1161752D03*
Y1158406D03*
Y1155059D03*
Y1151713D03*
Y1178485D03*
Y1175138D03*
Y1171792D03*
Y1168445D03*
Y1191870D03*
Y1188524D03*
Y1185177D03*
Y1181831D03*
Y1208603D03*
Y1205256D03*
Y1201910D03*
Y1198563D03*
Y1195217D03*
Y1221988D03*
Y1218642D03*
Y1215296D03*
Y1211949D03*
Y1238721D03*
Y1235374D03*
Y1232028D03*
Y1228681D03*
Y1225335D03*
Y1252107D03*
Y1248760D03*
Y1245414D03*
Y1242067D03*
Y1255453D03*
X1758442Y760177D03*
Y756831D03*
Y776910D03*
Y773563D03*
Y770217D03*
Y766870D03*
Y763524D03*
Y790296D03*
Y786949D03*
Y783603D03*
Y780256D03*
Y807028D03*
Y803681D03*
Y800335D03*
Y796988D03*
Y793642D03*
Y820414D03*
Y817067D03*
Y813721D03*
Y810374D03*
Y837146D03*
Y833799D03*
Y830453D03*
Y827107D03*
Y823760D03*
Y850532D03*
Y847185D03*
Y843839D03*
Y840492D03*
Y863918D03*
Y860571D03*
Y857225D03*
Y853878D03*
Y880650D03*
Y877303D03*
Y873957D03*
Y870610D03*
Y867264D03*
Y894036D03*
Y890689D03*
Y887343D03*
Y883996D03*
Y910768D03*
Y907422D03*
Y904075D03*
Y900729D03*
Y897382D03*
Y924154D03*
Y920807D03*
Y917461D03*
Y914114D03*
Y940886D03*
Y937540D03*
Y934193D03*
Y930847D03*
Y927500D03*
Y954272D03*
Y950925D03*
Y947579D03*
Y944233D03*
Y971004D03*
Y967658D03*
Y964311D03*
Y960965D03*
Y957618D03*
Y984390D03*
Y981044D03*
Y977697D03*
Y974351D03*
Y1001122D03*
Y997776D03*
Y994429D03*
Y991083D03*
Y987736D03*
Y1004469D03*
Y1027894D03*
Y1044626D03*
Y1041280D03*
Y1037933D03*
Y1034587D03*
Y1031240D03*
Y1058012D03*
Y1054666D03*
Y1051319D03*
Y1047973D03*
Y1074744D03*
Y1071398D03*
Y1068051D03*
Y1064705D03*
Y1061359D03*
Y1088130D03*
Y1084784D03*
Y1081437D03*
Y1078091D03*
Y1104862D03*
Y1101516D03*
Y1098170D03*
Y1094823D03*
Y1091477D03*
Y1118248D03*
Y1114902D03*
Y1111555D03*
Y1108209D03*
Y1134981D03*
Y1131634D03*
Y1128288D03*
Y1124941D03*
Y1121595D03*
Y1148366D03*
Y1145020D03*
Y1141674D03*
Y1138327D03*
Y1165099D03*
Y1161752D03*
Y1158406D03*
Y1155059D03*
Y1151713D03*
Y1178485D03*
Y1175138D03*
Y1171792D03*
Y1168445D03*
Y1191870D03*
Y1188524D03*
Y1185177D03*
Y1181831D03*
Y1208603D03*
Y1205256D03*
Y1201910D03*
Y1198563D03*
Y1195217D03*
Y1221988D03*
Y1218642D03*
Y1215296D03*
Y1211949D03*
Y1238721D03*
Y1235374D03*
Y1232028D03*
Y1228681D03*
Y1225335D03*
Y1252107D03*
Y1248760D03*
Y1245414D03*
Y1242067D03*
Y1255453D03*
X1772000Y760177D03*
Y756831D03*
Y776910D03*
Y773563D03*
Y770217D03*
Y766870D03*
Y763524D03*
Y790296D03*
Y786949D03*
Y783603D03*
Y780256D03*
Y807028D03*
Y803681D03*
Y800335D03*
Y796988D03*
Y793642D03*
Y820414D03*
Y817067D03*
Y813721D03*
Y810374D03*
Y837146D03*
Y833799D03*
Y830453D03*
Y827107D03*
Y823760D03*
Y850532D03*
Y847185D03*
Y843839D03*
Y840492D03*
Y863918D03*
Y860571D03*
Y857225D03*
Y853878D03*
Y880650D03*
Y877303D03*
Y873957D03*
Y870610D03*
Y867264D03*
Y894036D03*
Y890689D03*
Y887343D03*
Y883996D03*
Y910768D03*
Y907422D03*
Y904075D03*
Y900729D03*
Y897382D03*
Y924154D03*
Y920807D03*
Y917461D03*
Y914114D03*
Y940886D03*
Y937540D03*
Y934193D03*
Y930847D03*
Y927500D03*
Y954272D03*
Y950925D03*
Y947579D03*
Y944233D03*
Y971004D03*
Y967658D03*
Y964311D03*
Y960965D03*
Y957618D03*
Y984390D03*
Y981044D03*
Y977697D03*
Y974351D03*
Y1001122D03*
Y997776D03*
Y994429D03*
Y991083D03*
Y987736D03*
Y1004469D03*
Y1027894D03*
Y1044626D03*
Y1041280D03*
Y1037933D03*
Y1034587D03*
Y1031240D03*
Y1058012D03*
Y1054666D03*
Y1051319D03*
Y1047973D03*
Y1074744D03*
Y1071398D03*
Y1068051D03*
Y1064705D03*
Y1061359D03*
Y1088130D03*
Y1084784D03*
Y1081437D03*
Y1078091D03*
Y1104862D03*
Y1101516D03*
Y1098170D03*
Y1094823D03*
Y1091477D03*
Y1118248D03*
Y1114902D03*
Y1111555D03*
Y1108209D03*
Y1134981D03*
Y1131634D03*
Y1128288D03*
Y1124941D03*
Y1121595D03*
Y1148366D03*
Y1145020D03*
Y1141674D03*
Y1138327D03*
Y1165099D03*
Y1161752D03*
Y1158406D03*
Y1155059D03*
Y1151713D03*
Y1178485D03*
Y1175138D03*
Y1171792D03*
Y1168445D03*
Y1191870D03*
Y1188524D03*
Y1185177D03*
Y1181831D03*
Y1208603D03*
Y1205256D03*
Y1201910D03*
Y1198563D03*
Y1195217D03*
Y1221988D03*
Y1218642D03*
Y1215296D03*
Y1211949D03*
Y1238721D03*
Y1235374D03*
Y1232028D03*
Y1228681D03*
Y1225335D03*
Y1252107D03*
Y1248760D03*
Y1245414D03*
Y1242067D03*
Y1255453D03*
X1788142Y760177D03*
Y756831D03*
Y776910D03*
Y773563D03*
Y770217D03*
Y766870D03*
Y763524D03*
Y790296D03*
Y786949D03*
Y783603D03*
Y780256D03*
Y807028D03*
Y803681D03*
Y800335D03*
Y796988D03*
Y793642D03*
Y820414D03*
Y817067D03*
Y813721D03*
Y810374D03*
Y837146D03*
Y833799D03*
Y830453D03*
Y827107D03*
Y823760D03*
Y850532D03*
Y847185D03*
Y843839D03*
Y840492D03*
Y863918D03*
Y860571D03*
Y857225D03*
Y853878D03*
Y880650D03*
Y877303D03*
Y873957D03*
Y870610D03*
Y867264D03*
Y894036D03*
Y890689D03*
Y887343D03*
Y883996D03*
Y910768D03*
Y907422D03*
Y904075D03*
Y900729D03*
Y897382D03*
Y924154D03*
Y920807D03*
Y917461D03*
Y914114D03*
Y940886D03*
Y937540D03*
Y934193D03*
Y930847D03*
Y927500D03*
Y954272D03*
Y950925D03*
Y947579D03*
Y944233D03*
Y971004D03*
Y967658D03*
Y964311D03*
Y960965D03*
Y957618D03*
Y984390D03*
Y981044D03*
Y977697D03*
Y974351D03*
Y1001122D03*
Y997776D03*
Y994429D03*
Y991083D03*
Y987736D03*
Y1004469D03*
Y1027894D03*
Y1044626D03*
Y1041280D03*
Y1037933D03*
Y1034587D03*
Y1031240D03*
Y1058012D03*
Y1054666D03*
Y1051319D03*
Y1047973D03*
Y1074744D03*
Y1071398D03*
Y1068051D03*
Y1064705D03*
Y1061359D03*
Y1088130D03*
Y1084784D03*
Y1081437D03*
Y1078091D03*
Y1104862D03*
Y1101516D03*
Y1098170D03*
Y1094823D03*
Y1091477D03*
Y1118248D03*
Y1114902D03*
Y1111555D03*
Y1108209D03*
Y1134981D03*
Y1131634D03*
Y1128288D03*
Y1124941D03*
Y1121595D03*
Y1148366D03*
Y1145020D03*
Y1141674D03*
Y1138327D03*
Y1165099D03*
Y1161752D03*
Y1158406D03*
Y1155059D03*
Y1151713D03*
Y1178485D03*
Y1175138D03*
Y1171792D03*
Y1168445D03*
Y1191870D03*
Y1188524D03*
Y1185177D03*
Y1181831D03*
Y1208603D03*
Y1205256D03*
Y1201910D03*
Y1198563D03*
Y1195217D03*
Y1221988D03*
Y1218642D03*
Y1215296D03*
Y1211949D03*
Y1238721D03*
Y1235374D03*
Y1232028D03*
Y1228681D03*
Y1225335D03*
Y1252107D03*
Y1248760D03*
Y1245414D03*
Y1242067D03*
Y1255453D03*
G54D165*
X435262Y55016D03*
Y60016D03*
Y65016D03*
Y70016D03*
X456128Y60016D03*
Y55016D03*
Y70016D03*
Y65016D03*
X1148486Y53186D03*
Y58186D03*
Y63186D03*
Y68186D03*
X1169352Y58186D03*
Y53186D03*
Y68186D03*
Y63186D03*
G54D246*
X805690Y204724D03*
X1057659D03*
G54D18*
X14092Y290137D03*
Y298207D03*
X28068Y290137D03*
Y298207D03*
X44692Y290137D03*
Y298207D03*
X58668Y290137D03*
Y298207D03*
X1632822Y221842D03*
Y229912D03*
X1646798Y221842D03*
Y229912D03*
G54D309*
X1669100Y121762D03*
Y126762D03*
Y131762D03*
Y136762D03*
Y141762D03*
Y146762D03*
Y151762D03*
Y156762D03*
Y161762D03*
Y166762D03*
X1699100Y121762D03*
Y126762D03*
Y131762D03*
Y136762D03*
Y141762D03*
Y146762D03*
Y151762D03*
Y156762D03*
Y161762D03*
Y166762D03*
G54D318*
X1790355Y189682D03*
X1804135D03*
G54D81*
X147270Y461272D03*
X174050Y460732D03*
X951402Y1520482D03*
X974768D03*
X998134D03*
X1021500D03*
X1044866D03*
X1068232D03*
X1091598D03*
G54D174*
X455968Y288258D03*
Y294058D03*
X543208Y297268D03*
Y303068D03*
X646176Y206895D03*
Y201095D03*
X651612Y206890D03*
Y201090D03*
X983328Y211433D03*
X988228D03*
X983328Y217233D03*
X988228D03*
X1110000Y1680900D03*
Y1675100D03*
X1115217Y1680875D03*
Y1675075D03*
X1812174Y191599D03*
Y185799D03*
X1811827Y202598D03*
Y208398D03*
X1817674Y191799D03*
Y197599D03*
G54D228*
X722356Y1573552D03*
X718813D03*
X720585D03*
Y1591170D03*
X722356D03*
X718813D03*
X736530Y1573552D03*
X734758D03*
X732986D03*
X731215D03*
X729443D03*
X727671D03*
X724128D03*
X725900D03*
Y1591170D03*
X727671D03*
X729443D03*
X731215D03*
X732986D03*
X734758D03*
X736530D03*
X724128D03*
X740073Y1573552D03*
X738301D03*
Y1591170D03*
X740073D03*
G54D63*
X77000Y1447437D03*
X80740Y1439563D03*
X73260D03*
X154640Y431977D03*
X150900Y424103D03*
X158380D03*
X181420Y431437D03*
X185160Y423563D03*
X177680D03*
X426011Y532701D03*
X418531D03*
X422271Y540575D03*
X763029Y151312D03*
X766769Y143438D03*
X759289D03*
X757557Y1687769D03*
X765037D03*
X761297Y1679895D03*
X1050866Y1656096D03*
X1058346D03*
X1054606Y1648222D03*
G54D36*
X45951Y522792D03*
Y524760D03*
Y526729D03*
Y528697D03*
Y530666D03*
Y532634D03*
X60715Y522792D03*
Y532634D03*
Y530666D03*
Y528697D03*
Y526729D03*
Y524760D03*
X408943Y1605835D03*
Y1607804D03*
Y1609772D03*
Y1611741D03*
Y1613709D03*
Y1615678D03*
Y1617646D03*
Y1619615D03*
X427643Y1605835D03*
Y1607804D03*
Y1609772D03*
Y1611741D03*
Y1613709D03*
Y1615678D03*
Y1617646D03*
Y1619615D03*
X1116166Y1640051D03*
Y1642020D03*
Y1643988D03*
Y1645957D03*
Y1647925D03*
Y1649894D03*
Y1651862D03*
Y1653831D03*
X1134866Y1640051D03*
Y1642020D03*
Y1643988D03*
Y1645957D03*
Y1647925D03*
Y1649894D03*
Y1651862D03*
Y1653831D03*
G54D147*
X329219Y220874D03*
Y239378D03*
X649319Y219363D03*
Y237867D03*
X791526Y128244D03*
Y146748D03*
X882183Y216681D03*
Y235185D03*
G54D255*
X821993Y539872D03*
X821347Y557607D03*
Y565087D03*
X829867Y536132D03*
Y543612D03*
X829221Y561347D03*
X1160163Y1441260D03*
Y1448740D03*
X1168037Y1445000D03*
X1667635Y210191D03*
X1675509Y206451D03*
Y213931D03*
G54D273*
X916642Y1147586D03*
X963667D03*
X1326435Y553526D03*
X1632560Y553181D03*
G54D264*
X900590Y175177D03*
X945078Y155197D03*
G54D27*
X34296Y517025D03*
X34580Y1497914D03*
Y1502214D03*
X39849Y282916D03*
Y277798D03*
X37984Y288500D03*
X39849Y312916D03*
Y307798D03*
X46984Y303500D03*
X41117Y1622896D03*
Y1626896D03*
X38411Y1668587D03*
Y1663587D03*
X62709Y268223D03*
X62839Y280357D03*
Y276357D03*
Y272357D03*
X67484Y290000D03*
X62839Y310357D03*
X53984Y303500D03*
X64680Y1552869D03*
X77238Y157191D03*
Y161191D03*
Y165191D03*
X68592Y423746D03*
X75117Y521613D03*
Y525513D03*
Y543213D03*
Y539313D03*
X81680Y1549369D03*
X85085Y140950D03*
X84858Y386502D03*
X84875Y376026D03*
X90039Y1307499D03*
X90059Y1311619D03*
X89984Y1440000D03*
Y1444500D03*
Y1448500D03*
X86967Y1663138D03*
X86926Y1667127D03*
X88404Y1698511D03*
Y1702511D03*
X88241Y1724331D03*
Y1720331D03*
X104738Y153691D03*
Y158191D03*
X108949Y1385562D03*
X109984Y1414500D03*
X98984Y1412500D03*
Y1408000D03*
Y1417000D03*
Y1421500D03*
Y1444500D03*
Y1448500D03*
X98495Y1552796D03*
X107577Y1597797D03*
X115837Y1670313D03*
Y1674313D03*
X117484Y1712450D03*
X137961Y679290D03*
Y675290D03*
X130401Y1382305D03*
X141549Y1385562D03*
X132552Y1709346D03*
X139802Y1709166D03*
X144476Y526997D03*
X147984Y1433500D03*
Y1429500D03*
Y1437500D03*
X152837Y1670087D03*
X146837Y1682587D03*
X142751Y1718241D03*
X171344Y400560D03*
X163101Y1382305D03*
X165799Y1726500D03*
X177584Y412350D03*
X174249Y1385562D03*
X174984Y1715000D03*
Y1721000D03*
X195904Y144962D03*
X196984Y149000D03*
X197484Y156500D03*
X196001Y1382305D03*
X207149Y1385562D03*
X213557Y1419187D03*
X208984Y1707000D03*
X209299Y1723000D03*
X223964Y120662D03*
Y124662D03*
X225336Y148750D03*
X220984Y156500D03*
X227504Y206820D03*
X228801Y1382305D03*
X245204Y71862D03*
X232117Y571129D03*
X235770Y711602D03*
X239949Y1385562D03*
X250281Y111743D03*
X259645Y140882D03*
X250524Y224370D03*
X251111Y640909D03*
X274940Y74536D03*
X270034Y142892D03*
X262795Y144882D03*
X270037Y159203D03*
Y155203D03*
X263194Y207660D03*
X272984Y215000D03*
X264984Y221500D03*
X270903Y611172D03*
X265075Y644555D03*
X274482Y676901D03*
X273549Y1339416D03*
X276751Y99183D03*
X279884Y136962D03*
X279984Y207000D03*
Y211000D03*
X286775Y570398D03*
X279885Y585178D03*
X285341Y674150D03*
X298431Y75673D03*
X301150Y71128D03*
X299537Y156203D03*
Y151703D03*
X297805Y678796D03*
X295297Y1336131D03*
X320041Y91803D03*
X318984Y263000D03*
X317127Y694525D03*
X307212Y711142D03*
X306445Y1339388D03*
X325526Y69863D03*
X328875Y545521D03*
X331713Y566086D03*
X330575Y698946D03*
X328201Y1336074D03*
X337398Y165170D03*
X346200Y225070D03*
X341984Y285000D03*
X339982Y731292D03*
X339349Y1339331D03*
X355399Y215325D03*
X355417Y211407D03*
X360984Y307500D03*
X359091Y550415D03*
X356641Y562415D03*
Y566415D03*
Y570415D03*
Y574415D03*
X363635Y698678D03*
X361001Y1336274D03*
X366680Y130165D03*
X373947Y158028D03*
X368799Y211361D03*
Y219361D03*
X376529Y225145D03*
X368799Y215361D03*
X376529Y228645D03*
X377039Y243615D03*
X367616Y617438D03*
X373042Y731024D03*
X372149Y1339531D03*
X374246Y1387697D03*
X389477Y142937D03*
X384072Y280370D03*
Y294370D03*
X394484Y311500D03*
X398890Y134980D03*
X395780Y138980D03*
X408625Y148300D03*
X396984Y304000D03*
X402855Y551915D03*
X396675Y698746D03*
X406082Y731092D03*
X404731Y1358862D03*
X407490Y1631219D03*
X408984Y1645500D03*
Y1653500D03*
X422477Y59935D03*
X422321Y71665D03*
Y66865D03*
X423285Y99148D03*
X419735Y104148D03*
X415625Y144300D03*
Y148300D03*
X417424Y235442D03*
X418199Y250165D03*
Y258165D03*
Y266165D03*
X418650Y1006123D03*
Y1009864D03*
Y1013604D03*
Y1028564D03*
Y1021084D03*
Y1024824D03*
Y1017344D03*
X411984Y1637000D03*
X416984Y1657500D03*
X429675Y680946D03*
X439082Y713292D03*
X428100Y1014766D03*
X437929Y1014745D03*
X437925Y1018879D03*
X428082D03*
X437925Y1023013D03*
X428082D03*
X452389Y270911D03*
X446783Y1014745D03*
Y1018879D03*
Y1023013D03*
X441484Y1604200D03*
Y1600200D03*
X444984Y1622700D03*
Y1618700D03*
X465712Y70016D03*
X468880Y239764D03*
Y227764D03*
Y231764D03*
Y247764D03*
X462075Y656346D03*
X457019Y1014745D03*
Y1018879D03*
Y1023013D03*
X467984Y1668000D03*
Y1659500D03*
Y1676000D03*
X468484Y1697000D03*
X475337Y60029D03*
X475267Y55135D03*
X475337Y64975D03*
X476609Y90574D03*
Y105574D03*
Y100574D03*
Y95574D03*
X476674Y119644D03*
Y115644D03*
X476609Y110574D03*
X476674Y123644D03*
X476412Y284738D03*
Y280858D03*
X484949Y578572D03*
X471482Y688692D03*
X475484Y1655500D03*
Y1672000D03*
X472984Y1680000D03*
X475484Y1701000D03*
Y1706500D03*
Y1714500D03*
X492981Y171625D03*
X492166Y193516D03*
Y189516D03*
X486237Y206827D03*
X489168Y233000D03*
X497518Y238119D03*
X494675Y629846D03*
X500716Y193516D03*
Y185516D03*
X508991D03*
X500716Y189516D03*
X504260Y205285D03*
X511260Y202404D03*
X504082Y662192D03*
X529484Y432500D03*
X527975Y595746D03*
X544680Y195256D03*
X539484Y445500D03*
X537382Y628092D03*
X554320Y152742D03*
X559062Y193541D03*
X546472Y218441D03*
Y230441D03*
Y239566D03*
X556157Y399586D03*
Y414274D03*
Y423949D03*
X553484Y451000D03*
X547221Y663689D03*
X574220Y235821D03*
X563412Y293738D03*
Y289858D03*
X563484Y451000D03*
X572984Y471500D03*
X561984Y477500D03*
X572984Y475500D03*
X586687Y164356D03*
Y169415D03*
X578521Y193516D03*
X578536Y197481D03*
X581008Y261171D03*
X586107Y411846D03*
Y423949D03*
Y435949D03*
X574984Y462000D03*
X586690Y454242D03*
X574984Y466000D03*
X579984Y475500D03*
Y479500D03*
X603251Y136408D03*
X603254Y132270D03*
X603253Y141640D03*
X594007Y208991D03*
X594013Y221277D03*
Y217277D03*
Y225277D03*
Y229277D03*
X593294Y400287D03*
Y404287D03*
X593611Y458461D03*
X593690Y454242D03*
X593487Y468893D03*
X593505Y479631D03*
X596984Y493500D03*
X603255Y1266598D03*
Y1262598D03*
X605984Y412000D03*
X614984Y440000D03*
X623513Y221777D03*
Y226277D03*
X632905Y474020D03*
X630386Y1357114D03*
X622343Y1367166D03*
X622261Y1386732D03*
X646145Y473905D03*
X644884Y1728000D03*
Y1722138D03*
Y1717138D03*
Y1733000D03*
X649298Y166053D03*
Y161862D03*
X649350Y174201D03*
X649298Y170053D03*
X655484Y390000D03*
X659424Y461818D03*
X659407Y457755D03*
X653549Y486941D03*
X658720Y1371199D03*
X658652Y1378931D03*
X658686Y1375061D03*
X656284Y1698400D03*
Y1712084D03*
X651884Y1728000D03*
Y1717138D03*
Y1722138D03*
Y1733000D03*
X675529Y401567D03*
Y409320D03*
Y405488D03*
X675484Y457862D03*
Y453862D03*
Y461862D03*
Y477862D03*
Y465862D03*
X675400Y474268D03*
X675484Y482862D03*
X664439Y486941D03*
X664301Y495126D03*
X669770Y504895D03*
X677770D03*
X668484Y529500D03*
X674084Y1308002D03*
X665484Y1708184D03*
X683437Y115868D03*
X683261Y1530526D03*
Y1526526D03*
X680777Y1639704D03*
Y1643904D03*
X705124Y1560573D03*
X705094Y1580523D03*
X704984Y1608500D03*
Y1600500D03*
X705625Y1616656D03*
X699901Y1670408D03*
X699939Y1674429D03*
X699823Y1678474D03*
X709907Y103308D03*
X713184Y157762D03*
X732977Y90998D03*
X733007Y95158D03*
X738139Y1400414D03*
X728345Y1614743D03*
X748719Y142050D03*
X751184Y167537D03*
X760102Y89348D03*
X754617Y111288D03*
X759751Y276322D03*
X766727Y299279D03*
X755094Y1576023D03*
Y1589023D03*
Y1584023D03*
X766134Y1591733D03*
X760146Y1693369D03*
X777773Y158026D03*
X777787Y153728D03*
X780527Y299279D03*
X781984Y371000D03*
Y364000D03*
X774984D03*
X778153Y419464D03*
X778136Y455344D03*
Y463344D03*
Y459344D03*
Y476344D03*
Y472344D03*
Y487344D03*
Y491344D03*
Y499344D03*
Y495344D03*
X791250Y267822D03*
Y281822D03*
X792586Y415344D03*
X792484Y407500D03*
X792636Y439344D03*
Y451344D03*
Y463344D03*
Y459344D03*
Y455344D03*
Y471344D03*
X792805Y467646D03*
X793146Y483458D03*
X793363Y479511D03*
X792984Y507000D03*
X795330Y1328662D03*
X808543Y386791D03*
X808550Y381020D03*
Y376753D03*
X801484Y392500D03*
X809559Y422687D03*
X809370Y431344D03*
X809286Y463578D03*
X809198Y449802D03*
X809417Y471344D03*
X809530Y476159D03*
X809417Y487344D03*
X809486Y491344D03*
X809530Y480159D03*
X809484Y504000D03*
X809603Y495344D03*
X809484Y512000D03*
Y516000D03*
X811484Y534500D03*
X811192Y541448D03*
X807348Y1340762D03*
Y1336334D03*
X802484Y1330000D03*
X807755Y1351988D03*
X810895Y1364193D03*
X807634Y1574633D03*
Y1590633D03*
Y1598633D03*
Y1606633D03*
X823903Y415344D03*
Y419344D03*
X823895Y423099D03*
X823903Y455344D03*
X823842Y463578D03*
Y471344D03*
Y467568D03*
X834446Y58632D03*
X831204Y166862D03*
Y176362D03*
X838984Y393000D03*
X830167Y405347D03*
X834984Y471000D03*
X830652Y497912D03*
X851804Y162762D03*
X843685Y490567D03*
X843721Y486478D03*
X843684Y482128D03*
X849241Y507106D03*
X843570Y494661D03*
X856003Y494585D03*
X855809Y503154D03*
X856075Y498861D03*
X849634Y1574633D03*
Y1590633D03*
Y1598633D03*
Y1606633D03*
X859287Y269057D03*
X859317Y273217D03*
X859205Y384030D03*
X861984Y395500D03*
X871504Y418720D03*
X874204Y166362D03*
X882204Y171362D03*
Y176862D03*
X884209Y187449D03*
X884199Y183169D03*
X886912Y267407D03*
X880899Y289439D03*
X887984Y326000D03*
X888966Y1056033D03*
X891634Y1574633D03*
Y1590633D03*
Y1598633D03*
Y1606633D03*
X905265Y606915D03*
X919940Y570706D03*
X933634Y1582233D03*
Y1578233D03*
Y1586233D03*
X961109Y198171D03*
X948027Y585200D03*
X948715Y614150D03*
X947540Y628662D03*
X961961Y1498695D03*
X984608Y189347D03*
X987939Y260781D03*
Y271443D03*
X987568Y295641D03*
X991540Y516014D03*
Y521014D03*
Y526074D03*
Y531074D03*
X985327Y1498695D03*
X997396Y221233D03*
Y225233D03*
X1003818Y446175D03*
Y457175D03*
Y451675D03*
Y462675D03*
Y468175D03*
Y479175D03*
Y473675D03*
Y494175D03*
Y490175D03*
Y484675D03*
Y499675D03*
X1012794Y153868D03*
X1016704Y198999D03*
X1016679Y207423D03*
X1016604Y203099D03*
X1016679Y214423D03*
Y222423D03*
Y218423D03*
Y226423D03*
X1018318Y287311D03*
Y298311D03*
X1010186Y433426D03*
X1017041Y420902D03*
X1014248Y484155D03*
X1011690Y510304D03*
X1015984Y560500D03*
X1008693Y1498695D03*
X1024443Y397726D03*
X1024484Y566000D03*
X1032059Y1498695D03*
X1045586Y1646205D03*
X1045454Y1652082D03*
X1058001Y406560D03*
X1058964Y490037D03*
X1060630Y1311203D03*
Y1307203D03*
X1055425Y1498695D03*
X1068730Y445499D03*
X1068780Y457959D03*
X1068748Y453655D03*
Y449655D03*
X1068778Y462525D03*
X1077694Y457959D03*
X1068778Y467000D03*
Y471500D03*
X1068748Y479655D03*
X1080687Y1385543D03*
X1078791Y1498695D03*
X1093422Y446105D03*
Y440605D03*
Y462605D03*
Y457105D03*
Y451605D03*
Y468105D03*
X1086422Y472105D03*
X1093422Y489641D03*
Y484605D03*
Y494641D03*
X1094323Y1633726D03*
X1094365Y1629945D03*
X1101932Y479355D03*
X1102139Y1382286D03*
X1102157Y1498695D03*
X1102507Y1634400D03*
X1102700Y1630123D03*
X1101984Y1639000D03*
X1113287Y1385543D03*
X1129717Y52651D03*
X1136890Y52599D03*
X1136122Y56512D03*
X1136389Y380533D03*
Y385698D03*
X1127393Y398020D03*
X1134839Y1382286D03*
X1150302Y74738D03*
X1155177Y204835D03*
Y209835D03*
X1147722Y489819D03*
X1145987Y1385543D03*
X1150367Y1436579D03*
X1160622Y461691D03*
Y457691D03*
Y449691D03*
Y453691D03*
Y465691D03*
Y469691D03*
Y481691D03*
X1167739Y1382286D03*
X1174913Y89556D03*
Y93556D03*
X1182675Y95864D03*
X1172016Y580602D03*
X1172076Y584622D03*
X1178887Y1385543D03*
X1184084Y1433000D03*
X1195771Y61515D03*
X1195871Y57015D03*
X1195791Y52815D03*
X1188972Y87125D03*
Y91125D03*
X1195186Y164987D03*
Y160987D03*
X1191411Y436202D03*
Y444202D03*
Y452202D03*
X1200599Y1382088D03*
X1199984Y1396500D03*
Y1401000D03*
Y1410000D03*
Y1405500D03*
Y1424000D03*
X1191084Y1428500D03*
Y1433000D03*
X1199984Y1437500D03*
Y1447500D03*
Y1442500D03*
X1192839Y1673050D03*
X1192521Y1697850D03*
X1199521D03*
X1213065Y94846D03*
X1205240Y133866D03*
Y128748D03*
X1205496Y177187D03*
Y181187D03*
X1205527Y188942D03*
X1202911Y460202D03*
X1202971Y465272D03*
X1203047Y470376D03*
X1211687Y1385543D03*
X1210984Y1401000D03*
X1208181Y1673059D03*
X1207863Y1697859D03*
X1214863D03*
X1244677Y145239D03*
X1239938Y447255D03*
Y443255D03*
X1244801Y1418462D03*
X1244843Y1422362D03*
X1257931Y464372D03*
X1248811Y468152D03*
X1258984Y765000D03*
X1249678Y1339397D03*
X1261091Y155730D03*
Y164051D03*
Y160051D03*
Y176051D03*
Y180551D03*
Y168051D03*
Y172051D03*
Y185051D03*
X1273533Y390884D03*
X1265484Y390500D03*
X1265686Y411125D03*
Y407125D03*
Y415125D03*
X1271426Y1336112D03*
X1275595Y150030D03*
X1289591Y162051D03*
Y166051D03*
Y171551D03*
Y184051D03*
X1282574Y1339369D03*
X1284584Y1430000D03*
Y1434000D03*
X1298177Y133739D03*
Y125739D03*
Y129739D03*
Y145739D03*
X1293186Y403625D03*
Y408125D03*
X1296240Y552147D03*
X1294850Y597013D03*
X1304330Y1336055D03*
X1307126Y537299D03*
X1307242Y556545D03*
X1315478Y1339312D03*
X1346244Y674443D03*
X1337130Y1336255D03*
X1348278Y1339512D03*
X1371168Y100509D03*
X1375627Y613889D03*
X1369890Y1355715D03*
X1385034Y646235D03*
X1380860Y1358843D03*
X1391977Y1670391D03*
X1384977Y1674391D03*
X1387529Y1704038D03*
X1385288Y1733118D03*
X1399741Y642765D03*
X1408327Y646789D03*
X1394792Y1009863D03*
Y1013603D03*
X1404224Y1014744D03*
X1394792Y1006122D03*
X1404224Y1018878D03*
Y1023012D03*
X1394792Y1017343D03*
Y1028563D03*
Y1024823D03*
Y1021083D03*
X1408117Y1622167D03*
X1401117Y1626167D03*
X1404967Y1630167D03*
X1417734Y679135D03*
X1422925Y1014744D03*
X1414071D03*
X1422925Y1023012D03*
X1414067Y1018878D03*
X1422925D03*
X1414067Y1023012D03*
X1421799Y1642967D03*
X1435103Y244450D03*
X1433741Y675765D03*
X1433161Y1014744D03*
Y1023012D03*
Y1018878D03*
X1435793Y1609966D03*
X1426781Y1619504D03*
Y1613966D03*
X1435981Y1619566D03*
X1448103Y244450D03*
X1440927Y679369D03*
X1450334Y711715D03*
X1467889Y61563D03*
X1458726Y128242D03*
X1461741Y564977D03*
X1465241Y695265D03*
X1474889Y61563D03*
X1469741Y548977D03*
Y552977D03*
Y544977D03*
Y556977D03*
Y560977D03*
Y564977D03*
X1473845Y698946D03*
X1483252Y731292D03*
X1513741Y543977D03*
X1506927Y698946D03*
X1526803Y201250D03*
X1516334Y731292D03*
X1542001Y300816D03*
Y308816D03*
Y304816D03*
X1539727Y698946D03*
X1549848Y284575D03*
X1549134Y731292D03*
X1550158Y1266271D03*
X1550161Y1282188D03*
Y1278188D03*
Y1286188D03*
X1569501Y297316D03*
Y301816D03*
X1573127Y531220D03*
X1572857Y677006D03*
X1564972Y1273445D03*
X1582264Y709352D03*
X1584756Y1302278D03*
X1598937Y225250D03*
X1613603Y542733D03*
X1605627Y643237D03*
X1615034Y675583D03*
X1625426Y282728D03*
Y278520D03*
X1625393Y286742D03*
X1618793Y530739D03*
X1632733Y1420450D03*
X1632651Y1444016D03*
Y1440016D03*
X1645672Y627206D03*
X1638627Y624237D03*
X1637817Y1306874D03*
X1640974Y1410398D03*
X1642651Y1442228D03*
X1658009Y141762D03*
Y146762D03*
Y151762D03*
Y161762D03*
X1648034Y656583D03*
X1659650Y696318D03*
X1669240Y1432215D03*
X1669274Y1428345D03*
X1669308Y1424483D03*
X1669326Y1420567D03*
X1685872Y1399703D03*
X1691135Y1559526D03*
Y1563526D03*
X1704778Y373773D03*
Y369773D03*
X1702868Y401485D03*
X1695011Y1696422D03*
X1717674Y364962D03*
X1712818Y666238D03*
Y662238D03*
X1725402Y112867D03*
X1733063Y1530950D03*
Y1535250D03*
X1729947Y1663465D03*
Y1667965D03*
Y1658965D03*
Y1672465D03*
X1739793Y85339D03*
X1751872Y100307D03*
X1749094Y305106D03*
X1742981Y1435005D03*
X1751963Y1585905D03*
X1741947Y1653965D03*
X1738413Y1649456D03*
X1763552Y76797D03*
X1763522Y72637D03*
X1756420Y85407D03*
X1754204Y372452D03*
X1781559Y190799D03*
X1768963Y1582405D03*
X1771412Y1666984D03*
X1771373Y1670514D03*
X1770947Y1685465D03*
X1771292Y1674057D03*
X1770947Y1681702D03*
Y1678172D03*
Y1689965D03*
X1790647Y70987D03*
X1785162Y92927D03*
X1792874Y146834D03*
Y151834D03*
Y165834D03*
X1795255Y367866D03*
X1787783Y403932D03*
X1795255Y390411D03*
X1787783Y410432D03*
Y418932D03*
Y425432D03*
X1785778Y1585832D03*
X1825064Y147834D03*
X1818064Y151834D03*
X1820216Y371329D03*
X1826153Y383952D03*
Y379552D03*
X1820053Y395552D03*
X1819283Y407932D03*
X1818783Y421432D03*
Y427432D03*
X1818776Y431678D03*
X1827216Y371329D03*
Y367359D03*
X1847775Y161834D03*
G54D183*
X478794Y293510D03*
X565794Y302510D03*
G54D90*
X129932Y1679174D03*
G54D282*
X1004868Y194419D03*
G54D291*
X1156378Y133866D03*
X1173858Y207205D03*
X1391260Y174213D03*
G54D192*
X496693Y297114D03*
X519723D03*
X583693Y306114D03*
X606723D03*
G54D219*
X676509Y224606D03*
G54D156*
X385023Y-23871D03*
X836502Y-20011D03*
Y-11D03*
Y19989D03*
X1240022Y-20011D03*
Y-11D03*
Y19989D03*
X1533316Y-24212D03*
G54D72*
X106843Y1381137D03*
X139443D03*
X172143Y1381249D03*
X205043Y1381144D03*
X237843Y1381004D03*
X264213Y649037D03*
X271443Y1334995D03*
X296957Y683158D03*
X304339Y1334995D03*
X329713Y703362D03*
X337243Y1334856D03*
X362773Y703129D03*
X370043Y1335042D03*
X395813Y703176D03*
X402625Y1354338D03*
X428813Y685444D03*
X461213Y660759D03*
X484865Y1340924D03*
X486135Y1351429D03*
X475865Y1361180D03*
X477135Y1371685D03*
X493813Y634326D03*
X519116Y124200D03*
X515385Y115300D03*
X527113Y600085D03*
X590156Y759400D03*
X581760Y759700D03*
X588886Y769200D03*
X580490Y769100D03*
X606091Y760386D03*
X598124Y759500D03*
X596854Y765500D03*
X714672Y515211D03*
X714399Y1399498D03*
X746632Y516077D03*
X747181Y1399598D03*
X827904Y1312682D03*
X829174Y1323187D03*
X1078581Y1381102D03*
X1111181Y1381074D03*
X1143881Y1380963D03*
X1176781D03*
X1209581Y1381149D03*
X1247572Y1335094D03*
X1289574Y562834D03*
X1291695Y567536D03*
X1280468Y1335001D03*
X1313372Y1334907D03*
X1346172Y1335141D03*
X1374765Y618274D03*
X1378754Y1354318D03*
X1407465Y651240D03*
X1440065Y683835D03*
X1472983Y703385D03*
X1506065Y703404D03*
X1538865Y703451D03*
X1571995Y681501D03*
X1604765Y647601D03*
X1637765Y628715D03*
X1662137Y1398599D03*
X1694919Y1398699D03*
G54D54*
X62831Y1575194D03*
X80153D03*
X116246Y1580308D03*
X133568D03*
X203980Y627557D03*
X221302D03*
X1655694Y604703D03*
X1673016D03*
X1745150Y1621650D03*
X1762472D03*
X1797091Y1621550D03*
X1814413D03*
G54D129*
X270291Y589457D03*
G54D138*
X283817Y585179D03*
G54D91*
X139774Y1679174D03*
G54D64*
X71307Y1535961D03*
X107050D03*
X118703Y1370083D03*
X151303D03*
X184003D03*
X216903D03*
X249703D03*
X252353Y660034D03*
X285083Y694275D03*
X283303Y1323937D03*
X317853Y714425D03*
X316199Y1323909D03*
X350913Y714157D03*
X349103Y1323852D03*
X383953Y714225D03*
X381903Y1324052D03*
X416953Y696425D03*
X414485Y1343383D03*
X449353Y671825D03*
X481953Y645325D03*
X515253Y611225D03*
X726259Y1388092D03*
X759041Y1388192D03*
X1090441Y1370064D03*
X1123041D03*
X1155741D03*
X1188641D03*
X1221441D03*
X1259432Y1323918D03*
X1292328Y1323890D03*
X1325232Y1323833D03*
X1362905Y629368D03*
X1358032Y1324033D03*
X1395605Y662268D03*
X1390614Y1343364D03*
X1428205Y694848D03*
X1461123Y714425D03*
X1494205Y714593D03*
X1527005Y714425D03*
X1560135Y692485D03*
X1592905Y658716D03*
X1625905Y639716D03*
X1673992Y1387381D03*
X1706774Y1387481D03*
X1758590Y1568997D03*
X1794333D03*
G54D319*
X1790206Y204003D03*
G54D238*
X762913Y1490789D03*
Y1506538D03*
Y1502600D03*
Y1498663D03*
Y1494726D03*
Y1522286D03*
Y1518349D03*
Y1514412D03*
Y1510474D03*
Y1526223D03*
X779527Y1492758D03*
Y1488821D03*
Y1504569D03*
Y1500632D03*
Y1496695D03*
Y1520317D03*
Y1516380D03*
Y1512443D03*
Y1508506D03*
Y1528191D03*
Y1524254D03*
G54D193*
X492000Y413335D03*
X488260Y422665D03*
X495740D03*
X552000Y434835D03*
X548260Y444165D03*
X555740D03*
G54D148*
X335823Y270260D03*
X326177D03*
X335823Y277740D03*
X326177Y274000D03*
Y277740D03*
X382323Y311240D03*
Y303760D03*
X372677D03*
Y307500D03*
Y311240D03*
X604494Y432209D03*
X594848D03*
X604494Y439689D03*
X594848Y435949D03*
Y439689D03*
X797551Y384932D03*
Y377452D03*
X787905D03*
Y381192D03*
Y384932D03*
X1246555Y90470D03*
X1236909D03*
X1246555Y97950D03*
X1236909Y94210D03*
Y97950D03*
X1678258Y220857D03*
X1668612D03*
Y224597D03*
X1678258Y228337D03*
X1668612D03*
G54D229*
X721963Y1577932D03*
Y1586790D03*
G54D265*
X897439Y1144562D03*
X944464D03*
X1303767Y548297D03*
X1613357Y550157D03*
G54D37*
X50773Y754595D03*
Y775855D03*
G54D283*
X999455Y208592D03*
Y205049D03*
Y201506D03*
Y197962D03*
G54D19*
X14092Y292892D03*
Y295452D03*
X28068D03*
Y292892D03*
X44692D03*
Y295452D03*
X58668D03*
Y292892D03*
X1632822Y224597D03*
Y227157D03*
X1646798Y224597D03*
Y227157D03*
G54D55*
X66854Y1605956D03*
X65279D03*
X63704D03*
X62129D03*
X60554D03*
X58980D03*
X57405D03*
X55830D03*
X54255D03*
X52680D03*
Y1624854D03*
X54255D03*
X55830D03*
X57405D03*
X58980D03*
X60554D03*
X62129D03*
X63704D03*
X65279D03*
X66854D03*
X631608Y1362808D03*
X633183D03*
Y1381706D03*
X631608D03*
X634758Y1362808D03*
X636333D03*
X637908D03*
X639482D03*
X641057D03*
X642632D03*
X644207D03*
X645782D03*
X634758Y1381706D03*
X636333D03*
X637908D03*
X639482D03*
X641057D03*
X642632D03*
X644207D03*
X645782D03*
X1642196Y1416092D03*
X1643771D03*
X1645346D03*
X1646921D03*
X1645346Y1434990D03*
X1646921D03*
X1643771D03*
X1642196D03*
X1648496Y1416092D03*
X1650070D03*
X1651645D03*
X1653220D03*
X1654795D03*
X1656370D03*
X1648496Y1434990D03*
X1650070D03*
X1651645D03*
X1653220D03*
X1654795D03*
X1656370D03*
X1750116Y1659507D03*
X1748542D03*
X1746967D03*
X1745392D03*
X1743817D03*
X1742242D03*
Y1678405D03*
X1743817D03*
X1745392D03*
X1746967D03*
X1748542D03*
X1750116D03*
X1756416Y1659507D03*
X1754841D03*
X1753266D03*
X1751691D03*
Y1678405D03*
X1753266D03*
X1754841D03*
X1756416D03*
G54D157*
X388273Y-24855D03*
Y-22887D03*
X728493D03*
Y-24855D03*
X839752Y-20995D03*
Y-19027D03*
Y-995D03*
Y973D03*
Y19005D03*
Y20973D03*
X1179972Y-19027D03*
Y-20995D03*
Y973D03*
Y-995D03*
Y20973D03*
Y19005D03*
X1243272Y-20995D03*
Y-19027D03*
Y-995D03*
Y973D03*
Y19005D03*
Y20973D03*
X1438831Y-19027D03*
Y-20995D03*
Y973D03*
Y-995D03*
Y20973D03*
Y19005D03*
X1536566Y-25196D03*
Y-23228D03*
X1732125D03*
Y-25196D03*
X1803347Y201642D03*
G54D292*
X1176972Y76008D03*
X1171854D03*
Y83488D03*
X1176972D03*
G54D175*
X467750Y1684738D03*
Y1692218D03*
X470309Y1684738D03*
X472868D03*
X470309Y1692218D03*
X472868D03*
X1387620Y1716438D03*
X1385061D03*
X1390179D03*
X1387620Y1723918D03*
X1385061D03*
X1390179D03*
G54D73*
X111339Y1422181D03*
Y1444819D03*
X125512Y1422181D03*
X123937D03*
X122362D03*
X120787D03*
X119213D03*
X117638D03*
X116063D03*
X114488D03*
X112913D03*
Y1444819D03*
X114488D03*
X116063D03*
X117638D03*
X119213D03*
X120787D03*
X122362D03*
X123937D03*
X125512D03*
X128661Y1422181D03*
X127087D03*
Y1444819D03*
X128661D03*
X1213913Y1408681D03*
X1212339D03*
Y1431319D03*
X1213913D03*
X1229661Y1408681D03*
X1228087D03*
X1226512D03*
X1224937D03*
X1223362D03*
X1221787D03*
X1220213D03*
X1218638D03*
X1217063D03*
X1215488D03*
Y1431319D03*
X1217063D03*
X1218638D03*
X1220213D03*
X1221787D03*
X1223362D03*
X1224937D03*
X1226512D03*
X1228087D03*
X1229661D03*
G54D274*
X905815Y1155362D03*
X952840D03*
X1315608Y561302D03*
X1621733Y560957D03*
G54D82*
X129932Y1665000D03*
G54D184*
X476826Y293510D03*
X563826Y302510D03*
G54D247*
X791280Y1297982D03*
Y1321012D03*
G54D28*
X26272Y1461614D03*
Y1478936D03*
X50272Y1461614D03*
Y1478936D03*
X74272Y1461614D03*
Y1478936D03*
X98272Y1461614D03*
Y1478936D03*
X692761Y1301317D03*
Y1318639D03*
X716639Y1301357D03*
Y1318679D03*
X740639Y1301357D03*
Y1318679D03*
X764639Y1301357D03*
Y1318679D03*
X891423Y1234759D03*
Y1252081D03*
X915423Y1234759D03*
Y1252081D03*
X950407Y1234759D03*
Y1252081D03*
X974407Y1234759D03*
Y1252081D03*
X1313500Y624839D03*
Y642161D03*
X1655872Y1300929D03*
Y1318251D03*
X1679872Y1300929D03*
Y1318251D03*
X1703872Y1300929D03*
Y1318251D03*
X1727667Y1300929D03*
Y1318251D03*
X1747479Y1487944D03*
Y1505266D03*
X1771479Y1487944D03*
Y1505266D03*
X1795479Y1487944D03*
Y1505266D03*
X1819479Y1487944D03*
Y1505266D03*
G54D46*
X71121Y1493645D03*
Y1511755D03*
X82974Y1326471D03*
Y1344581D03*
X99696Y1493645D03*
Y1511755D03*
X227957Y683164D03*
Y701274D03*
X438700Y1300918D03*
Y1319028D03*
X553787Y622456D03*
Y640566D03*
X1054712Y1326452D03*
Y1344562D03*
X1339222Y643716D03*
Y661826D03*
X1414559Y1300319D03*
Y1318429D03*
X1664127Y665084D03*
Y683194D03*
X1758404Y1526681D03*
Y1544791D03*
X1786979Y1526681D03*
Y1544791D03*
G54D256*
X828390Y1420331D03*
X841240Y1407481D03*
X832154Y1411245D03*
Y1429417D03*
X841240Y1433181D03*
X850326Y1411245D03*
Y1429417D03*
X854090Y1420331D03*
X916546Y309460D03*
X911495Y321654D03*
X916546Y333848D03*
X928740Y304409D03*
Y338899D03*
X940934Y309460D03*
X945985Y321654D03*
X940934Y333848D03*
X1007154Y1411245D03*
X1003390Y1420331D03*
X1007154Y1429417D03*
X1016240Y1407481D03*
Y1433181D03*
X1025326Y1411245D03*
Y1429417D03*
X1029090Y1420331D03*
G54D139*
X286784Y585177D03*
G54D166*
X439169Y106684D03*
X437200D03*
X435232D03*
X433263D03*
X431295D03*
X429326D03*
Y141330D03*
X431295D03*
X433263D03*
X435232D03*
X437200D03*
X439169D03*
X452948Y106684D03*
X450980D03*
X449011D03*
X447043D03*
X445074D03*
X443106D03*
X441137D03*
Y141330D03*
X443106D03*
X445074D03*
X447043D03*
X449011D03*
X450980D03*
X452948D03*
X458854Y106684D03*
X456885D03*
X454917D03*
Y141330D03*
X456885D03*
X458854D03*
G54D176*
X483967Y213093D03*
G54D83*
X139774Y1665000D03*
G54D185*
X474070Y295282D03*
X561070Y304282D03*
G54D56*
X59767Y1615405D03*
X638695Y1372257D03*
X1649283Y1425541D03*
X1749329Y1668956D03*
G54D149*
X330934Y552397D03*
X328375D03*
X325816D03*
Y560271D03*
X328375D03*
X330934D03*
X1542675Y547341D03*
X1540116D03*
Y555215D03*
X1542675D03*
X1545234Y547341D03*
Y555215D03*
G54D167*
X444090Y124007D03*
G54D284*
X1008631Y514587D03*
Y517146D03*
Y519705D03*
Y522264D03*
Y524824D03*
Y527383D03*
Y529942D03*
Y532501D03*
X1030679Y522264D03*
Y519705D03*
Y517146D03*
Y514587D03*
Y532501D03*
Y529942D03*
Y527383D03*
Y524824D03*
X1040045Y376007D03*
Y378566D03*
Y381125D03*
Y383684D03*
Y386244D03*
Y388803D03*
Y391362D03*
Y393921D03*
X1040425Y411704D03*
Y414263D03*
Y416822D03*
Y419381D03*
Y421941D03*
Y424500D03*
Y427059D03*
Y429618D03*
X1062093Y388803D03*
Y386244D03*
Y383684D03*
Y381125D03*
Y378566D03*
Y376007D03*
Y393921D03*
Y391362D03*
X1062473Y419381D03*
Y416822D03*
Y414263D03*
Y411704D03*
Y429618D03*
Y427059D03*
Y424500D03*
Y421941D03*
X1097111Y375469D03*
Y378028D03*
Y380587D03*
Y383146D03*
Y385706D03*
Y388265D03*
Y390824D03*
Y393383D03*
X1119159Y388265D03*
Y385706D03*
Y383146D03*
Y380587D03*
Y378028D03*
Y375469D03*
Y393383D03*
Y390824D03*
X1220178Y162158D03*
Y164717D03*
Y167276D03*
Y169835D03*
Y172395D03*
Y174954D03*
Y177513D03*
Y180072D03*
X1242226Y164717D03*
Y162158D03*
Y180072D03*
Y177513D03*
Y174954D03*
Y172395D03*
Y169835D03*
Y167276D03*
G54D92*
X136428Y1680945D03*
X134853D03*
X133278D03*
G54D275*
X910741Y1641723D03*
X947553D03*
G54D29*
X47300Y277798D03*
Y280357D03*
Y282916D03*
X47260Y308541D03*
Y311100D03*
Y313659D03*
X54780Y282916D03*
Y280357D03*
Y277798D03*
X54740Y313659D03*
Y311100D03*
Y308541D03*
X384155Y152818D03*
Y157936D03*
X391635D03*
Y155377D03*
Y152818D03*
X603245Y401728D03*
Y404287D03*
Y406846D03*
X610725Y401728D03*
Y406846D03*
X1005169Y295634D03*
Y293075D03*
Y290516D03*
X997689D03*
Y293075D03*
Y295634D03*
X1810280Y146716D03*
X1802800D03*
Y149275D03*
X1810280Y151834D03*
X1802800D03*
X1805069Y366053D03*
Y368612D03*
Y371171D03*
X1805629Y385293D03*
Y387852D03*
Y390411D03*
X1805648Y418775D03*
X1798168D03*
X1805659Y410615D03*
Y408056D03*
Y405497D03*
X1798179D03*
Y408056D03*
Y410615D03*
X1805648Y423893D03*
Y421334D03*
X1798168D03*
Y423893D03*
X1812549Y371171D03*
Y366053D03*
X1813109Y385293D03*
Y390411D03*
G54D194*
X507261Y135722D03*
Y134147D03*
Y149895D03*
Y148321D03*
Y146746D03*
Y145171D03*
Y143596D03*
Y142021D03*
Y140447D03*
Y138872D03*
Y137297D03*
Y156195D03*
Y154620D03*
Y153045D03*
Y151470D03*
X537575Y134147D03*
Y135722D03*
Y137297D03*
Y138872D03*
Y140447D03*
Y142021D03*
Y143596D03*
Y145171D03*
Y146746D03*
Y148321D03*
Y149895D03*
Y156195D03*
Y151470D03*
Y153045D03*
Y154620D03*
G54D266*
X897437Y1141595D03*
X944462D03*
X1303765Y545330D03*
X1613355Y547190D03*
G54D293*
X1196187Y98316D03*
Y100875D03*
Y103434D03*
X1204849D03*
Y98316D03*
G54D74*
X108681Y1424839D03*
Y1426413D03*
Y1427988D03*
Y1429563D03*
Y1431138D03*
Y1432713D03*
Y1434287D03*
Y1435862D03*
Y1437437D03*
Y1439012D03*
Y1440587D03*
Y1442161D03*
X131319Y1432713D03*
Y1431138D03*
Y1429563D03*
Y1427988D03*
Y1426413D03*
Y1424839D03*
Y1442161D03*
Y1440587D03*
Y1439012D03*
Y1437437D03*
Y1435862D03*
Y1434287D03*
X1209681Y1411339D03*
Y1412913D03*
Y1414488D03*
Y1416063D03*
Y1417638D03*
Y1419213D03*
Y1420787D03*
Y1422362D03*
Y1423937D03*
Y1425512D03*
Y1427087D03*
Y1428661D03*
X1232319Y1417638D03*
Y1416063D03*
Y1414488D03*
Y1412913D03*
Y1411339D03*
Y1428661D03*
Y1427087D03*
Y1425512D03*
Y1423937D03*
Y1422362D03*
Y1420787D03*
Y1419213D03*
G54D257*
X828780Y1684890D03*
X818780D03*
X828780Y1694890D03*
X818780D03*
X828780Y1704890D03*
X818780D03*
X828780Y1714890D03*
X818780D03*
X853780Y1684890D03*
Y1694890D03*
Y1704890D03*
Y1714890D03*
X863780Y1684890D03*
Y1694890D03*
Y1704890D03*
Y1714890D03*
X888780Y1684890D03*
Y1694890D03*
Y1704890D03*
Y1714890D03*
X898780Y1684890D03*
Y1694890D03*
Y1704890D03*
Y1714890D03*
X918780Y1684890D03*
Y1694890D03*
Y1704890D03*
Y1714890D03*
X928780Y1684890D03*
Y1694890D03*
Y1704890D03*
Y1714890D03*
X938780Y1684890D03*
Y1694890D03*
Y1704890D03*
X958780Y1684890D03*
Y1694890D03*
Y1704890D03*
Y1714890D03*
X968780Y1684890D03*
Y1694890D03*
Y1704890D03*
Y1714890D03*
X993780Y1684890D03*
Y1694890D03*
Y1704890D03*
Y1714890D03*
X1003780Y1684890D03*
Y1694890D03*
Y1704890D03*
Y1714890D03*
X1028780Y1684890D03*
X1038780D03*
X1028780Y1694890D03*
X1038780D03*
X1028780Y1704890D03*
Y1714890D03*
X1038780Y1704890D03*
Y1714890D03*
G54D65*
X91454Y156791D03*
X286253Y154803D03*
X610229Y224877D03*
X823514Y136898D03*
X847479Y214391D03*
X1279902Y406725D03*
X1556217Y300416D03*
X1689073Y1686245D03*
X1734992Y370384D03*
G54D47*
X65205Y1519505D03*
X100948D03*
X112601Y1353627D03*
X145201D03*
X177901D03*
X210801D03*
X243601D03*
X258455Y676490D03*
X277201Y1307481D03*
X291185Y710731D03*
X310097Y1307453D03*
X323955Y730881D03*
X343001Y1307396D03*
X357015Y730613D03*
X375801Y1307596D03*
X390055Y730681D03*
X408383Y1326927D03*
X423055Y712881D03*
X455455Y688281D03*
X488055Y661781D03*
X521355Y627681D03*
X720157Y1371636D03*
X752939Y1371736D03*
X1084339Y1353608D03*
X1116939D03*
X1149639D03*
X1182539D03*
X1215339D03*
X1253330Y1307462D03*
X1286226Y1307434D03*
X1319130Y1307377D03*
X1351930Y1307577D03*
X1369007Y645824D03*
X1384512Y1326908D03*
X1401707Y678724D03*
X1434307Y711304D03*
X1467225Y730881D03*
X1500307Y731049D03*
X1533107Y730881D03*
X1566237Y708941D03*
X1599007Y675172D03*
X1632007Y656172D03*
X1667890Y1370925D03*
X1700672Y1371025D03*
X1752488Y1552541D03*
X1788231D03*
G54D239*
X766889Y1486756D03*
Y1530256D03*
G54D158*
X385443Y256059D03*
Y271807D03*
X846352Y256772D03*
Y272520D03*
X974408Y153162D03*
Y168910D03*
G54D38*
X50773Y753020D03*
G54D248*
X785252Y1342245D03*
G54D75*
X120000Y1433500D03*
X1221000Y1420000D03*
G54D285*
X1029035Y455244D03*
Y457803D03*
Y460362D03*
Y462921D03*
Y465480D03*
Y468039D03*
Y470599D03*
Y473158D03*
Y475717D03*
Y478276D03*
Y480835D03*
Y483394D03*
X1051083Y462921D03*
Y460362D03*
Y457803D03*
Y455244D03*
Y478276D03*
Y475717D03*
Y473158D03*
Y470599D03*
Y468039D03*
Y465480D03*
Y483394D03*
Y480835D03*
X1118614Y455244D03*
Y457803D03*
Y460362D03*
Y462921D03*
Y465480D03*
Y468039D03*
Y470599D03*
Y473158D03*
Y475717D03*
Y478276D03*
Y480835D03*
Y483394D03*
X1140662Y462921D03*
Y460362D03*
Y457803D03*
Y455244D03*
Y478276D03*
Y475717D03*
Y473158D03*
Y470599D03*
Y468039D03*
Y465480D03*
Y483394D03*
Y480835D03*
G54D258*
X842596Y58448D03*
X840037D03*
Y81448D03*
X842596D03*
X847715Y58448D03*
X845156D03*
Y81448D03*
X847715D03*
G54D294*
X1211531Y128748D03*
Y133866D03*
X1217831Y131307D03*
G54D186*
X475251Y299219D03*
X562251Y308219D03*
G54D249*
X785252Y1334469D03*
X796276Y1347855D03*
X905618Y1141976D03*
X916642Y1155362D03*
X952643Y1141976D03*
X963667Y1155362D03*
X1315411Y547916D03*
X1326435Y561302D03*
X1621536Y547571D03*
X1632560Y560957D03*
G54D195*
X512969Y130014D03*
X511394D03*
Y160328D03*
X512969D03*
X528717Y130014D03*
X527142D03*
X525568D03*
X523993D03*
X522418D03*
X520843D03*
X519268D03*
X517694D03*
X516119D03*
X514544D03*
X520843Y160328D03*
X522418D03*
X523993D03*
X525568D03*
X527142D03*
X528717D03*
X514544D03*
X516119D03*
X517694D03*
X519268D03*
X533442Y130014D03*
X531867D03*
X530292D03*
Y160328D03*
X531867D03*
X533442D03*
G54D48*
X59201Y1529938D03*
X94944D03*
X106597Y1364060D03*
X139197D03*
X171897D03*
X204797D03*
X237597D03*
X264459Y666057D03*
X271197Y1317914D03*
X297189Y700298D03*
X304093Y1317886D03*
X329959Y720448D03*
X336997Y1317829D03*
X363019Y720180D03*
X369797Y1318029D03*
X396059Y720248D03*
X402379Y1337360D03*
X429059Y702448D03*
X461459Y677848D03*
X494059Y651348D03*
X527359Y617248D03*
X714153Y1382069D03*
X746935Y1382169D03*
X1078335Y1364041D03*
X1110935D03*
X1143635D03*
X1176535D03*
X1209335D03*
X1247326Y1317895D03*
X1280222Y1317867D03*
X1313126Y1317810D03*
X1345926Y1318010D03*
X1375011Y635391D03*
X1378508Y1337341D03*
X1407711Y668291D03*
X1440311Y700871D03*
X1473229Y720448D03*
X1506311Y720616D03*
X1539111Y720448D03*
X1572241Y698508D03*
X1605011Y664739D03*
X1638011Y645739D03*
X1661886Y1381358D03*
X1694668Y1381458D03*
X1746484Y1562974D03*
X1782227D03*
G54D177*
X481161Y214077D03*
X579478Y227071D03*
G54D159*
X389743Y482395D03*
X387184D03*
X384625D03*
Y491057D03*
X387184D03*
X389743D03*
G54D39*
X50773Y777430D03*
G54D276*
X938780Y1714890D03*
G54D93*
X131703Y1680945D03*
G54D267*
X900240Y1143460D03*
X947265D03*
G54D66*
X99729Y289822D03*
Y310256D03*
X757184Y1722772D03*
X1072863Y1429176D03*
X1080970Y1660958D03*
X1299439Y92812D03*
X1550377Y581353D03*
G54D84*
X139774Y1671300D03*
Y1669725D03*
Y1666575D03*
Y1668150D03*
Y1674449D03*
Y1672874D03*
Y1677599D03*
Y1676024D03*
G54D57*
X64462Y1658400D03*
X66430D03*
X62493D03*
X60525D03*
X64462Y1673360D03*
X62493D03*
X60525D03*
X66430D03*
X68399Y1658400D03*
X70367D03*
X68399Y1673360D03*
X70367D03*
G54D168*
X426767Y109243D03*
Y111212D03*
Y113180D03*
Y115149D03*
Y117117D03*
Y119086D03*
Y121054D03*
Y123023D03*
Y124991D03*
Y126960D03*
Y128928D03*
Y130897D03*
Y132865D03*
Y134834D03*
Y136802D03*
Y138771D03*
X461413Y121054D03*
Y119086D03*
Y117117D03*
Y115149D03*
Y113180D03*
Y111212D03*
Y109243D03*
Y134834D03*
Y132865D03*
Y130897D03*
Y128928D03*
Y126960D03*
Y124991D03*
Y123023D03*
Y138771D03*
Y136802D03*
G54D187*
X476826Y304928D03*
X563826Y313928D03*
G54D196*
X522418Y145171D03*
G54D58*
X65446Y1665880D03*
G54D49*
X61760Y1535942D03*
X97503D03*
X109156Y1370064D03*
X141756D03*
X174456D03*
X207356D03*
X240156D03*
X261900Y660053D03*
X273756Y1323918D03*
X294630Y694294D03*
X306652Y1323890D03*
X327400Y714444D03*
X339556Y1323833D03*
X360460Y714176D03*
X372356Y1324033D03*
X393500Y714244D03*
X404938Y1343364D03*
X426500Y696444D03*
X458900Y671844D03*
X491500Y645344D03*
X524800Y611244D03*
X716712Y1388073D03*
X749494Y1388173D03*
X1080894Y1370045D03*
X1113494D03*
X1146194D03*
X1179094D03*
X1211894D03*
X1249885Y1323899D03*
X1282781Y1323871D03*
X1315685Y1323814D03*
X1348485Y1324014D03*
X1372452Y629387D03*
X1381067Y1343345D03*
X1405152Y662287D03*
X1437752Y694867D03*
X1470670Y714444D03*
X1503752Y714612D03*
X1536552Y714444D03*
X1569682Y692504D03*
X1602452Y658735D03*
X1635452Y639735D03*
X1664445Y1387362D03*
X1697227Y1387462D03*
X1749043Y1568978D03*
X1784786D03*
G54D259*
X841742Y105951D03*
Y99651D03*
X850088Y105951D03*
Y99651D03*
G54D268*
X901650Y1175243D03*
Y1219735D03*
X956504Y1175243D03*
Y1219735D03*
G54D169*
X428899Y225205D03*
Y227764D03*
Y230323D03*
Y232883D03*
Y235442D03*
Y238001D03*
X451931Y225205D03*
Y238001D03*
Y235442D03*
Y232883D03*
Y230323D03*
Y227764D03*
X506945Y227882D03*
Y230441D03*
Y233000D03*
Y235560D03*
Y238119D03*
Y240678D03*
X529977D03*
Y238119D03*
Y235560D03*
Y233000D03*
Y230441D03*
Y227882D03*
G54D277*
X961084Y1541966D03*
Y1559682D03*
X992696Y1541982D03*
Y1559698D03*
X1024296Y1541982D03*
Y1559698D03*
X1055896Y1541982D03*
Y1559698D03*
G54D76*
X110770Y1662719D03*
X107620D03*
X110770D03*
X110775Y1657752D03*
D03*
X107625D03*
X113920Y1662719D03*
X113925Y1657752D03*
X134902Y671290D03*
X131752D03*
X138052D03*
X134902D03*
Y683290D03*
X131752D03*
X138052D03*
X134902D03*
X155710Y1679384D03*
X152560D03*
X155710D03*
Y1674239D03*
X152560D03*
X155710D03*
X169575Y670500D03*
D03*
X166425D03*
X169575Y676500D03*
D03*
X166425D03*
X158860Y1679384D03*
Y1674239D03*
X172725Y670500D03*
Y676500D03*
X235147Y127118D03*
X238297D03*
X273474Y1512220D03*
Y1516120D03*
X276624D03*
X279774D03*
X276624Y1512220D03*
Y1516120D03*
Y1512220D03*
X279774D03*
X404686Y1516120D03*
X407836D03*
X404686Y1512220D03*
X407836D03*
X401536D03*
X404686D03*
X401536Y1516120D03*
X404686D03*
X484080Y144392D03*
Y139492D03*
D03*
X480930D03*
X484080Y144392D03*
X480930D03*
X492080Y128942D03*
X495230D03*
X492080Y133942D03*
X495230D03*
X492080Y128942D03*
X488930D03*
X492080Y133942D03*
X488930D03*
X487230Y144392D03*
Y139492D03*
X540797Y1516120D03*
X543947D03*
X537647Y1512220D03*
X540797D03*
D03*
X543947D03*
X537647Y1516120D03*
X540797D03*
X573360Y122785D03*
X565210D03*
X568360D03*
X576510D03*
X672715Y1530526D03*
X675865D03*
X672715Y1526626D03*
X675865D03*
X669565Y1530526D03*
X672715D03*
X669565Y1526626D03*
X672715D03*
X1013620Y230423D03*
X1016770D03*
X1168957Y575602D03*
X1165807D03*
X1168957D03*
X1169000Y592673D03*
X1165850D03*
X1169000D03*
X1172107Y575602D03*
X1172150Y592673D03*
X1228118Y132739D03*
D03*
X1224968D03*
X1228118Y128239D03*
D03*
X1224968D03*
X1231268Y132739D03*
Y128239D03*
X1269437Y166051D03*
X1272587D03*
D03*
X1269437Y162051D03*
X1272587D03*
D03*
Y158051D03*
X1269437D03*
X1272587D03*
Y180565D03*
X1269437D03*
X1272587D03*
Y176051D03*
X1269437D03*
X1272587D03*
X1269437Y171551D03*
X1272587D03*
D03*
X1269437Y184987D03*
X1272587D03*
D03*
X1275737Y166051D03*
Y162051D03*
Y158051D03*
Y180565D03*
Y176051D03*
Y171551D03*
Y184987D03*
X1284497Y1549120D03*
X1287647D03*
X1281347D03*
X1284497D03*
X1281347Y1545220D03*
X1284497D03*
D03*
X1287647D03*
X1412559Y1549120D03*
X1415709D03*
X1409409D03*
X1412559D03*
X1409409Y1545220D03*
X1412559D03*
D03*
X1415709D03*
X1548671Y1549120D03*
X1551821D03*
X1548671Y1545220D03*
X1551821D03*
X1545521D03*
X1548671D03*
X1545521Y1549120D03*
X1548671D03*
X1677439Y1559626D03*
Y1563526D03*
X1680589D03*
X1683739D03*
X1680589Y1559626D03*
Y1563526D03*
Y1559626D03*
X1683739D03*
G54D178*
X481211Y215652D03*
Y217227D03*
X488297D03*
Y215652D03*
Y214077D03*
X509320Y212498D03*
Y214072D03*
X514832D03*
X572342Y223921D03*
Y225496D03*
Y227071D03*
X579428Y223921D03*
Y225496D03*
X796276Y1342737D03*
Y1341162D03*
Y1339587D03*
Y1338012D03*
Y1336438D03*
Y1345886D03*
Y1344312D03*
X905618Y1143945D03*
Y1145519D03*
Y1147094D03*
Y1148669D03*
Y1150244D03*
Y1151819D03*
Y1153393D03*
X952643Y1143945D03*
Y1145519D03*
Y1147094D03*
Y1148669D03*
Y1150244D03*
Y1151819D03*
Y1153393D03*
X1315411Y549885D03*
Y551459D03*
Y553034D03*
Y554609D03*
Y556184D03*
Y557759D03*
Y559333D03*
X1621536Y549540D03*
Y551114D03*
Y552689D03*
Y554264D03*
Y555839D03*
Y557414D03*
Y558988D03*
G54D286*
X1027520Y543499D03*
Y549799D03*
G54D94*
X138003Y1680945D03*
G54D67*
X102160Y1444500D03*
X103950Y1436000D03*
X246314Y561512D03*
X265210Y559512D03*
X527280Y120930D03*
X533520Y122200D03*
X663728Y422820D03*
X666919Y471854D03*
X829390Y1466384D03*
X818885Y1467654D03*
X1189242Y1465128D03*
X1178737Y1466398D03*
X1310450Y556184D03*
X1662146Y1414965D03*
G54D85*
X136428Y1663229D03*
X134853D03*
X133278D03*
G54D295*
X1225530Y60384D03*
X1233404D03*
X1241278D03*
X1439049Y87432D03*
X1454797D03*
X1446923D03*
G54D86*
X138003Y1663229D03*
G54D188*
X478794Y304928D03*
X565794Y313928D03*
G54D77*
X111369Y1683513D03*
X109269D03*
X107169D03*
X109269D03*
X111369Y1688013D03*
X109269D03*
X107169D03*
X109269D03*
X155811Y1661655D03*
X153711D03*
X155811D03*
Y1666210D03*
X153711D03*
X155811D03*
X168113Y1483690D03*
X170213D03*
X168113Y1480090D03*
X170213D03*
X165750Y1491010D03*
X167850D03*
X168113Y1501890D03*
X170213D03*
X168113Y1505490D03*
X170213D03*
X165640Y1494340D03*
X167740D03*
X163288Y1510800D03*
X165388D03*
X164288Y1518040D03*
X166388D03*
X169288Y1510800D03*
X171388D03*
X169288Y1514420D03*
X171388D03*
X169288Y1518040D03*
X171388D03*
X166383Y1523431D03*
X168483D03*
X166383Y1526631D03*
X168483D03*
X164650Y1534800D03*
X162550D03*
Y1531600D03*
X164650D03*
X162550Y1542500D03*
X164650D03*
X162550Y1538000D03*
X164650D03*
X157911Y1661655D03*
Y1666210D03*
X179786Y1649166D03*
X181886D03*
X179786Y1652366D03*
X181886D03*
X179786Y1655566D03*
X181886D03*
X186386Y1658766D03*
X179786D03*
X181886D03*
X188486D03*
X275621Y1480582D03*
X273521D03*
X275621Y1484182D03*
X273521D03*
X275621Y1493982D03*
X273521D03*
X275621Y1497582D03*
X273521D03*
X273350Y1535270D03*
X275450D03*
X273350Y1538370D03*
X275450D03*
X280450Y1506600D03*
X278350D03*
X283550Y1505000D03*
X285650D03*
X278350Y1503100D03*
X280450D03*
X296175Y1480090D03*
X298275D03*
X296175Y1483690D03*
X298275D03*
X296175Y1505490D03*
X298275D03*
X296175Y1501890D03*
X298275D03*
X297350Y1518040D03*
X299450D03*
X297350Y1514420D03*
X299450D03*
X292350Y1517640D03*
X294450D03*
X297350Y1510800D03*
X299450D03*
X291350D03*
X293450D03*
X294445Y1523431D03*
X296545D03*
X294445Y1526631D03*
X296545D03*
X296207Y1532851D03*
X294107D03*
X371850Y1579400D03*
X369750D03*
X371850Y1582600D03*
X369750D03*
X372950Y1639400D03*
X370850D03*
X379250D03*
X377150D03*
X379250Y1642600D03*
X377150D03*
X379250Y1649000D03*
X377150D03*
X379250Y1645800D03*
X377150D03*
X383673Y1576448D03*
X385773D03*
X403683Y1480582D03*
X401583D03*
X403683Y1484182D03*
X401583D03*
X403683Y1497582D03*
X401583D03*
X403683Y1493982D03*
X401583D03*
X408512Y1506600D03*
X406412D03*
Y1503100D03*
X404312D03*
X409150Y1544200D03*
Y1538000D03*
X403005Y1598560D03*
X400905D03*
X411612Y1505000D03*
X413712D03*
X411400Y1533440D03*
X413500D03*
X411250Y1544200D03*
Y1538000D03*
X418090Y1557310D03*
X415990D03*
X411319Y1563520D03*
X413419D03*
X432286Y1480090D03*
X434386D03*
X432286Y1483690D03*
X434386D03*
X432286Y1501890D03*
X434386D03*
X432286Y1505490D03*
X434386D03*
X433461Y1518040D03*
X435561D03*
X433461Y1514420D03*
X435561D03*
X428461Y1517640D03*
X430561D03*
X433461Y1510800D03*
X435561D03*
X427461D03*
X429561D03*
X430556Y1523431D03*
X432656D03*
X430556Y1526631D03*
X432656D03*
X434558Y1563907D03*
X436658D03*
X431491Y1596983D03*
X429391D03*
X445567Y1579843D03*
X447667D03*
X463950Y1579400D03*
X466050D03*
X463950Y1576200D03*
X466050D03*
X513770Y107320D03*
X511670D03*
X518270D03*
X520370D03*
X539794Y1484182D03*
X537694D03*
X539794Y1480582D03*
X537694D03*
X539794Y1493982D03*
X537694D03*
X539794Y1497582D03*
X537694D03*
X542523Y1506600D03*
Y1503100D03*
X537547Y1534709D03*
X539647D03*
X537547Y1539572D03*
X539647D03*
X548338Y1503960D03*
X550438D03*
X544623Y1506600D03*
Y1503100D03*
X556523Y1517640D03*
X558623D03*
X555523Y1510800D03*
X557623D03*
X558618Y1523431D03*
Y1526631D03*
X558280Y1532851D03*
X560348Y1483690D03*
X562448D03*
X560348Y1480090D03*
X562448D03*
X560348Y1501890D03*
X562448D03*
X560348Y1505490D03*
X562448D03*
X561523Y1518040D03*
X563623D03*
X561523Y1514420D03*
X563623D03*
X561523Y1510800D03*
X563623D03*
X560718Y1523431D03*
Y1526631D03*
X560380Y1532851D03*
X643455Y1685970D03*
X641355D03*
X649750Y1652400D03*
X651850D03*
X667856Y1484182D03*
X665756D03*
X667856Y1480582D03*
X665756D03*
X667856Y1493982D03*
X665756D03*
X667856Y1497582D03*
X665756D03*
X672099Y1505135D03*
X674199D03*
Y1508335D03*
X672099D03*
X674536Y1652759D03*
X676636D03*
X667312Y1689063D03*
X665212D03*
X686211Y1537520D03*
X684111D03*
X691211D03*
X689111D03*
X686211Y1540720D03*
X684111D03*
X691211D03*
X689111D03*
X698990Y1536250D03*
X701090D03*
X698990Y1531700D03*
X701090D03*
X698990Y1548400D03*
X701090D03*
X698990Y1551700D03*
X701090D03*
X698990Y1541800D03*
X701090D03*
X711792Y173587D03*
X709692D03*
X711792Y177187D03*
X709692D03*
X711792Y185587D03*
X709692D03*
X711792Y189187D03*
X709692D03*
X711792Y197087D03*
X709692D03*
X711792Y200687D03*
X709692D03*
X711792Y208921D03*
X709692D03*
X711792Y212521D03*
X709692D03*
X709150Y1545100D03*
X711250D03*
X709150Y1551700D03*
X711250D03*
X709150Y1538500D03*
X711250D03*
X942596Y208375D03*
X940496D03*
X942596Y204775D03*
X940496D03*
X942596Y211897D03*
X940496D03*
X942596Y215497D03*
X940496D03*
X942596Y229635D03*
X940496D03*
X942596Y226035D03*
X940496D03*
X949296Y218948D03*
X947196D03*
X949296Y222548D03*
X947196D03*
X1141310Y1565312D03*
X1143410D03*
X1148727Y1565315D03*
X1146627D03*
X1161522Y1544575D03*
X1159422D03*
X1170423Y1564600D03*
X1160818Y1554023D03*
X1158718D03*
X1170423Y1575500D03*
Y1571000D03*
Y1567800D03*
X1175986Y1516690D03*
X1178086D03*
X1175986Y1513090D03*
X1178086D03*
X1175986Y1534890D03*
X1178086D03*
X1175986Y1538490D03*
X1178086D03*
X1177161Y1551040D03*
X1179261D03*
X1177161Y1547420D03*
X1179261D03*
X1172161Y1551040D03*
X1174261D03*
X1177161Y1543800D03*
X1179261D03*
X1171161D03*
X1173261D03*
X1174256Y1556431D03*
X1176356D03*
X1174256Y1559631D03*
X1176356D03*
X1172523Y1564600D03*
Y1575500D03*
Y1571000D03*
Y1567800D03*
X1283494Y1517182D03*
X1281394D03*
X1283494Y1513582D03*
X1281394D03*
X1283494Y1530582D03*
X1281394D03*
X1283494Y1526982D03*
X1281394D03*
X1286223Y1536100D03*
X1288323D03*
Y1539600D03*
X1286223D03*
X1281223Y1571370D03*
X1283323D03*
X1281223Y1568270D03*
X1283323D03*
X1304048Y1513090D03*
Y1516690D03*
Y1534890D03*
X1301834Y1528147D03*
X1303934D03*
X1301834Y1525001D03*
X1303934D03*
X1304048Y1538490D03*
X1291423Y1538000D03*
X1293523D03*
X1300223Y1550640D03*
X1302323D03*
X1299223Y1543800D03*
X1301323D03*
X1302318Y1556431D03*
X1304418D03*
X1302318Y1559631D03*
X1304418D03*
X1304080Y1565851D03*
X1301980D03*
X1306148Y1513090D03*
Y1516690D03*
Y1534890D03*
Y1538490D03*
X1305223Y1543800D03*
X1307323D03*
X1305223Y1551040D03*
X1307323D03*
X1305223Y1547420D03*
X1307323D03*
X1411556Y1517182D03*
X1409456D03*
X1411556Y1513582D03*
X1409456D03*
X1411556Y1526982D03*
X1409456D03*
X1411556Y1530582D03*
X1409456D03*
X1414285Y1536100D03*
X1412185D03*
X1419485Y1538000D03*
X1421585D03*
X1416385Y1539600D03*
X1414285D03*
X1419273Y1566440D03*
X1421373D03*
X1417023Y1577200D03*
X1419123D03*
X1416950Y1580400D03*
X1419050D03*
X1417023Y1571000D03*
X1419123D03*
X1436335Y1550640D03*
X1438435D03*
X1435335Y1543800D03*
X1437435D03*
X1438430Y1556431D03*
Y1559631D03*
X1440160Y1513090D03*
X1442260D03*
X1440160Y1516690D03*
X1442260D03*
X1440160Y1534890D03*
X1442260D03*
X1440160Y1538490D03*
X1442260D03*
X1441335Y1543800D03*
X1443435D03*
X1441335Y1551040D03*
X1443435D03*
X1441335Y1547420D03*
X1443435D03*
X1440530Y1556431D03*
Y1559631D03*
X1441187Y1682665D03*
X1439087D03*
X1441187Y1686165D03*
X1439087D03*
X1439050Y1679544D03*
X1441150D03*
X1439067Y1689273D03*
X1441167D03*
X1482680Y1668917D03*
X1480580D03*
X1482450Y1678500D03*
X1484550D03*
X1547668Y1513582D03*
X1545568D03*
X1547668Y1517182D03*
X1545568D03*
X1547668Y1530582D03*
X1545568D03*
X1547668Y1526982D03*
X1545568D03*
X1550396Y1536100D03*
X1552496D03*
X1555596Y1538000D03*
X1557696D03*
X1552496Y1539600D03*
X1550396D03*
X1545396Y1571370D03*
X1547496D03*
X1545397Y1568270D03*
X1547497D03*
X1568222Y1513090D03*
X1570322D03*
X1568222Y1516690D03*
X1570322D03*
X1568222Y1534890D03*
X1570322D03*
X1568222Y1538490D03*
X1570322D03*
X1564397Y1550640D03*
X1566497D03*
X1569397Y1543800D03*
X1571497D03*
X1563397D03*
X1565497D03*
X1569397Y1551040D03*
X1571497D03*
X1569397Y1547420D03*
X1571497D03*
X1566492Y1556431D03*
X1568592D03*
X1566492Y1559631D03*
X1568592D03*
X1568253Y1565851D03*
X1566153D03*
X1656089Y1704237D03*
X1658189D03*
X1675730Y1517182D03*
X1673630D03*
X1675730Y1513582D03*
X1673630D03*
X1675730Y1530582D03*
X1673630D03*
X1675730Y1526982D03*
X1673630D03*
X1668268Y1670149D03*
X1666168D03*
X1679972Y1538135D03*
X1682072D03*
Y1541335D03*
X1679972D03*
X1691975Y1570520D03*
Y1573720D03*
X1694075Y1570520D03*
Y1573720D03*
X1700950Y1595000D03*
X1703050D03*
X1700950Y1598100D03*
X1703050D03*
X1700950Y1604300D03*
X1703050D03*
X1700950Y1601200D03*
X1703050D03*
X1700950Y1607400D03*
X1703050D03*
X1715693Y1606340D03*
X1717793D03*
X1715693Y1599740D03*
X1717793D03*
X1715693Y1612940D03*
X1717793D03*
G54D95*
X150318Y230828D03*
Y227088D03*
X1214094Y277848D03*
Y274108D03*
X1230094Y277848D03*
Y274108D03*
X1222094Y277848D03*
Y274108D03*
X1238094Y277848D03*
Y274108D03*
X1246094Y277848D03*
Y274108D03*
X1254094Y277848D03*
Y274108D03*
X1270094Y277848D03*
Y274108D03*
X1262094Y277848D03*
Y274108D03*
X1278094Y277848D03*
Y274108D03*
X1286094Y277848D03*
Y274108D03*
X1294094Y277848D03*
Y274108D03*
X1302094Y277848D03*
Y274108D03*
X1310094Y277848D03*
Y274108D03*
X1318094Y277848D03*
Y274108D03*
X1325530Y60824D03*
Y64564D03*
X1326094Y277848D03*
Y274108D03*
X1334094Y277848D03*
Y274108D03*
X1337440Y60824D03*
Y64564D03*
X1342094Y277848D03*
Y274108D03*
X1350094Y277848D03*
Y274108D03*
X1361550Y60824D03*
Y64564D03*
X1358094Y277848D03*
Y274108D03*
X1373750Y60824D03*
Y64564D03*
X1366094Y277848D03*
Y274108D03*
G54D197*
X509820Y129423D03*
Y160919D03*
X535016Y129423D03*
Y160919D03*
G54D278*
X961084Y1547766D03*
Y1553882D03*
X992696Y1547782D03*
Y1553898D03*
X1024296Y1547782D03*
Y1553898D03*
X1055896Y1547782D03*
Y1553898D03*
X1091434Y1542225D03*
Y1559343D03*
G54D287*
X1024961Y543499D03*
Y545074D03*
Y546649D03*
Y548224D03*
Y549799D03*
X1030079D03*
Y548224D03*
Y546649D03*
Y545074D03*
Y543499D03*
G54D296*
X1249152Y60384D03*
X1431175Y87432D03*
G54D179*
X476412Y288567D03*
X563412Y297567D03*
G54D269*
X922441Y154311D03*
Y243799D03*
G54D68*
X97477Y1577854D03*
Y1592224D03*
X166600Y1552015D03*
Y1566385D03*
X1174473Y1585015D03*
Y1599385D03*
X1715780Y170079D03*
Y184449D03*
X1779981Y1618865D03*
Y1633235D03*
G54D59*
X57966Y1668833D03*
Y1670801D03*
Y1660959D03*
Y1662927D03*
Y1666864D03*
Y1664896D03*
X72926Y1666864D03*
Y1664896D03*
Y1660959D03*
Y1662927D03*
Y1668833D03*
Y1670801D03*
G54D297*
X1259835Y127553D03*
Y130053D03*
Y132553D03*
Y135053D03*
Y137553D03*
Y140053D03*
Y142553D03*
Y145053D03*
X1280741Y135053D03*
Y132553D03*
Y130053D03*
Y127553D03*
Y145053D03*
Y142553D03*
Y140053D03*
Y137553D03*
G54D69*
X117933Y605376D03*
X763602Y605413D03*
X1094076Y605378D03*
X1739745Y605411D03*
G54D78*
X102529Y1701386D03*
Y1698827D03*
Y1703946D03*
Y1706505D03*
X102583Y1718438D03*
Y1720997D03*
Y1723557D03*
Y1726116D03*
X120107Y1701386D03*
Y1698827D03*
Y1706505D03*
Y1703946D03*
X120161Y1720997D03*
Y1723557D03*
Y1726116D03*
Y1718438D03*
X1128889Y1679853D03*
Y1677293D03*
Y1674734D03*
Y1682412D03*
X1146467D03*
Y1679853D03*
Y1677293D03*
Y1674734D03*
G54D198*
X506670Y132573D03*
Y157769D03*
X538166Y132573D03*
Y157769D03*
G54D189*
X481550Y303156D03*
X568550Y312156D03*
G54D96*
X147290Y481917D03*
Y505343D03*
X174070Y481377D03*
Y504803D03*
G54D279*
X968690Y1633144D03*
Y1659128D03*
X996314Y1633113D03*
Y1659097D03*
G54D288*
X1091434Y1538875D03*
Y1562693D03*
G54D87*
X134853Y1672087D03*
G54D289*
X1108894Y1627567D03*
Y1620087D03*
X1110000Y1689260D03*
Y1696740D03*
G54D97*
X152705Y680396D03*
Y673782D03*
X382797Y1580912D03*
Y1587526D03*
X454288Y1576826D03*
Y1583440D03*
X1188192Y579015D03*
Y585629D03*
X1726334Y667545D03*
Y660931D03*
G54D79*
X123811Y524366D03*
Y529484D03*
X130811D03*
Y526925D03*
Y524366D03*
X271500Y220441D03*
Y223000D03*
Y225559D03*
X278500D03*
Y220441D03*
X852500Y395559D03*
Y390441D03*
X845500D03*
Y393000D03*
Y395559D03*
G54D88*
X129932Y1669725D03*
Y1671300D03*
Y1666575D03*
Y1668150D03*
Y1674449D03*
Y1672874D03*
Y1677599D03*
Y1676024D03*
G54D298*
X1319667Y83687D03*
Y101327D03*
X1323604Y74869D03*
X1327541Y83687D03*
X1323604Y92509D03*
X1327541Y101327D03*
X1373745Y74869D03*
X1369808Y83687D03*
X1377682D03*
G54D199*
X513651Y209692D03*
G54D89*
X131703Y1663229D03*
G54D299*
X1408817Y109037D03*
Y116911D03*
X1417635Y112974D03*
G54D98*
X150185Y680042D03*
X155225D03*
X150185Y674136D03*
X155225D03*
X380277Y1581266D03*
Y1587172D03*
X385317Y1581266D03*
Y1587172D03*
X451768Y1577180D03*
Y1583086D03*
X456808Y1577180D03*
Y1583086D03*
X1185672Y579369D03*
Y585275D03*
X1190712Y579369D03*
Y585275D03*
X1723814Y667191D03*
X1728854D03*
X1723814Y661285D03*
X1728854D03*
G54D99*
X150185Y678073D03*
X155225D03*
X150185Y676105D03*
X155225D03*
X380277Y1583235D03*
Y1585203D03*
X385317Y1583235D03*
Y1585203D03*
X451768Y1581117D03*
Y1579149D03*
X456808Y1581117D03*
Y1579149D03*
X1185672Y583306D03*
Y581338D03*
X1190712Y583306D03*
Y581338D03*
X1723814Y665222D03*
X1728854D03*
X1723814Y663254D03*
X1728854D03*
M02*
